P  UNITS CUST 0
C   
C   vSure IPC 356 OUTPUT.  
C
C   FTP Site : valor.com
C   WEB Site : http://www.valor.com 
C
P   NNAME00000     SSD0_CLK0_OE_R_N                                         
P   NNAME00001     SSD10_CLK0_OE_R_N                                        
P   NNAME00002     P12V_SSD14_SENSE                                         
P   NNAME00003     SSD9_CLK0_OE_R_N                                         
P   NNAME00004     SSD3_CLK0_OE_R_N                                         
P   NNAME00005     SSD1_CLK0_OE_R_N                                         
P   NNAME00006     SSD4_CLK0_OE_R_N                                         
P   NNAME00007     SSD5_CLK0_OE_R_N                                         
P   NNAME00008     SSD6_CLK0_OE_R_N                                         
P   NNAME00009     SSD7_CLK0_OE_R_N                                         
P   NNAME00010     SSD8_CLK0_OE_R_N                                         
P   NNAME00011     SSD11_CLK0_OE_R_N                                        
P   NNAME00012     SSD12_CLK0_OE_R_N                                        
P   NNAME00013     SSD13_CLK0_OE_R_N                                        
P   NNAME00014     SSD14_CLK0_OE_R_N                                        
P   NNAME00015     SSD2_CLK0_OE_R_N                                         
P   NNAME00016     PE_100M_CLK1_C_N                                         
P   NNAME00017     PE_100M_CLK1_C_P                                         
P   NNAME00018     PE_100M_CLK2_C_P                                         
P   NNAME00019     PE_100M_CLK2_C_N                                         
P   NNAME00020     PE_100M_CLK3_C_P                                         
P   NNAME00021     PE_100M_CLK3_C_N                                         
P   NNAME00022     PE_100M_CLK4_C_P                                         
P   NNAME00023     PE_100M_CLK4_C_N                                         
P   NNAME00024     PEER_TRAY_PRESENT                                        
P   NNAME00025     SELF_TRAY_PRESENT                                        
P   NNAME00026     FCB_HW_REVISION                                          
P   NNAME00027     SD_LATCH_RELEASE                                         
P   NNAME00028     CLK_BUF_EU1_100M_133M#                                   
P   NNAME00029     CLK_BUF_EU1_HIBW_BYPM_LOBW#                              
P   NNAME00030     CLK_BUF_EU1_SMB_A0_TRI                                   
P   NNAME00031     I2C_SDA_BUF_9_EU1_R                                      
P   NNAME00032     I2C_SCL_BUF_9_EU1_R                                      
P   NNAME00033     CLK_BUF_EU1_SMB_A1_TRI                                   
P   NNAME00034     PE_CLK_100M_DR10_2_R_P                                   
P   NNAME00035     PE_CLK_100M_DR10_2_R_N                                   
P   NNAME00036     PE_CLK_100M_DR10_1_R_P                                   
P   NNAME00037     PE_CLK_100M_DR10_1_R_N                                   
P   NNAME00038     CLK_BUFFER_EU1_VOE_N                                     
P   NNAME00039     PE_CLK_100M_DR0_2_R_P                                    
P   NNAME00040     PE_CLK_100M_DR0_2_R_N                                    
P   NNAME00041     PE_CLK_100M_DR0_1_R_P                                    
P   NNAME00042     PE_CLK_100M_DR0_1_R_N                                    
P   NNAME00043     PE_CLK_100M_DR5_2_R_P                                    
P   NNAME00044     PE_CLK_100M_DR5_2_R_N                                    
P   NNAME00045     PE_CLK_100M_DR5_1_R_P                                    
P   NNAME00046     PE_CLK_100M_DR5_1_R_N                                    
P   NNAME00047     I2C_SW_EU16_ADDRESS_A2                                   
P   NNAME00048     I2C8_SCL_R_SW_EU16                                       
P   NNAME00049     I2C8_SDA_R_SW_EU16                                       
P   NNAME00050     I2C_SW_EU16_ADDRESS_A0                                   
P   NNAME00051     I2C_SW_EU16_ADDRESS_A1                                   
P   NNAME00052     I2C_MUX_RESET_R_EU16                                     
P   NNAME00053     I2C_SW_EU17_ADDRESS_A2                                   
P   NNAME00054     I2C8_SCL_R_SW_EU17                                       
P   NNAME00055     I2C8_SDA_R_SW_EU17                                       
P   NNAME00056     I2C_SW_EU17_ADDRESS_A0                                   
P   NNAME00057     I2C_SW_EU17_ADDRESS_A1                                   
P   NNAME00058     I2C_MUX_RESET_R_EU17                                     
P   NNAME00059     CLK_BUF_EU2_100M_133M#                                   
P   NNAME00060     CLK_BUF_EU2_HIBW_BYPM_LOBW#                              
P   NNAME00061     CLK_BUF_EU2_SMB_A0_TRI                                   
P   NNAME00062     I2C_SDA_BUF_9_EU2_R                                      
P   NNAME00063     I2C_SCL_BUF_9_EU2_R                                      
P   NNAME00064     CLK_BUF_EU2_SMB_A1_TRI                                   
P   NNAME00065     CLK_BUFFER_EU2_VOE_N                                     
P   NNAME00066     PE_CLK_100M_DR2_2_R_P                                    
P   NNAME00067     PE_CLK_100M_DR2_2_R_N                                    
P   NNAME00068     PE_CLK_100M_DR2_1_R_P                                    
P   NNAME00069     PE_CLK_100M_DR2_1_R_N                                    
P   NNAME00070     PE_CLK_100M_DR1_2_R_P                                    
P   NNAME00071     PE_CLK_100M_DR1_2_R_N                                    
P   NNAME00072     PE_CLK_100M_DR1_1_R_P                                    
P   NNAME00073     PE_CLK_100M_DR1_1_R_N                                    
P   NNAME00074     PE_CLK_100M_DR6_2_R_P                                    
P   NNAME00075     PE_CLK_100M_DR6_2_R_N                                    
P   NNAME00076     PE_CLK_100M_DR6_1_R_P                                    
P   NNAME00077     PE_CLK_100M_DR6_1_R_N                                    
P   NNAME00078     PE_CLK_100M_DR11_2_R_P                                   
P   NNAME00079     PE_CLK_100M_DR11_2_R_N                                   
P   NNAME00080     PE_CLK_100M_DR11_1_R_P                                   
P   NNAME00081     PE_CLK_100M_DR11_1_R_N                                   
P   NNAME00082     CLK_BUF_EU3_100M_133M#                                   
P   NNAME00083     CLK_BUF_EU3_HIBW_BYPM_LOBW#                              
P   NNAME00084     CLK_BUF_EU3_SMB_A0_TRI                                   
P   NNAME00085     I2C_SDA_BUF_8_EU3_R                                      
P   NNAME00086     I2C_SCL_BUF_8_EU3_R                                      
P   NNAME00087     CLK_BUF_EU3_SMB_A1_TRI                                   
P   NNAME00088     CLK_BUFFER_EU3_VOE_N                                     
P   NNAME00089     PE_CLK_100M_DR4_2_R_P                                    
P   NNAME00090     PE_CLK_100M_DR4_2_R_N                                    
P   NNAME00091     PE_CLK_100M_DR4_1_R_P                                    
P   NNAME00092     PE_CLK_100M_DR4_1_R_N                                    
P   NNAME00093     PE_CLK_100M_DR3_2_R_P                                    
P   NNAME00094     PE_CLK_100M_DR3_2_R_N                                    
P   NNAME00095     PE_CLK_100M_DR3_1_R_P                                    
P   NNAME00096     PE_CLK_100M_DR3_1_R_N                                    
P   NNAME00097     PE_CLK_100M_DR7_2_R_P                                    
P   NNAME00098     PE_CLK_100M_DR7_2_R_N                                    
P   NNAME00099     PE_CLK_100M_DR7_1_R_P                                    
P   NNAME00100     PE_CLK_100M_DR7_1_R_N                                    
P   NNAME00101     PE_CLK_100M_DR12_2_R_P                                   
P   NNAME00102     PE_CLK_100M_DR12_2_R_N                                   
P   NNAME00103     PE_CLK_100M_DR12_1_R_P                                   
P   NNAME00104     PE_CLK_100M_DR12_1_R_N                                   
P   NNAME00105     CLK_BUF_EU4_100M_133M#                                   
P   NNAME00106     CLK_BUF_EU4_HIBW_BYPM_LOBW#                              
P   NNAME00107     CLK_BUF_EU4_SMB_A0_TRI                                   
P   NNAME00108     I2C_SDA_BUF_8_EU4_R                                      
P   NNAME00109     I2C_SCL_BUF_8_EU4_R                                      
P   NNAME00110     CLK_BUF_EU4_SMB_A1_TRI                                   
P   NNAME00111     PE_CLK_100M_DR9_2_R_P                                    
P   NNAME00112     PE_CLK_100M_DR9_2_R_N                                    
P   NNAME00113     PE_CLK_100M_DR9_1_R_P                                    
P   NNAME00114     PE_CLK_100M_DR9_1_R_N                                    
P   NNAME00115     PE_CLK_100M_DR14_2_R_P                                   
P   NNAME00116     PE_CLK_100M_DR14_2_R_N                                   
P   NNAME00117     PE_CLK_100M_DR14_1_R_P                                   
P   NNAME00118     PE_CLK_100M_DR14_1_R_N                                   
P   NNAME00119     CLK_BUFFER_EU4_VOE_N                                     
P   NNAME00120     PE_CLK_100M_DR8_2_R_P                                    
P   NNAME00121     PE_CLK_100M_DR8_2_R_N                                    
P   NNAME00122     PE_CLK_100M_DR8_1_R_P                                    
P   NNAME00123     PE_CLK_100M_DR8_1_R_N                                    
P   NNAME00124     PE_CLK_100M_DR13_2_R_P                                   
P   NNAME00125     PE_CLK_100M_DR13_2_R_N                                   
P   NNAME00126     PE_CLK_100M_DR13_1_R_P                                   
P   NNAME00127     PE_CLK_100M_DR13_1_R_N                                   
P   NNAME00128     PE_CLK100M_DR1_2_P                                       
P   NNAME00129     PE_CLK100M_DR1_2_N                                       
P   NNAME00130     PE_CLK100M_DR1_1_P                                       
P   NNAME00131     PE_CLK100M_DR1_1_N                                       
P   NNAME00132     PE_CLK100M_DR10_2_P                                      
P   NNAME00133     PE_CLK100M_DR10_2_N                                      
P   NNAME00134     PE_CLK100M_DR10_1_P                                      
P   NNAME00135     PE_CLK100M_DR10_1_N                                      
P   NNAME00136     SSD10_CLK0_OE_N                                          
P   NNAME00137     SSD_PRSNT_NET10                                          
P   NNAME00138     12V_PRECH_SSD10                                          
P   NNAME00139     PE_CLK100M_DR0_2_P                                       
P   NNAME00140     PE_CLK100M_DR0_2_N                                       
P   NNAME00141     PE_CLK100M_DR0_1_P                                       
P   NNAME00142     PE_CLK100M_DR0_1_N                                       
P   NNAME00143     PE_CLK100M_DR11_2_P                                      
P   NNAME00144     PE_CLK100M_DR11_2_N                                      
P   NNAME00145     PE_CLK100M_DR11_1_P                                      
P   NNAME00146     PE_CLK100M_DR11_1_N                                      
P   NNAME00147     SSD11_CLK0_OE_N                                          
P   NNAME00148     SSD_PRSNT_NET11                                          
P   NNAME00149     12V_PRECH_SSD11                                          
P   NNAME00150     PE_CLK100M_DR12_2_P                                      
P   NNAME00151     PE_CLK100M_DR12_2_N                                      
P   NNAME00152     PE_CLK100M_DR12_1_P                                      
P   NNAME00153     PE_CLK100M_DR12_1_N                                      
P   NNAME00154     SSD12_CLK0_OE_N                                          
P   NNAME00155     SSD_PRSNT_NET12                                          
P   NNAME00156     12V_PRECH_SSD12                                          
P   NNAME00157     PE_CLK100M_DR13_2_P                                      
P   NNAME00158     PE_CLK100M_DR13_2_N                                      
P   NNAME00159     PE_CLK100M_DR13_1_P                                      
P   NNAME00160     PE_CLK100M_DR13_1_N                                      
P   NNAME00161     SSD13_CLK0_OE_N                                          
P   NNAME00162     SSD_PRSNT_NET13                                          
P   NNAME00163     12V_PRECH_SSD13                                          
P   NNAME00164     PE_CLK100M_DR14_2_P                                      
P   NNAME00165     PE_CLK100M_DR14_2_N                                      
P   NNAME00166     PE_CLK100M_DR14_1_P                                      
P   NNAME00167     PE_CLK100M_DR14_1_N                                      
P   NNAME00168     SSD14_CLK0_OE_N                                          
P   NNAME00169     SSD_PRSNT_NET14                                          
P   NNAME00170     12V_PRECH_SSD14                                          
P   NNAME00171     SAS_I2C_B_BUF_SCL_R                                      
P   NNAME00172     SAS_I2C_B_BUF_SDA_R                                      
P   NNAME00173     BMC_I2C_SCL_BUF_9                                        
P   NNAME00174     BMC_I2C_SDA_BUF_9                                        
P   NNAME00175     SAS_I2C_C_BUF_SCL_R                                      
P   NNAME00176     SAS_I2C_C_BUF_SDA_R                                      
P   NNAME00177     ATTN_LED_DR10_N                                          
P   NNAME00178     BMC_I2C_SCL_BUF_8                                        
P   NNAME00179     BMC_I2C_SDA_BUF_8                                        
P   NNAME00180     DPB_HW_REVISION                                          
P   NNAME00181     SELF_TRAY_PRESENT_R                                      
P   NNAME00182     ATTN_LED_DR12_N                                          
P   NNAME00183     ATTN_LED_DR11_N                                          
P   NNAME00184     ATTN_LED_DR13_N                                          
P   NNAME00185     SD_LATCH_RELEASE_R                                       
P   NNAME00186     ATTN_LED_DR14_N                                          
P   NNAME00187     I2C_MUX_RESET_PEB                                        
P   NNAME00188     PE_CLK100M_DR2_2_P                                       
P   NNAME00189     PE_CLK100M_DR2_2_N                                       
P   NNAME00190     PE_CLK100M_DR2_1_P                                       
P   NNAME00191     PE_CLK100M_DR2_1_N                                       
P   NNAME00192     PE_CLK100M_DR3_2_P                                       
P   NNAME00193     PE_CLK100M_DR3_2_N                                       
P   NNAME00194     PE_CLK100M_DR3_1_P                                       
P   NNAME00195     PE_CLK100M_DR3_1_N                                       
P   NNAME00196     PE_CLK100M_DR4_2_P                                       
P   NNAME00197     PE_CLK100M_DR4_2_N                                       
P   NNAME00198     PE_CLK100M_DR4_1_P                                       
P   NNAME00199     PE_CLK100M_DR4_1_N                                       
P   NNAME00200     PE_CLK100M_DR5_2_P                                       
P   NNAME00201     PE_CLK100M_DR5_2_N                                       
P   NNAME00202     PE_CLK100M_DR5_1_P                                       
P   NNAME00203     PE_CLK100M_DR5_1_N                                       
P   NNAME00204     PE_CLK100M_DR6_2_P                                       
P   NNAME00205     PE_CLK100M_DR6_2_N                                       
P   NNAME00206     PE_CLK100M_DR6_1_P                                       
P   NNAME00207     PE_CLK100M_DR6_1_N                                       
P   NNAME00208     PE_CLK100M_DR7_2_P                                       
P   NNAME00209     PE_CLK100M_DR7_2_N                                       
P   NNAME00210     PE_CLK100M_DR7_1_P                                       
P   NNAME00211     PE_CLK100M_DR7_1_N                                       
P   NNAME00212     PE_CLK100M_DR8_2_P                                       
P   NNAME00213     PE_CLK100M_DR8_2_N                                       
P   NNAME00214     PE_CLK100M_DR8_1_P                                       
P   NNAME00215     PE_CLK100M_DR8_1_N                                       
P   NNAME00216     PE_CLK100M_DR9_2_P                                       
P   NNAME00217     PE_CLK100M_DR9_2_N                                       
P   NNAME00218     PE_CLK100M_DR9_1_P                                       
P   NNAME00219     PE_CLK100M_DR9_1_N                                       
P   NNAME00220     SSD_ACT_DR1_MOS_N                                        
P   NNAME00221     ATTN_LED_DR1_MOS_N                                       
P   NNAME00222     SSD_ACT_DR10_MOS_N                                       
P   NNAME00223     ATTN_LED_DR10_MOS_N                                      
P   NNAME00224     SSD_ACT_DR0_MOS_N                                        
P   NNAME00225     ATTN_LED_DR0_MOS_N                                       
P   NNAME00226     SSD_ACT_DR11_MOS_N                                       
P   NNAME00227     ATTN_LED_DR11_MOS_N                                      
P   NNAME00228     SSD_ACT_DR12_MOS_N                                       
P   NNAME00229     ATTN_LED_DR12_MOS_N                                      
P   NNAME00230     SSD_ACT_DR13_MOS_N                                       
P   NNAME00231     ATTN_LED_DR13_MOS_N                                      
P   NNAME00232     SSD_ACT_DR14_MOS_N                                       
P   NNAME00233     ATTN_LED_DR14_MOS_N                                      
P   NNAME00234     SSD_ACT_DR2_MOS_N                                        
P   NNAME00235     ATTN_LED_DR2_MOS_N                                       
P   NNAME00236     SSD_ACT_DR3_MOS_N                                        
P   NNAME00237     ATTN_LED_DR3_MOS_N                                       
P   NNAME00238     SSD_ACT_DR4_MOS_N                                        
P   NNAME00239     ATTN_LED_DR4_MOS_N                                       
P   NNAME00240     SSD_ACT_DR5_MOS_N                                        
P   NNAME00241     ATTN_LED_DR5_MOS_N                                       
P   NNAME00242     SSD_ACT_DR6_MOS_N                                        
P   NNAME00243     ATTN_LED_DR6_MOS_N                                       
P   NNAME00244     SSD_ACT_DR7_MOS_N                                        
P   NNAME00245     ATTN_LED_DR7_MOS_N                                       
P   NNAME00246     SSD_ACT_DR8_MOS_N                                        
P   NNAME00247     ATTN_LED_DR8_MOS_N                                       
P   NNAME00248     SSD_ACT_DR9_MOS_N                                        
P   NNAME00249     ATTN_LED_DR9_MOS_N                                       
P   NNAME00250     TPS53312_P3V3_PG                                         
P   NNAME00251     SSD14_CLK0_OE_MOS_N                                      
P   NNAME00252     ATTN_LED_DR14_R                                          
P   NNAME00253     P12V_MOST0_GATE                                          
P   NNAME00254     P12V_MOST0_GATE_D                                        
P   NNAME00255     SSD0_CLK0_OE_MOS_N                                       
P   NNAME00256     ATTN_LED_DR0_AND_R                                       
P   NNAME00257     P12V_MOST1_GATE                                          
P   NNAME00258     P12V_MOST1_GATE_D                                        
P   NNAME00259     ATTN_LED_DR1_AND_R                                       
P   NNAME00260     SSD1_CLK0_OE_MOS_N                                       
P   NNAME00261     P12V_MOST2_GATE                                          
P   NNAME00262     P12V_MOST2_GATE_D                                        
P   NNAME00263     ATTN_LED_DR2_AND_R                                       
P   NNAME00264     SSD2_CLK0_OE_MOS_N                                       
P   NNAME00265     P12V_MOST3_GATE_D                                        
P   NNAME00266     P12V_MOST3_GATE                                          
P   NNAME00267     ATTN_LED_DR3_AND_R                                       
P   NNAME00268     SSD3_CLK0_OE_MOS_N                                       
P   NNAME00269     P12V_MOST4_GATE_D                                        
P   NNAME00270     P12V_MOST4_GATE                                          
P   NNAME00271     ATTN_LED_DR4_AND_R                                       
P   NNAME00272     SSD4_CLK0_OE_MOS_N                                       
P   NNAME00273     P12V_MOST5_GATE_D                                        
P   NNAME00274     P12V_MOST5_GATE                                          
P   NNAME00275     ATTN_LED_DR5_AND_R                                       
P   NNAME00276     SSD5_CLK0_OE_MOS_N                                       
P   NNAME00277     P12V_MOST6_GATE_D                                        
P   NNAME00278     P12V_MOST6_GATE                                          
P   NNAME00279     ATTN_LED_DR6_AND_R                                       
P   NNAME00280     SSD6_CLK0_OE_MOS_N                                       
P   NNAME00281     P12V_MOST7_GATE_D                                        
P   NNAME00282     P12V_MOST7_GATE                                          
P   NNAME00283     ATTN_LED_DR7_AND_R                                       
P   NNAME00284     SSD7_CLK0_OE_MOS_N                                       
P   NNAME00285     P12V_MOST8_GATE                                          
P   NNAME00286     P12V_MOST8_GATE_D                                        
P   NNAME00287     ATTN_LED_DR8_AND_R                                       
P   NNAME00288     SSD8_CLK0_OE_MOS_N                                       
P   NNAME00289     P12V_MOST9_GATE                                          
P   NNAME00290     P12V_MOST9_GATE_D                                        
P   NNAME00291     ATTN_LED_DR9_AND_R                                       
P   NNAME00292     SSD9_CLK0_OE_MOS_N                                       
P   NNAME00293     P12V_MOST10_GATE                                         
P   NNAME00294     P12V_MOST10_GATE_D                                       
P   NNAME00295     ATTN_LED_DR10_AND_R                                      
P   NNAME00296     SSD10_CLK0_OE_MOS_N                                      
P   NNAME00297     ATTN_LED_DR10_R                                          
P   NNAME00298     P12V_MOST11_GATE_D                                       
P   NNAME00299     P12V_MOST11_GATE                                         
P   NNAME00300     ATTN_LED_DR11_AND_R                                      
P   NNAME00301     SSD11_CLK0_OE_MOS_N                                      
P   NNAME00302     ATTN_LED_DR11_R                                          
P   NNAME00303     P12V_MOST12_GATE_D                                       
P   NNAME00304     P12V_MOST12_GATE                                         
P   NNAME00305     ATTN_LED_DR12_AND_R                                      
P   NNAME00306     SSD12_CLK0_OE_MOS_N                                      
P   NNAME00307     ATTN_LED_DR12_R                                          
P   NNAME00308     P12V_MOST13_GATE_D                                       
P   NNAME00309     P12V_MOST13_GATE                                         
P   NNAME00310     ATTN_LED_DR13_AND_R                                      
P   NNAME00311     SSD13_CLK0_OE_MOS_N                                      
P   NNAME00312     ATTN_LED_DR13_R                                          
P   NNAME00313     P12V_MOST14_GATE_D                                       
P   NNAME00314     P12V_MOST14_GATE                                         
P   NNAME00315     ATTN_LED_DR14_AND_R                                      
P   NNAME00316     ATTN_LED_DR0_AND                                         
P   NNAME00317     ATTN_LED_DR1_AND                                         
P   NNAME00318     ATTN_LED_DR2_AND                                         
P   NNAME00319     ATTN_LED_DR3_AND                                         
P   NNAME00320     ATTN_LED_DR4_AND                                         
P   NNAME00321     ATTN_LED_DR5_AND                                         
P   NNAME00322     ATTN_LED_DR6_AND                                         
P   NNAME00323     ATTN_LED_DR7_AND                                         
P   NNAME00324     ATTN_LED_DR8_AND                                         
P   NNAME00325     ATTN_LED_DR9_AND                                         
P   NNAME00326     ATTN_LED_DR10_AND                                        
P   NNAME00327     ATTN_LED_DR11_AND                                        
P   NNAME00328     ATTN_LED_DR12_AND                                        
P   NNAME00329     ATTN_LED_DR13_AND                                        
P   NNAME00330     ATTN_LED_DR14_AND                                        
P   NNAME00331     I2C_B_TMP2_ALERT                                         
P   NNAME00332     I2C_B_TMP1_ALERT                                         
P   NNAME00333     I2C_B_TMP3_ALERT                                         
317$NONE$                       D0010PA00X+002165Y+192284               S0      
317$NONE$                       D0010PA00X+027559Y+027953               S0      
317$NONE$                       D0010PA00X+099803Y+016338               S0      
317$NONE$                       D0010PA00X+099803Y+190353               S0      
317$NONE$                       D0010PA00X+013386Y+001772               S0      
317$NONE$                       D0010PA00X+027559Y+190353               S0      
317$NONE$                       D0010PA00X+027559Y+108857               S0      
317$NONE$                       D0010PA00X+099803Y+108267               S0      
317$NONE$                       D0010PA00X+027559Y+068503               S0      
317$NONE$                       D0010PA00X+099803Y+068700               S0      
317$NONE$                       D0010PA00X+003347Y+028150               S0      
317$NONE$                       D0870PA00X+001181Y+057143               S0      
317$NONE$                       D0870PA00X+001181Y+094938               S0      
317$NONE$                       D0870PA00X+001181Y+106749               S0      
317$NONE$                       D0870PA00X+001181Y+144544               S0      
317$NONE$                       D0870PA00X+001181Y+148481               S0      
317$NONE$                       D0870PA00X+001181Y+186276               S0      
327$NONE$                             A01X+030098Y+057770X0120Y0420     S0      
327$NONE$                             A01X+030295Y+057770X0120Y0420     S0      
327$NONE$                             A01X+035259Y+041083X0460Y0120     S0      
327$NONE$                             A01X+035259Y+038721X0460Y0120     S0      
327$NONE$                             A01X+035208Y+038523X0360Y0120     S0      
327$NONE$                             A01X+038742Y+038721X0460Y0120     S0      
327$NONE$                             A01X+038742Y+038918X0460Y0120     S0      
327$NONE$                             A01X+038742Y+039508X0460Y0120     S0      
327$NONE$                             A01X+038742Y+039704X0460Y0120     S0      
327$NONE$                             A01X+038742Y+040296X0460Y0120     S0      
327$NONE$                             A01X+038742Y+040492X0460Y0120     S0      
327$NONE$                             A01X+038742Y+041083X0460Y0120     S0      
327$NONE$                             A01X+038742Y+041280X0460Y0120     S0      
327$NONE$                             A01X+035259Y+084083X0460Y0120     S0      
327$NONE$                             A01X+035259Y+081721X0460Y0120     S0      
327$NONE$                             A01X+035208Y+081524X0360Y0120     S0      
327$NONE$                             A01X+035524Y+081208X0120Y0360     S0      
327$NONE$                             A01X+035721Y+081259X0120Y0460     S0      
327$NONE$                             A01X+036311Y+081259X0120Y0460     S0      
327$NONE$                             A01X+036508Y+081259X0120Y0460     S0      
327$NONE$                             A01X+038742Y+083296X0460Y0120     S0      
327$NONE$                             A01X+038742Y+083492X0460Y0120     S0      
327$NONE$                             A01X+038742Y+084083X0460Y0120     S0      
327$NONE$                             A01X+038742Y+084279X0460Y0120     S0      
327$NONE$                             A01X+035259Y+121233X0460Y0120     S0      
327$NONE$                             A01X+035259Y+118871X0460Y0120     S0      
327$NONE$                             A01X+035208Y+118674X0360Y0120     S0      
327$NONE$                             A01X+035524Y+118358X0120Y0360     S0      
327$NONE$                             A01X+035721Y+118409X0120Y0460     S0      
327$NONE$                             A01X+036311Y+118409X0120Y0460     S0      
327$NONE$                             A01X+036508Y+118409X0120Y0460     S0      
327$NONE$                             A01X+038742Y+118871X0460Y0120     S0      
327$NONE$                             A01X+038742Y+119068X0460Y0120     S0      
327$NONE$                             A01X+038742Y+119658X0460Y0120     S0      
327$NONE$                             A01X+038742Y+119855X0460Y0120     S0      
327$NONE$                             A01X+035259Y+171083X0460Y0120     S0      
327$NONE$                             A01X+035259Y+168720X0460Y0120     S0      
327$NONE$                             A01X+035208Y+168523X0360Y0120     S0      
327$NONE$                             A01X+037296Y+168259X0120Y0460     S0      
327$NONE$                             A01X+037492Y+168259X0120Y0460     S0      
327$NONE$                             A01X+038083Y+168259X0120Y0460     S0      
327$NONE$                             A01X+038280Y+168259X0120Y0460     S0      
327$NONE$                             A01X+038742Y+168720X0460Y0120     S0      
327$NONE$                             A01X+038742Y+168917X0460Y0120     S0      
327$NONE$                             A01X+038742Y+169508X0460Y0120     S0      
327$NONE$                             A01X+038742Y+169705X0460Y0120     S0      
327$NONE$                             A01X+038280Y+171742X0120Y0460     S0      
327$NONE$                             A01X+038083Y+171742X0120Y0460     S0      
327$NONE$                             A01X+037492Y+171742X0120Y0460     S0      
327$NONE$                             A01X+037296Y+171742X0120Y0460     S0      
327$NONE$                             A01X+036047Y+010465X0120Y0600     S0      
317$NONE$                       D1460PA00X+102323Y+141602               S0      
317$NONE$                       D1460PA00X+102323Y+169421               S0      
327$NONE$                             A01X+100974Y+162110X2300Y0320     S0      
327$NONE$                             A01X+089524Y+187634X0790Y0200     S0      
327$NONE$                             A01X+088268Y+185587X0790Y0200     S0      
317$NONE$                       D0730PA00X+089035Y+181366               S0      
317$NONE$                       D0730PA00X+089035Y+196327               S0      
327$NONE$                             A01X+089360Y+188096X0810Y0260     S0      
327$NONE$                             A01X+089360Y+188596X0810Y0260     S0      
327$NONE$                             A01X+089360Y+189097X0810Y0260     S0      
327$NONE$                             A01X+089360Y+191096X0810Y0260     S0      
327$NONE$                             A01X+089360Y+191597X0810Y0260     S0      
327$NONE$                             A01X+089360Y+192097X0810Y0260     S0      
317$NONE$                       D0320PA00X+089961Y+180185               S0      
317$NONE$                       D0320PA00X+089961Y+197508               S0      
327$NONE$                             A01X+089360Y+183096X0810Y0260     S0      
327$NONE$                             A01X+089360Y+183596X0810Y0260     S0      
327$NONE$                             A01X+089360Y+184597X0810Y0260     S0      
327$NONE$                             A01X+089360Y+185097X0810Y0260     S0      
327$NONE$                             A01X+088268Y+186217X0790Y0200     S0      
327$NONE$                             A01X+088268Y+186532X0790Y0200     S0      
327$NONE$                             A01X+088268Y+187162X0790Y0200     S0      
327$NONE$                             A01X+088268Y+187476X0790Y0200     S0      
327$NONE$                             A01X+088268Y+188106X0790Y0200     S0      
327$NONE$                             A01X+089524Y+147083X0790Y0200     S0      
327$NONE$                             A01X+088268Y+145036X0790Y0200     S0      
317$NONE$                       D0730PA00X+089035Y+140815               S0      
317$NONE$                       D0730PA00X+089035Y+155776               S0      
327$NONE$                             A01X+089360Y+147545X0810Y0260     S0      
327$NONE$                             A01X+089360Y+148045X0810Y0260     S0      
327$NONE$                             A01X+089360Y+148545X0810Y0260     S0      
327$NONE$                             A01X+089360Y+150545X0810Y0260     S0      
327$NONE$                             A01X+089360Y+151045X0810Y0260     S0      
327$NONE$                             A01X+089360Y+151545X0810Y0260     S0      
317$NONE$                       D0320PA00X+089961Y+139634               S0      
317$NONE$                       D0320PA00X+089961Y+156957               S0      
327$NONE$                             A01X+089360Y+142545X0810Y0260     S0      
327$NONE$                             A01X+089360Y+143045X0810Y0260     S0      
327$NONE$                             A01X+089360Y+144045X0810Y0260     S0      
327$NONE$                             A01X+089360Y+144545X0810Y0260     S0      
327$NONE$                             A01X+088268Y+145665X0790Y0200     S0      
327$NONE$                             A01X+088268Y+145980X0790Y0200     S0      
327$NONE$                             A01X+088268Y+146610X0790Y0200     S0      
327$NONE$                             A01X+088268Y+146925X0790Y0200     S0      
327$NONE$                             A01X+088268Y+147555X0790Y0200     S0      
327$NONE$                             A01X+089524Y+106532X0790Y0200     S0      
327$NONE$                             A01X+088268Y+104484X0790Y0200     S0      
317$NONE$                       D0730PA00X+089035Y+100264               S0      
317$NONE$                       D0730PA00X+089035Y+115224               S0      
327$NONE$                             A01X+089360Y+106994X0810Y0260     S0      
327$NONE$                             A01X+089360Y+107494X0810Y0260     S0      
327$NONE$                             A01X+089360Y+107994X0810Y0260     S0      
327$NONE$                             A01X+089360Y+109994X0810Y0260     S0      
327$NONE$                             A01X+089360Y+110494X0810Y0260     S0      
327$NONE$                             A01X+089360Y+110994X0810Y0260     S0      
317$NONE$                       D0320PA00X+089961Y+099083               S0      
317$NONE$                       D0320PA00X+089961Y+116406               S0      
327$NONE$                             A01X+089360Y+101994X0810Y0260     S0      
327$NONE$                             A01X+089360Y+102494X0810Y0260     S0      
327$NONE$                             A01X+089360Y+103494X0810Y0260     S0      
327$NONE$                             A01X+089360Y+103994X0810Y0260     S0      
327$NONE$                             A01X+088268Y+105114X0790Y0200     S0      
327$NONE$                             A01X+088268Y+105429X0790Y0200     S0      
327$NONE$                             A01X+088268Y+106059X0790Y0200     S0      
327$NONE$                             A01X+088268Y+106374X0790Y0200     S0      
327$NONE$                             A01X+088268Y+107004X0790Y0200     S0      
327$NONE$                             A01X+089524Y+065980X0790Y0200     S0      
327$NONE$                             A01X+088268Y+063933X0790Y0200     S0      
317$NONE$                       D0730PA00X+089035Y+059713               S0      
317$NONE$                       D0730PA00X+089035Y+074673               S0      
327$NONE$                             A01X+089360Y+066443X0810Y0260     S0      
327$NONE$                             A01X+089360Y+066943X0810Y0260     S0      
327$NONE$                             A01X+089360Y+067443X0810Y0260     S0      
327$NONE$                             A01X+089360Y+069443X0810Y0260     S0      
327$NONE$                             A01X+089360Y+069943X0810Y0260     S0      
327$NONE$                             A01X+089360Y+070443X0810Y0260     S0      
317$NONE$                       D0320PA00X+089961Y+058532               S0      
317$NONE$                       D0320PA00X+089961Y+075854               S0      
327$NONE$                             A01X+089360Y+061443X0810Y0260     S0      
327$NONE$                             A01X+089360Y+061943X0810Y0260     S0      
327$NONE$                             A01X+089360Y+062943X0810Y0260     S0      
327$NONE$                             A01X+089360Y+063443X0810Y0260     S0      
327$NONE$                             A01X+088268Y+064563X0790Y0200     S0      
327$NONE$                             A01X+088268Y+064878X0790Y0200     S0      
327$NONE$                             A01X+088268Y+065508X0790Y0200     S0      
327$NONE$                             A01X+088268Y+065823X0790Y0200     S0      
327$NONE$                             A01X+088268Y+066453X0790Y0200     S0      
327$NONE$                             A01X+089524Y+025429X0790Y0200     S0      
327$NONE$                             A01X+088268Y+023382X0790Y0200     S0      
317$NONE$                       D0730PA00X+089035Y+019161               S0      
317$NONE$                       D0730PA00X+089035Y+034122               S0      
327$NONE$                             A01X+089360Y+025892X0810Y0260     S0      
327$NONE$                             A01X+089360Y+026392X0810Y0260     S0      
327$NONE$                             A01X+089360Y+026892X0810Y0260     S0      
327$NONE$                             A01X+089360Y+028892X0810Y0260     S0      
327$NONE$                             A01X+089360Y+029392X0810Y0260     S0      
327$NONE$                             A01X+089360Y+029892X0810Y0260     S0      
317$NONE$                       D0320PA00X+089961Y+017980               S0      
317$NONE$                       D0320PA00X+089961Y+035303               S0      
327$NONE$                             A01X+089360Y+020892X0810Y0260     S0      
327$NONE$                             A01X+089360Y+021392X0810Y0260     S0      
327$NONE$                             A01X+089360Y+022392X0810Y0260     S0      
327$NONE$                             A01X+089360Y+022892X0810Y0260     S0      
327$NONE$                             A01X+088268Y+024012X0790Y0200     S0      
327$NONE$                             A01X+088268Y+024327X0790Y0200     S0      
327$NONE$                             A01X+088268Y+024957X0790Y0200     S0      
327$NONE$                             A01X+088268Y+025272X0790Y0200     S0      
327$NONE$                             A01X+088268Y+025902X0790Y0200     S0      
327$NONE$                             A01X+016689Y+187634X0790Y0200     S0      
327$NONE$                             A01X+015433Y+185587X0790Y0200     S0      
317$NONE$                       D0730PA00X+016201Y+181366               S0      
317$NONE$                       D0730PA00X+016201Y+196327               S0      
327$NONE$                             A01X+016526Y+188096X0810Y0260     S0      
327$NONE$                             A01X+016526Y+188596X0810Y0260     S0      
327$NONE$                             A01X+016526Y+189097X0810Y0260     S0      
327$NONE$                             A01X+016526Y+191096X0810Y0260     S0      
327$NONE$                             A01X+016526Y+191597X0810Y0260     S0      
327$NONE$                             A01X+016526Y+192097X0810Y0260     S0      
317$NONE$                       D0320PA00X+017126Y+180185               S0      
317$NONE$                       D0320PA00X+017126Y+197508               S0      
327$NONE$                             A01X+016526Y+183096X0810Y0260     S0      
327$NONE$                             A01X+016526Y+183596X0810Y0260     S0      
327$NONE$                             A01X+016526Y+184597X0810Y0260     S0      
327$NONE$                             A01X+016526Y+185097X0810Y0260     S0      
327$NONE$                             A01X+015433Y+186217X0790Y0200     S0      
327$NONE$                             A01X+015433Y+186532X0790Y0200     S0      
327$NONE$                             A01X+015433Y+187162X0790Y0200     S0      
327$NONE$                             A01X+015433Y+187476X0790Y0200     S0      
327$NONE$                             A01X+015433Y+188106X0790Y0200     S0      
327$NONE$                             A01X+016689Y+147083X0790Y0200     S0      
327$NONE$                             A01X+015433Y+145036X0790Y0200     S0      
317$NONE$                       D0730PA00X+016201Y+140815               S0      
317$NONE$                       D0730PA00X+016201Y+155776               S0      
327$NONE$                             A01X+016526Y+147545X0810Y0260     S0      
327$NONE$                             A01X+016526Y+148045X0810Y0260     S0      
327$NONE$                             A01X+016526Y+148545X0810Y0260     S0      
327$NONE$                             A01X+016526Y+150545X0810Y0260     S0      
327$NONE$                             A01X+016526Y+151045X0810Y0260     S0      
327$NONE$                             A01X+016526Y+151545X0810Y0260     S0      
317$NONE$                       D0320PA00X+017126Y+139634               S0      
317$NONE$                       D0320PA00X+017126Y+156957               S0      
327$NONE$                             A01X+016526Y+142545X0810Y0260     S0      
327$NONE$                             A01X+016526Y+143045X0810Y0260     S0      
327$NONE$                             A01X+016526Y+144045X0810Y0260     S0      
327$NONE$                             A01X+016526Y+144545X0810Y0260     S0      
327$NONE$                             A01X+015433Y+145665X0790Y0200     S0      
327$NONE$                             A01X+015433Y+145980X0790Y0200     S0      
327$NONE$                             A01X+015433Y+146610X0790Y0200     S0      
327$NONE$                             A01X+015433Y+146925X0790Y0200     S0      
327$NONE$                             A01X+015433Y+147555X0790Y0200     S0      
327$NONE$                             A01X+016689Y+106532X0790Y0200     S0      
327$NONE$                             A01X+015433Y+104484X0790Y0200     S0      
317$NONE$                       D0730PA00X+016201Y+100264               S0      
317$NONE$                       D0730PA00X+016201Y+115224               S0      
327$NONE$                             A01X+016526Y+106994X0810Y0260     S0      
327$NONE$                             A01X+016526Y+107494X0810Y0260     S0      
327$NONE$                             A01X+016526Y+107994X0810Y0260     S0      
327$NONE$                             A01X+016526Y+109994X0810Y0260     S0      
327$NONE$                             A01X+016526Y+110494X0810Y0260     S0      
327$NONE$                             A01X+016526Y+110994X0810Y0260     S0      
317$NONE$                       D0320PA00X+017126Y+099083               S0      
317$NONE$                       D0320PA00X+017126Y+116406               S0      
327$NONE$                             A01X+016526Y+101994X0810Y0260     S0      
327$NONE$                             A01X+016526Y+102494X0810Y0260     S0      
327$NONE$                             A01X+016526Y+103494X0810Y0260     S0      
327$NONE$                             A01X+016526Y+103994X0810Y0260     S0      
327$NONE$                             A01X+015433Y+105114X0790Y0200     S0      
327$NONE$                             A01X+015433Y+105429X0790Y0200     S0      
327$NONE$                             A01X+015433Y+106059X0790Y0200     S0      
327$NONE$                             A01X+015433Y+106374X0790Y0200     S0      
327$NONE$                             A01X+015433Y+107004X0790Y0200     S0      
327$NONE$                             A01X+016689Y+065980X0790Y0200     S0      
327$NONE$                             A01X+015433Y+063933X0790Y0200     S0      
317$NONE$                       D0730PA00X+016201Y+059713               S0      
317$NONE$                       D0730PA00X+016201Y+074673               S0      
327$NONE$                             A01X+016526Y+066443X0810Y0260     S0      
327$NONE$                             A01X+016526Y+066943X0810Y0260     S0      
327$NONE$                             A01X+016526Y+067443X0810Y0260     S0      
327$NONE$                             A01X+016526Y+069443X0810Y0260     S0      
327$NONE$                             A01X+016526Y+069943X0810Y0260     S0      
327$NONE$                             A01X+016526Y+070443X0810Y0260     S0      
317$NONE$                       D0320PA00X+017126Y+058532               S0      
317$NONE$                       D0320PA00X+017126Y+075854               S0      
327$NONE$                             A01X+016526Y+061443X0810Y0260     S0      
327$NONE$                             A01X+016526Y+061943X0810Y0260     S0      
327$NONE$                             A01X+016526Y+062943X0810Y0260     S0      
327$NONE$                             A01X+016526Y+063443X0810Y0260     S0      
327$NONE$                             A01X+015433Y+064563X0790Y0200     S0      
327$NONE$                             A01X+015433Y+064878X0790Y0200     S0      
327$NONE$                             A01X+015433Y+065508X0790Y0200     S0      
327$NONE$                             A01X+015433Y+065823X0790Y0200     S0      
327$NONE$                             A01X+015433Y+066453X0790Y0200     S0      
327$NONE$                             A01X+016689Y+025429X0790Y0200     S0      
327$NONE$                             A01X+015433Y+023382X0790Y0200     S0      
317$NONE$                       D0730PA00X+016201Y+019161               S0      
317$NONE$                       D0730PA00X+016201Y+034122               S0      
327$NONE$                             A01X+016526Y+025892X0810Y0260     S0      
327$NONE$                             A01X+016526Y+026392X0810Y0260     S0      
327$NONE$                             A01X+016526Y+026892X0810Y0260     S0      
327$NONE$                             A01X+016526Y+028892X0810Y0260     S0      
327$NONE$                             A01X+016526Y+029392X0810Y0260     S0      
327$NONE$                             A01X+016526Y+029892X0810Y0260     S0      
317$NONE$                       D0320PA00X+017126Y+017980               S0      
317$NONE$                       D0320PA00X+017126Y+035303               S0      
327$NONE$                             A01X+016526Y+020892X0810Y0260     S0      
327$NONE$                             A01X+016526Y+021392X0810Y0260     S0      
327$NONE$                             A01X+016526Y+022392X0810Y0260     S0      
327$NONE$                             A01X+016526Y+022892X0810Y0260     S0      
327$NONE$                             A01X+015433Y+024012X0790Y0200     S0      
327$NONE$                             A01X+015433Y+024327X0790Y0200     S0      
327$NONE$                             A01X+015433Y+024957X0790Y0200     S0      
327$NONE$                             A01X+015433Y+025272X0790Y0200     S0      
327$NONE$                             A01X+015433Y+025902X0790Y0200     S0      
327$NONE$                             A01X+007721Y+173783X0790Y0200     S0      
327$NONE$                             A01X+008976Y+175831X0790Y0200     S0      
317$NONE$                       D0730PA00X+008209Y+180051               S0      
317$NONE$                       D0730PA00X+008209Y+165091               S0      
327$NONE$                             A01X+007884Y+173321X0810Y0260     S0      
327$NONE$                             A01X+007884Y+172821X0810Y0260     S0      
327$NONE$                             A01X+007884Y+172321X0810Y0260     S0      
327$NONE$                             A01X+007884Y+170321X0810Y0260     S0      
327$NONE$                             A01X+007884Y+169821X0810Y0260     S0      
327$NONE$                             A01X+007884Y+169321X0810Y0260     S0      
317$NONE$                       D0320PA00X+007284Y+181232               S0      
317$NONE$                       D0320PA00X+007284Y+163910               S0      
327$NONE$                             A01X+007884Y+178321X0810Y0260     S0      
327$NONE$                             A01X+007884Y+177821X0810Y0260     S0      
327$NONE$                             A01X+007884Y+176821X0810Y0260     S0      
327$NONE$                             A01X+007884Y+176321X0810Y0260     S0      
327$NONE$                             A01X+008976Y+175201X0790Y0200     S0      
327$NONE$                             A01X+008976Y+174886X0790Y0200     S0      
327$NONE$                             A01X+008976Y+174256X0790Y0200     S0      
327$NONE$                             A01X+008976Y+173941X0790Y0200     S0      
327$NONE$                             A01X+008976Y+173311X0790Y0200     S0      
327$NONE$                             A01X+007721Y+133232X0790Y0200     S0      
327$NONE$                             A01X+008976Y+135280X0790Y0200     S0      
317$NONE$                       D0730PA00X+008209Y+139500               S0      
317$NONE$                       D0730PA00X+008209Y+124539               S0      
327$NONE$                             A01X+007884Y+132770X0810Y0260     S0      
327$NONE$                             A01X+007884Y+132270X0810Y0260     S0      
327$NONE$                             A01X+007884Y+131770X0810Y0260     S0      
327$NONE$                             A01X+007884Y+129770X0810Y0260     S0      
327$NONE$                             A01X+007884Y+129270X0810Y0260     S0      
327$NONE$                             A01X+007884Y+128770X0810Y0260     S0      
317$NONE$                       D0320PA00X+007284Y+140681               S0      
317$NONE$                       D0320PA00X+007284Y+123358               S0      
327$NONE$                             A01X+007884Y+137770X0810Y0260     S0      
327$NONE$                             A01X+007884Y+137270X0810Y0260     S0      
327$NONE$                             A01X+007884Y+136270X0810Y0260     S0      
327$NONE$                             A01X+007884Y+135770X0810Y0260     S0      
327$NONE$                             A01X+008976Y+134650X0790Y0200     S0      
327$NONE$                             A01X+008976Y+134335X0790Y0200     S0      
327$NONE$                             A01X+008976Y+133705X0790Y0200     S0      
327$NONE$                             A01X+008976Y+133390X0790Y0200     S0      
327$NONE$                             A01X+008976Y+132760X0790Y0200     S0      
327$NONE$                             A01X+007721Y+092681X0790Y0200     S0      
327$NONE$                             A01X+008976Y+094728X0790Y0200     S0      
317$NONE$                       D0730PA00X+008209Y+098949               S0      
317$NONE$                       D0730PA00X+008209Y+083988               S0      
327$NONE$                             A01X+007884Y+092219X0810Y0260     S0      
327$NONE$                             A01X+007884Y+091718X0810Y0260     S0      
327$NONE$                             A01X+007884Y+091219X0810Y0260     S0      
327$NONE$                             A01X+007884Y+089218X0810Y0260     S0      
327$NONE$                             A01X+007884Y+088719X0810Y0260     S0      
327$NONE$                             A01X+007884Y+088219X0810Y0260     S0      
317$NONE$                       D0320PA00X+007284Y+100130               S0      
317$NONE$                       D0320PA00X+007284Y+082807               S0      
327$NONE$                             A01X+007884Y+097219X0810Y0260     S0      
327$NONE$                             A01X+007884Y+096718X0810Y0260     S0      
327$NONE$                             A01X+007884Y+095719X0810Y0260     S0      
327$NONE$                             A01X+007884Y+095219X0810Y0260     S0      
327$NONE$                             A01X+008976Y+094098X0790Y0200     S0      
327$NONE$                             A01X+008976Y+093784X0790Y0200     S0      
327$NONE$                             A01X+008976Y+093154X0790Y0200     S0      
327$NONE$                             A01X+008976Y+092839X0790Y0200     S0      
327$NONE$                             A01X+008976Y+092209X0790Y0200     S0      
327$NONE$                             A01X+007721Y+052130X0790Y0200     S0      
327$NONE$                             A01X+008976Y+054177X0790Y0200     S0      
317$NONE$                       D0730PA00X+008209Y+058398               S0      
317$NONE$                       D0730PA00X+008209Y+043437               S0      
327$NONE$                             A01X+007884Y+051667X0810Y0260     S0      
327$NONE$                             A01X+007884Y+051167X0810Y0260     S0      
327$NONE$                             A01X+007884Y+050667X0810Y0260     S0      
327$NONE$                             A01X+007884Y+048667X0810Y0260     S0      
327$NONE$                             A01X+007884Y+048167X0810Y0260     S0      
327$NONE$                             A01X+007884Y+047667X0810Y0260     S0      
317$NONE$                       D0320PA00X+007284Y+059579               S0      
317$NONE$                       D0320PA00X+007284Y+042256               S0      
327$NONE$                             A01X+007884Y+056667X0810Y0260     S0      
327$NONE$                             A01X+007884Y+056167X0810Y0260     S0      
327$NONE$                             A01X+007884Y+055167X0810Y0260     S0      
327$NONE$                             A01X+007884Y+054667X0810Y0260     S0      
327$NONE$                             A01X+008976Y+053547X0790Y0200     S0      
327$NONE$                             A01X+008976Y+053232X0790Y0200     S0      
327$NONE$                             A01X+008976Y+052602X0790Y0200     S0      
327$NONE$                             A01X+008976Y+052287X0790Y0200     S0      
327$NONE$                             A01X+008976Y+051658X0790Y0200     S0      
327$NONE$                             A01X+007721Y+011579X0790Y0200     S0      
327$NONE$                             A01X+008976Y+013626X0790Y0200     S0      
317$NONE$                       D0730PA00X+008209Y+017846               S0      
317$NONE$                       D0730PA00X+008209Y+002886               S0      
327$NONE$                             A01X+007884Y+011116X0810Y0260     S0      
327$NONE$                             A01X+007884Y+010616X0810Y0260     S0      
327$NONE$                             A01X+007884Y+010116X0810Y0260     S0      
327$NONE$                             A01X+007884Y+008116X0810Y0260     S0      
327$NONE$                             A01X+007884Y+007616X0810Y0260     S0      
327$NONE$                             A01X+007884Y+007116X0810Y0260     S0      
317$NONE$                       D0320PA00X+007284Y+019028               S0      
317$NONE$                       D0320PA00X+007284Y+001705               S0      
327$NONE$                             A01X+007884Y+016116X0810Y0260     S0      
327$NONE$                             A01X+007884Y+015616X0810Y0260     S0      
327$NONE$                             A01X+007884Y+014616X0810Y0260     S0      
327$NONE$                             A01X+007884Y+014116X0810Y0260     S0      
327$NONE$                             A01X+008976Y+012996X0790Y0200     S0      
327$NONE$                             A01X+008976Y+012681X0790Y0200     S0      
327$NONE$                             A01X+008976Y+012051X0790Y0200     S0      
327$NONE$                             A01X+008976Y+011736X0790Y0200     S0      
327$NONE$                             A01X+008976Y+011106X0790Y0200     S0      
317$NONE$                       D0400PA01X-004917Y+005214               S0      
317$NONE$                       D0400PA01X+100950Y+002750               S0      
317$NONE$                       D0400PA01X+101050Y+196600               S0      
317$NONE$                       D0400PA01X+108574Y+196760               S0      
317$NONE$                       D0400PA01X+108574Y+002266               S0      
317$NONE$                       D0400PA01X+002600Y+196550               S0      
317$NONE$                       D0400PA01X+032750Y+166200               S0      
317$NONE$                       D0400PA01X+032950Y+036350               S0      
317$NONE$                       D0400PA01X+034050Y+079350               S0      
317$NONE$                       D0400PA01X+034300Y+116600               S0      
317$NONE$                       D0400PA01X+039950Y+173400               S0      
317$NONE$                       D0400PA01X+040400Y+043200               S0      
317$NONE$                       D0400PA01X+040500Y+086250               S0      
317$NONE$                       D0400PA01X+041350Y+124750               S0      
327$NONE$                             A01X+071050Y+004150X2720Y2720     S0      
327SSD_PRSNT0                         A01X+038742Y+170689X0460Y0120     S0      
317SSD_PRSNT0                   D0220PA01X+042130Y+171050               S0      
317SSD_PRSNT0                   D0240PA01X+041750Y+171020               S0      
317SSD_PRSNT0       VIA        MD0280PA01X+041250Y+171150               S0      
317GND                          D0200PA00X+003169Y+192284               S0      
317GND                          D0200PA00X+003036Y+192784               S0      
317GND                          D0200PA00X+002665Y+193154               S0      
317GND                          D0200PA00X+001662Y+193154               S0      
317GND                          D0200PA00X+001295Y+192784               S0      
317GND                          D0200PA00X+001162Y+192284               S0      
317GND                          D0200PA00X+028563Y+027953               S0      
317GND                          D0200PA00X+028429Y+028453               S0      
317GND                          D0200PA00X+028059Y+028823               S0      
317GND                          D0200PA00X+027055Y+028823               S0      
317GND                          D0200PA00X+026689Y+028453               S0      
317GND                          D0200PA00X+026555Y+027953               S0      
317GND                          D0200PA00X+100807Y+016338               S0      
317GND                          D0200PA00X+100673Y+016838               S0      
317GND                          D0200PA00X+100303Y+017208               S0      
317GND                          D0200PA00X+099299Y+017208               S0      
317GND                          D0200PA00X+098933Y+016838               S0      
317GND                          D0200PA00X+098799Y+016338               S0      
317GND                          D0200PA00X+100807Y+190353               S0      
317GND                          D0200PA00X+100673Y+190853               S0      
317GND                          D0200PA00X+100303Y+191224               S0      
317GND                          D0200PA00X+099299Y+191224               S0      
317GND                          D0200PA00X+098933Y+190853               S0      
317GND                          D0200PA00X+098799Y+190353               S0      
317GND                          D0200PA00X+014390Y+001772               S0      
317GND                          D0200PA00X+014256Y+002272               S0      
317GND                          D0200PA00X+013886Y+002642               S0      
317GND                          D0200PA00X+012882Y+002642               S0      
317GND                          D0200PA00X+012516Y+002272               S0      
317GND                          D0200PA00X+012382Y+001772               S0      
317GND                          D0200PA00X+028563Y+190353               S0      
317GND                          D0200PA00X+028429Y+190853               S0      
317GND                          D0200PA00X+028059Y+191224               S0      
317GND                          D0200PA00X+027055Y+191224               S0      
317GND                          D0200PA00X+026689Y+190853               S0      
317GND                          D0200PA00X+026555Y+190353               S0      
317GND                          D0200PA00X+028563Y+108857               S0      
317GND                          D0200PA00X+028429Y+109357               S0      
317GND                          D0200PA00X+028059Y+109727               S0      
317GND                          D0200PA00X+027055Y+109727               S0      
317GND                          D0200PA00X+026689Y+109357               S0      
317GND                          D0200PA00X+026555Y+108857               S0      
317GND                          D0200PA00X+100807Y+108267               S0      
317GND                          D0200PA00X+100673Y+108767               S0      
317GND                          D0200PA00X+100303Y+109137               S0      
317GND                          D0200PA00X+099299Y+109137               S0      
317GND                          D0200PA00X+098933Y+108767               S0      
317GND                          D0200PA00X+098799Y+108267               S0      
317GND                          D0200PA00X+028563Y+068503               S0      
317GND                          D0200PA00X+028429Y+069003               S0      
317GND                          D0200PA00X+028059Y+069373               S0      
317GND                          D0200PA00X+027055Y+069373               S0      
317GND                          D0200PA00X+026689Y+069003               S0      
317GND                          D0200PA00X+026555Y+068503               S0      
317GND                          D0200PA00X+100807Y+068700               S0      
317GND                          D0200PA00X+100673Y+069200               S0      
317GND                          D0200PA00X+100303Y+069570               S0      
317GND                          D0200PA00X+099299Y+069570               S0      
317GND                          D0200PA00X+098933Y+069200               S0      
317GND                          D0200PA00X+098799Y+068700               S0      
317GND                          D0200PA00X+004350Y+028150               S0      
317GND                          D0200PA00X+004217Y+028650               S0      
317GND                          D0200PA00X+003847Y+029020               S0      
317GND                          D0200PA00X+002843Y+029020               S0      
317GND                          D0200PA00X+002476Y+028650               S0      
317GND                          D0200PA00X+002343Y+028150               S0      
327GND                                A01X+082750Y+170020X0550Y0450     S0      
327GND                                A01X+082750Y+173480X0550Y0450     S0      
327GND                                A01X+087886Y+168350X0570Y0830     S0      
327GND                                A01X+087886Y+167104X0570Y0830     S0      
327GND                                A01X+096070Y+141422X0830Y0570     S0      
327GND                                A01X+097320Y+141422X0830Y0570     S0      
327GND                                A01X+010630Y+084658X0830Y0570     S0      
327GND                                A01X+010020Y+081622X0830Y0570     S0      
327GND                                A01X+013780Y+114512X0830Y0570     S0      
327GND                                A01X+014000Y+117548X0830Y0570     S0      
327GND                                A01X+013760Y+155082X0830Y0570     S0      
327GND                                A01X+014550Y+158198X0830Y0570     S0      
327GND                                A01X+086630Y+155222X0830Y0570     S0      
327GND                                A01X+087450Y+158298X0830Y0570     S0      
327GND                                A01X+015210Y+005928X0830Y0570     S0      
327GND                                A01X+013960Y+005928X0830Y0570     S0      
327GND                                A01X+086610Y+074032X0830Y0570     S0      
327GND                                A01X+087400Y+077098X0830Y0570     S0      
327GND                                A01X+010640Y+125228X0830Y0570     S0      
327GND                                A01X+010640Y+122192X0830Y0570     S0      
327GND                                A01X+013780Y+074012X0830Y0570     S0      
327GND                                A01X+013790Y+077068X0830Y0570     S0      
327GND                                A01X+010630Y+044148X0830Y0570     S0      
327GND                                A01X+009960Y+041102X0830Y0570     S0      
327GND                                A01X+009740Y+196818X0830Y0570     S0      
327GND                                A01X+010990Y+196818X0830Y0570     S0      
327GND                                A01X+086630Y+033502X0830Y0570     S0      
327GND                                A01X+087400Y+036548X0830Y0570     S0      
327GND                                A01X+013780Y+033442X0830Y0570     S0      
327GND                                A01X+013790Y+036508X0830Y0570     S0      
327GND                                A01X+086620Y+114602X0830Y0570     S0      
327GND                                A01X+086600Y+117648X0830Y0570     S0      
327GND                                A01X+082550Y+196798X0830Y0570     S0      
327GND                                A01X+083800Y+196798X0830Y0570     S0      
327GND                                A01X+010000Y+162742X0830Y0570     S0      
327GND                                A01X+010700Y+165798X0830Y0570     S0      
327GND                                A01X+004018Y+184060X0570Y0830     S0      
327GND                                A01X+004018Y+187750X0570Y0830     S0      
327GND                                A01X+004018Y+185290X0570Y0830     S0      
327GND                                A01X+004018Y+186520X0570Y0830     S0      
327GND                                A01X+000886Y+059820X0980Y0200     S0      
327GND                                A01X+000886Y+060765X0980Y0200     S0      
327GND                                A01X+000886Y+061080X0980Y0200     S0      
327GND                                A01X+000886Y+062025X0980Y0200     S0      
327GND                                A01X+000886Y+062339X0980Y0200     S0      
327GND                                A01X+000886Y+063284X0980Y0200     S0      
327GND                                A01X+000886Y+063599X0980Y0200     S0      
327GND                                A01X+000886Y+064544X0980Y0200     S0      
327GND                                A01X+000886Y+066119X0980Y0200     S0      
327GND                                A01X+000886Y+067064X0980Y0200     S0      
327GND                                A01X+000886Y+067379X0980Y0200     S0      
327GND                                A01X+000886Y+068324X0980Y0200     S0      
327GND                                A01X+000886Y+068639X0980Y0200     S0      
327GND                                A01X+000886Y+069584X0980Y0200     S0      
327GND                                A01X+000886Y+069899X0980Y0200     S0      
327GND                                A01X+000886Y+070843X0980Y0200     S0      
327GND                                A01X+000886Y+071158X0980Y0200     S0      
327GND                                A01X+000886Y+072103X0980Y0200     S0      
327GND                                A01X+000886Y+072418X0980Y0200     S0      
327GND                                A01X+000886Y+073363X0980Y0200     S0      
327GND                                A01X+000886Y+075568X0980Y0200     S0      
327GND                                A01X+000886Y+076513X0980Y0200     S0      
327GND                                A01X+000886Y+076828X0980Y0200     S0      
327GND                                A01X+000886Y+077773X0980Y0200     S0      
327GND                                A01X+000886Y+079032X0980Y0200     S0      
327GND                                A01X+000886Y+079977X0980Y0200     S0      
327GND                                A01X+000886Y+080292X0980Y0200     S0      
327GND                                A01X+000886Y+081237X0980Y0200     S0      
327GND                                A01X+000886Y+081552X0980Y0200     S0      
327GND                                A01X+000886Y+082497X0980Y0200     S0      
327GND                                A01X+000886Y+082812X0980Y0200     S0      
327GND                                A01X+000886Y+083757X0980Y0200     S0      
327GND                                A01X+000886Y+084072X0980Y0200     S0      
327GND                                A01X+000886Y+085017X0980Y0200     S0      
327GND                                A01X+000886Y+085332X0980Y0200     S0      
327GND                                A01X+000886Y+086276X0980Y0200     S0      
327GND                                A01X+000886Y+086591X0980Y0200     S0      
327GND                                A01X+000886Y+087536X0980Y0200     S0      
327GND                                A01X+000886Y+087851X0980Y0200     S0      
327GND                                A01X+000886Y+088796X0980Y0200     S0      
327GND                                A01X+000886Y+089111X0980Y0200     S0      
327GND                                A01X+000886Y+090056X0980Y0200     S0      
327GND                                A01X+000886Y+090371X0980Y0200     S0      
327GND                                A01X+000886Y+091316X0980Y0200     S0      
327GND                                A08X+000886Y+060450X0980Y0200     S0      
327GND                                A08X+000886Y+061395X0980Y0200     S0      
327GND                                A08X+000886Y+061709X0980Y0200     S0      
327GND                                A08X+000886Y+062654X0980Y0200     S0      
327GND                                A08X+000886Y+062969X0980Y0200     S0      
327GND                                A08X+000886Y+063914X0980Y0200     S0      
327GND                                A08X+000886Y+064229X0980Y0200     S0      
327GND                                A08X+000886Y+065174X0980Y0200     S0      
327GND                                A08X+000886Y+065489X0980Y0200     S0      
327GND                                A08X+000886Y+066434X0980Y0200     S0      
327GND                                A08X+000886Y+066749X0980Y0200     S0      
327GND                                A08X+000886Y+067694X0980Y0200     S0      
327GND                                A08X+000886Y+068009X0980Y0200     S0      
327GND                                A08X+000886Y+068954X0980Y0200     S0      
327GND                                A08X+000886Y+069269X0980Y0200     S0      
327GND                                A08X+000886Y+070213X0980Y0200     S0      
327GND                                A08X+000886Y+070528X0980Y0200     S0      
327GND                                A08X+000886Y+071473X0980Y0200     S0      
327GND                                A08X+000886Y+071788X0980Y0200     S0      
327GND                                A08X+000886Y+072733X0980Y0200     S0      
327GND                                A08X+000886Y+074938X0980Y0200     S0      
327GND                                A08X+000886Y+075883X0980Y0200     S0      
327GND                                A08X+000886Y+076198X0980Y0200     S0      
327GND                                A08X+000886Y+077143X0980Y0200     S0      
327GND                                A08X+000886Y+078402X0980Y0200     S0      
327GND                                A08X+000886Y+079347X0980Y0200     S0      
327GND                                A08X+000886Y+079662X0980Y0200     S0      
327GND                                A08X+000886Y+080607X0980Y0200     S0      
327GND                                A08X+000886Y+080922X0980Y0200     S0      
327GND                                A08X+000886Y+081867X0980Y0200     S0      
327GND                                A08X+000886Y+082182X0980Y0200     S0      
327GND                                A08X+000886Y+083127X0980Y0200     S0      
327GND                                A08X+000886Y+083442X0980Y0200     S0      
327GND                                A08X+000886Y+084387X0980Y0200     S0      
327GND                                A08X+000886Y+084702X0980Y0200     S0      
327GND                                A08X+000886Y+085647X0980Y0200     S0      
327GND                                A08X+000886Y+085962X0980Y0200     S0      
327GND                                A08X+000886Y+086906X0980Y0200     S0      
327GND                                A08X+000886Y+087221X0980Y0200     S0      
327GND                                A08X+000886Y+088166X0980Y0200     S0      
327GND                                A08X+000886Y+089741X0980Y0200     S0      
327GND                                A08X+000886Y+090686X0980Y0200     S0      
327GND                                A08X+000886Y+091001X0980Y0200     S0      
327GND                                A08X+000886Y+091946X0980Y0200     S0      
327GND                                A01X+000886Y+109426X0980Y0200     S0      
327GND                                A01X+000886Y+110371X0980Y0200     S0      
327GND                                A01X+000886Y+110686X0980Y0200     S0      
327GND                                A01X+000886Y+111631X0980Y0200     S0      
327GND                                A01X+000886Y+113206X0980Y0200     S0      
327GND                                A01X+000886Y+114150X0980Y0200     S0      
327GND                                A01X+000886Y+114465X0980Y0200     S0      
327GND                                A01X+000886Y+115410X0980Y0200     S0      
327GND                                A01X+000886Y+115725X0980Y0200     S0      
327GND                                A01X+000886Y+116670X0980Y0200     S0      
327GND                                A01X+000886Y+116985X0980Y0200     S0      
327GND                                A01X+000886Y+117930X0980Y0200     S0      
327GND                                A01X+000886Y+118245X0980Y0200     S0      
327GND                                A01X+000886Y+119190X0980Y0200     S0      
327GND                                A01X+000886Y+119505X0980Y0200     S0      
327GND                                A01X+000886Y+120450X0980Y0200     S0      
327GND                                A01X+000886Y+120765X0980Y0200     S0      
327GND                                A01X+000886Y+121710X0980Y0200     S0      
327GND                                A01X+000886Y+122025X0980Y0200     S0      
327GND                                A01X+000886Y+122969X0980Y0200     S0      
327GND                                A01X+000886Y+125174X0980Y0200     S0      
327GND                                A01X+000886Y+126119X0980Y0200     S0      
327GND                                A01X+000886Y+126434X0980Y0200     S0      
327GND                                A01X+000886Y+127379X0980Y0200     S0      
327GND                                A01X+000886Y+127694X0980Y0200     S0      
327GND                                A01X+000886Y+128639X0980Y0200     S0      
327GND                                A01X+000886Y+128954X0980Y0200     S0      
327GND                                A01X+000886Y+129898X0980Y0200     S0      
327GND                                A01X+000886Y+131158X0980Y0200     S0      
327GND                                A01X+000886Y+132103X0980Y0200     S0      
327GND                                A01X+000886Y+132418X0980Y0200     S0      
327GND                                A01X+000886Y+133363X0980Y0200     S0      
327GND                                A01X+000886Y+133678X0980Y0200     S0      
327GND                                A01X+000886Y+134623X0980Y0200     S0      
327GND                                A01X+000886Y+134938X0980Y0200     S0      
327GND                                A01X+000886Y+135883X0980Y0200     S0      
327GND                                A01X+000886Y+136198X0980Y0200     S0      
327GND                                A01X+000886Y+137143X0980Y0200     S0      
327GND                                A01X+000886Y+137458X0980Y0200     S0      
327GND                                A01X+000886Y+138402X0980Y0200     S0      
327GND                                A01X+000886Y+138717X0980Y0200     S0      
327GND                                A01X+000886Y+139662X0980Y0200     S0      
327GND                                A01X+000886Y+139977X0980Y0200     S0      
327GND                                A01X+000886Y+140922X0980Y0200     S0      
327GND                                A08X+000886Y+110056X0980Y0200     S0      
327GND                                A08X+000886Y+111001X0980Y0200     S0      
327GND                                A08X+000886Y+111316X0980Y0200     S0      
327GND                                A08X+000886Y+112261X0980Y0200     S0      
327GND                                A08X+000886Y+113836X0980Y0200     S0      
327GND                                A08X+000886Y+114780X0980Y0200     S0      
327GND                                A08X+000886Y+115095X0980Y0200     S0      
327GND                                A08X+000886Y+116040X0980Y0200     S0      
327GND                                A08X+000886Y+116355X0980Y0200     S0      
327GND                                A08X+000886Y+117300X0980Y0200     S0      
327GND                                A08X+000886Y+117615X0980Y0200     S0      
327GND                                A08X+000886Y+118560X0980Y0200     S0      
327GND                                A08X+000886Y+118875X0980Y0200     S0      
327GND                                A08X+000886Y+119820X0980Y0200     S0      
327GND                                A08X+000886Y+120135X0980Y0200     S0      
327GND                                A08X+000886Y+121080X0980Y0200     S0      
327GND                                A08X+000886Y+121395X0980Y0200     S0      
327GND                                A08X+000886Y+122339X0980Y0200     S0      
327GND                                A08X+000886Y+124544X0980Y0200     S0      
327GND                                A08X+000886Y+125489X0980Y0200     S0      
327GND                                A08X+000886Y+125804X0980Y0200     S0      
327GND                                A08X+000886Y+126749X0980Y0200     S0      
327GND                                A08X+000886Y+127064X0980Y0200     S0      
327GND                                A08X+000886Y+128009X0980Y0200     S0      
327GND                                A08X+000886Y+128324X0980Y0200     S0      
327GND                                A08X+000886Y+129269X0980Y0200     S0      
327GND                                A08X+000886Y+129584X0980Y0200     S0      
327GND                                A08X+000886Y+130528X0980Y0200     S0      
327GND                                A08X+000886Y+131788X0980Y0200     S0      
327GND                                A08X+000886Y+132733X0980Y0200     S0      
327GND                                A08X+000886Y+133048X0980Y0200     S0      
327GND                                A08X+000886Y+133993X0980Y0200     S0      
327GND                                A08X+000886Y+134308X0980Y0200     S0      
327GND                                A08X+000886Y+135253X0980Y0200     S0      
327GND                                A08X+000886Y+135568X0980Y0200     S0      
327GND                                A08X+000886Y+136513X0980Y0200     S0      
327GND                                A08X+000886Y+136828X0980Y0200     S0      
327GND                                A08X+000886Y+137773X0980Y0200     S0      
327GND                                A08X+000886Y+138087X0980Y0200     S0      
327GND                                A08X+000886Y+139032X0980Y0200     S0      
327GND                                A08X+000886Y+139347X0980Y0200     S0      
327GND                                A08X+000886Y+140292X0980Y0200     S0      
327GND                                A08X+000886Y+140607X0980Y0200     S0      
327GND                                A08X+000886Y+141552X0980Y0200     S0      
327GND                                A01X+000886Y+151158X0980Y0200     S0      
327GND                                A01X+000886Y+152103X0980Y0200     S0      
327GND                                A01X+000886Y+153048X0980Y0200     S0      
327GND                                A01X+000886Y+153363X0980Y0200     S0      
327GND                                A01X+000886Y+154308X0980Y0200     S0      
327GND                                A01X+000886Y+154623X0980Y0200     S0      
327GND                                A01X+000886Y+155568X0980Y0200     S0      
327GND                                A01X+000886Y+155883X0980Y0200     S0      
327GND                                A01X+000886Y+156828X0980Y0200     S0      
327GND                                A01X+000886Y+158087X0980Y0200     S0      
327GND                                A01X+000886Y+159032X0980Y0200     S0      
327GND                                A01X+000886Y+159347X0980Y0200     S0      
327GND                                A01X+000886Y+160292X0980Y0200     S0      
327GND                                A01X+000886Y+160607X0980Y0200     S0      
327GND                                A01X+000886Y+161552X0980Y0200     S0      
327GND                                A01X+000886Y+161867X0980Y0200     S0      
327GND                                A01X+000886Y+162812X0980Y0200     S0      
327GND                                A01X+000886Y+163127X0980Y0200     S0      
327GND                                A01X+000886Y+164072X0980Y0200     S0      
327GND                                A01X+000886Y+166906X0980Y0200     S0      
327GND                                A01X+000886Y+167851X0980Y0200     S0      
327GND                                A01X+000886Y+168166X0980Y0200     S0      
327GND                                A01X+000886Y+169111X0980Y0200     S0      
327GND                                A01X+000886Y+169426X0980Y0200     S0      
327GND                                A01X+000886Y+170371X0980Y0200     S0      
327GND                                A01X+000886Y+171631X0980Y0200     S0      
327GND                                A01X+000886Y+172576X0980Y0200     S0      
327GND                                A01X+000886Y+172891X0980Y0200     S0      
327GND                                A01X+000886Y+173835X0980Y0200     S0      
327GND                                A01X+000886Y+174150X0980Y0200     S0      
327GND                                A01X+000886Y+175095X0980Y0200     S0      
327GND                                A01X+000886Y+175410X0980Y0200     S0      
327GND                                A01X+000886Y+176355X0980Y0200     S0      
327GND                                A01X+000886Y+177300X0980Y0200     S0      
327GND                                A01X+000886Y+178245X0980Y0200     S0      
327GND                                A01X+000886Y+179190X0980Y0200     S0      
327GND                                A01X+000886Y+180135X0980Y0200     S0      
327GND                                A01X+000886Y+180450X0980Y0200     S0      
327GND                                A01X+000886Y+180764X0980Y0200     S0      
327GND                                A01X+000886Y+181080X0980Y0200     S0      
327GND                                A01X+000886Y+181394X0980Y0200     S0      
327GND                                A01X+000886Y+181709X0980Y0200     S0      
327GND                                A08X+000886Y+151158X0980Y0200     S0      
327GND                                A08X+000886Y+152103X0980Y0200     S0      
327GND                                A08X+000886Y+152733X0980Y0200     S0      
327GND                                A08X+000886Y+153678X0980Y0200     S0      
327GND                                A08X+000886Y+153993X0980Y0200     S0      
327GND                                A08X+000886Y+154938X0980Y0200     S0      
327GND                                A08X+000886Y+155253X0980Y0200     S0      
327GND                                A08X+000886Y+156198X0980Y0200     S0      
327GND                                A08X+000886Y+156513X0980Y0200     S0      
327GND                                A08X+000886Y+157457X0980Y0200     S0      
327GND                                A08X+000886Y+158717X0980Y0200     S0      
327GND                                A08X+000886Y+159662X0980Y0200     S0      
327GND                                A08X+000886Y+159977X0980Y0200     S0      
327GND                                A08X+000886Y+160922X0980Y0200     S0      
327GND                                A08X+000886Y+161237X0980Y0200     S0      
327GND                                A08X+000886Y+162182X0980Y0200     S0      
327GND                                A08X+000886Y+162497X0980Y0200     S0      
327GND                                A08X+000886Y+163442X0980Y0200     S0      
327GND                                A08X+000886Y+163757X0980Y0200     S0      
327GND                                A08X+000886Y+164702X0980Y0200     S0      
327GND                                A08X+000886Y+166276X0980Y0200     S0      
327GND                                A08X+000886Y+167221X0980Y0200     S0      
327GND                                A08X+000886Y+167536X0980Y0200     S0      
327GND                                A08X+000886Y+168481X0980Y0200     S0      
327GND                                A08X+000886Y+168796X0980Y0200     S0      
327GND                                A08X+000886Y+169741X0980Y0200     S0      
327GND                                A08X+000886Y+171001X0980Y0200     S0      
327GND                                A08X+000886Y+171946X0980Y0200     S0      
327GND                                A08X+000886Y+172261X0980Y0200     S0      
327GND                                A08X+000886Y+173206X0980Y0200     S0      
327GND                                A08X+000886Y+173520X0980Y0200     S0      
327GND                                A08X+000886Y+174465X0980Y0200     S0      
327GND                                A08X+000886Y+174780X0980Y0200     S0      
327GND                                A08X+000886Y+175725X0980Y0200     S0      
327GND                                A08X+000886Y+176670X0980Y0200     S0      
327GND                                A08X+000886Y+177615X0980Y0200     S0      
327GND                                A08X+000886Y+180135X0980Y0200     S0      
327GND                                A08X+000886Y+180450X0980Y0200     S0      
327GND                                A08X+000886Y+180764X0980Y0200     S0      
327GND                                A08X+000886Y+181080X0980Y0200     S0      
327GND                                A08X+000886Y+181394X0980Y0200     S0      
327GND                                A08X+000886Y+181709X0980Y0200     S0      
327GND                                A01X+089125Y+135143X0480Y0160     S0      
327GND                                A01X+089125Y+094592X0480Y0160     S0      
327GND                                A01X+089125Y+054041X0480Y0160     S0      
327GND                                A01X+089225Y+013489X0480Y0160     S0      
327GND                                A01X+009773Y+024698X0480Y0160     S0      
327GND                                A01X+009773Y+065249X0480Y0160     S0      
327GND                                A01X+009773Y+105801X0480Y0160     S0      
327GND                                A01X+009773Y+146352X0480Y0160     S0      
327GND                                A01X+009076Y+184715X0160Y0480     S0      
327GND                                A01X+016290Y+013589X0480Y0160     S0      
327GND                                A01X+015606Y+055675X0160Y0480     S0      
327GND                                A01X+019256Y+094975X0160Y0480     S0      
327GND                                A01X+016290Y+135143X0480Y0160     S0      
327GND                                A01X+020760Y+177456X0480Y0160     S0      
327GND                                A01X+089125Y+175694X0480Y0160     S0      
327GND                                A01X+083550Y+173480X0550Y0450     S0      
327GND                                A01X+083550Y+170020X0550Y0450     S0      
317GND                          D1400PA00X+003347Y+102952               S0      
317GND                          D1400PA00X+026969Y+149015               S0      
317GND                          D0340PA01X+030810Y+041620               S0      
317GND                          D0340PA01X+030810Y+084670               S0      
317GND                          D0340PA01X+030820Y+121750               S0      
317GND                          D0340PA01X+030920Y+171570               S0      
327GND                                A01X+089252Y+171606X0120Y0370     S0      
327GND                                A01X+089055Y+171611X0120Y0360     S0      
327GND                                A01X+089350Y+171000X0660Y0660     S0      
317GND                          D0163PA01X+091650Y+172575               S0      
327GND                                A01X+030098Y+142930X0120Y0420     S0      
327GND                                A01X+030000Y+142150X0890Y0890     S0      
327GND                                A01X+029220Y+058648X0420Y0120     S0      
327GND                                A01X+030000Y+058550X0890Y0890     S0      
327GND                                A01X+035259Y+041280X0460Y0120     S0      
327GND                                A01X+035259Y+040296X0460Y0120     S0      
327GND                                A01X+036705Y+038259X0120Y0460     S0      
327GND                                A01X+038792Y+038523X0360Y0120     S0      
327GND                                A01X+038742Y+040099X0460Y0120     S0      
327GND                                A01X+038792Y+041477X0360Y0120     S0      
327GND                                A01X+036705Y+041742X0120Y0460     S0      
327GND                                A01X+037000Y+040000X2460Y2460     S0      
327GND                                A01X+035259Y+084279X0460Y0120     S0      
327GND                                A01X+035259Y+083296X0460Y0120     S0      
327GND                                A01X+036705Y+081259X0120Y0460     S0      
327GND                                A01X+038792Y+081524X0360Y0120     S0      
327GND                                A01X+038742Y+083099X0460Y0120     S0      
327GND                                A01X+038792Y+084477X0360Y0120     S0      
327GND                                A01X+036705Y+084742X0120Y0460     S0      
327GND                                A01X+037000Y+083000X2460Y2460     S0      
327GND                                A01X+035259Y+121430X0460Y0120     S0      
327GND                                A01X+035259Y+120445X0460Y0120     S0      
327GND                                A01X+036705Y+118409X0120Y0460     S0      
327GND                                A01X+038792Y+118674X0360Y0120     S0      
327GND                                A01X+038742Y+120248X0460Y0120     S0      
327GND                                A01X+038792Y+121627X0360Y0120     S0      
327GND                                A01X+036705Y+121892X0120Y0460     S0      
327GND                                A01X+037000Y+120150X2460Y2460     S0      
327GND                                A01X+035259Y+171280X0460Y0120     S0      
327GND                                A01X+035259Y+170296X0460Y0120     S0      
327GND                                A01X+036705Y+168259X0120Y0460     S0      
327GND                                A01X+038792Y+168523X0360Y0120     S0      
327GND                                A01X+038742Y+170099X0460Y0120     S0      
327GND                                A01X+038792Y+171477X0360Y0120     S0      
327GND                                A01X+036705Y+171742X0120Y0460     S0      
327GND                                A01X+037000Y+170000X2460Y2460     S0      
327GND                                A01X+003171Y+108129X1100Y0450     S0      
327GND                                A01X+004110Y+161515X1100Y0450     S0      
317GND                          D0220PA01X+005200Y+188420               S0      
327GND                                A01X+035850Y+008835X0120Y0600     S0      
327GND                                A01X+027316Y+177460X0140Y0600     S0      
327GND                                A01X+016514Y+053947X0600Y0140     S0      
327GND                                A01X+011396Y+148829X0600Y0140     S0      
327GND                                A01X+082065Y+018907X0600Y0140     S0      
327GND                                A01X+082065Y+180325X0600Y0140     S0      
327GND                                A01X+088450Y+172320X0550Y0450     S0      
317GND                          D0220PA01X+030620Y+169255               S0      
317GND                          D0220PA01X+030620Y+170345               S0      
317GND                          D0220PA01X+030520Y+120495               S0      
317GND                          D0220PA01X+030520Y+119405               S0      
317GND                          D0220PA01X+030450Y+083350               S0      
317GND                          D0220PA01X+030450Y+082260               S0      
317GND                          D0220PA01X+030510Y+040400               S0      
317GND                          D0220PA01X+030510Y+039310               S0      
317GND                          D0220PA01X+032920Y+058900               S0      
317GND                          D0220PA01X+031150Y+139230               S0      
317GND                          D0220PA01X+076924Y+195981               S0      
317GND                          D0220PA01X+081900Y+178830               S0      
317GND                          D0220PA01X+082100Y+158580               S0      
317GND                          D0220PA01X+082100Y+118030               S0      
317GND                          D0220PA01X+082100Y+077480               S0      
317GND                          D0220PA01X+082100Y+036930               S0      
317GND                          D0220PA01X+082050Y+017430               S0      
317GND                          D0220PA01X+085450Y+114560               S0      
317GND                          D0220PA01X+085610Y+074020               S0      
317GND                          D0220PA01X+085620Y+033420               S0      
317GND                          D0220PA01X+082850Y+017430               S0      
317GND                          D0220PA01X+083650Y+017430               S0      
317GND                          D0220PA01X+084790Y+194970               S0      
317GND                          D0220PA01X+082950Y+178830               S0      
317GND                          D0220PA01X+083750Y+178830               S0      
317GND                          D0220PA01X+085550Y+155120               S0      
317GND                          D0220PA01X+090650Y+173070               S0      
317GND                          D0220PA01X+037750Y+010130               S0      
317GND                          D0220PA01X+012160Y+005130               S0      
317GND                          D0220PA01X+020000Y+003220               S0      
317GND                          D0220PA01X+012080Y+044110               S0      
317GND                          D0220PA01X+012225Y+084555               S0      
317GND                          D0220PA01X+014913Y+040583               S0      
317GND                          D0220PA01X+014950Y+081170               S0      
317GND                          D0220PA01X+012150Y+125210               S0      
317GND                          D0220PA01X+011700Y+165780               S0      
317GND                          D0220PA01X+014950Y+121720               S0      
317GND                          D0220PA01X+014950Y+162270               S0      
317GND                          D0220PA01X+012645Y+033502               S0      
317GND                          D0220PA01X+012245Y+074062               S0      
317GND                          D0220PA01X+009450Y+036930               S0      
317GND                          D0220PA01X+009450Y+077480               S0      
317GND                          D0220PA01X+012240Y+114600               S0      
317GND                          D0220PA01X+010910Y+154820               S0      
317GND                          D0220PA01X+009450Y+118030               S0      
317GND                          D0220PA01X+008388Y+158018               S0      
317GND                          D0220PA01X+012650Y+194720               S0      
317GND                          D0220PA01X+004180Y+196060               S0      
317GND                          D0220PA01X+037810Y+008470               S0      
317GND                          D0220PA01X+027680Y+140750               S0      
317GND                          D0220PA01X+030350Y+139230               S0      
317GND                          D0220PA01X+032920Y+059700               S0      
317GND                          D0220PA01X+031300Y+056230               S0      
317GND                          D0220PA01X+033080Y+037300               S0      
317GND                          D0220PA01X+033080Y+080300               S0      
317GND                          D0220PA01X+032480Y+041300               S0      
317GND                          D0220PA01X+032480Y+084300               S0      
317GND                          D0220PA01X+033480Y+039300               S0      
317GND                          D0220PA01X+033480Y+082300               S0      
317GND                          D0220PA01X+033480Y+119450               S0      
317GND                          D0220PA01X+033080Y+117450               S0      
317GND                          D0220PA01X+033480Y+169500               S0      
317GND                          D0220PA01X+033080Y+167300               S0      
317GND                          D0220PA01X+032480Y+121450               S0      
317GND                          D0220PA01X+032480Y+171300               S0      
317GND                          D0220PA01X+036380Y+006850               S0      
317GND                          D0220PA01X+035250Y+007180               S0      
317GND                          D0220PA01X+028050Y+173130               S0      
317GND                          D0220PA01X+027150Y+179170               S0      
317GND                          D0220PA01X+027950Y+179170               S0      
317GND                          D0220PA01X+028750Y+179170               S0      
317GND                          D0220PA01X+019900Y+054620               S0      
317GND                          D0220PA01X+019900Y+053120               S0      
317GND                          D0220PA01X+019900Y+053870               S0      
317GND                          D0220PA01X+011400Y+147330               S0      
317GND                          D0220PA01X+012200Y+147330               S0      
317GND                          D0220PA01X+013000Y+147330               S0      
317GND                          D0300PA01X+078496Y+195326               S0      
317GND                          D0300PA01X+082013Y+157925               S0      
317GND                          D0300PA01X+082013Y+117375               S0      
317GND                          D0300PA01X+082013Y+076825               S0      
317GND                          D0300PA01X+082013Y+036275               S0      
317GND                          D0300PA01X+087288Y+135074               S0      
317GND                          D0300PA01X+087288Y+094523               S0      
317GND                          D0300PA01X+087288Y+053972               S0      
317GND                          D0300PA01X+086925Y+014112               S0      
317GND                          D0300PA01X+079449Y+196053               S0      
317GND                          D0300PA01X+077499Y+196053               S0      
317GND                          D0300PA01X+084625Y+158653               S0      
317GND                          D0300PA01X+082675Y+158653               S0      
317GND                          D0300PA01X+084625Y+118103               S0      
317GND                          D0300PA01X+082675Y+118103               S0      
317GND                          D0300PA01X+084625Y+077553               S0      
317GND                          D0300PA01X+082675Y+077553               S0      
317GND                          D0300PA01X+084625Y+037003               S0      
317GND                          D0300PA01X+082675Y+037003               S0      
317GND                          D0300PA01X+010175Y+022784               S0      
317GND                          D0300PA01X+019425Y+003148               S0      
317GND                          D0300PA01X+017475Y+003148               S0      
317GND                          D0300PA01X+010175Y+063335               S0      
317GND                          D0300PA01X+014337Y+040510               S0      
317GND                          D0300PA01X+012388Y+040510               S0      
317GND                          D0300PA01X+010175Y+103886               S0      
317GND                          D0300PA01X+014375Y+081098               S0      
317GND                          D0300PA01X+012425Y+081098               S0      
317GND                          D0300PA01X+010175Y+144438               S0      
317GND                          D0300PA01X+014375Y+121648               S0      
317GND                          D0300PA01X+012425Y+121648               S0      
317GND                          D0300PA01X+007697Y+185965               S0      
317GND                          D0300PA01X+012425Y+162198               S0      
317GND                          D0300PA01X+014375Y+162198               S0      
317GND                          D0300PA01X+014713Y+015625               S0      
317GND                          D0300PA01X+011975Y+037003               S0      
317GND                          D0300PA01X+010025Y+037003               S0      
317GND                          D0300PA01X+013612Y+056375               S0      
317GND                          D0300PA01X+011975Y+077553               S0      
317GND                          D0300PA01X+010025Y+077553               S0      
317GND                          D0300PA01X+020113Y+095273               S0      
317GND                          D0300PA01X+010025Y+118103               S0      
317GND                          D0300PA01X+011975Y+118103               S0      
317GND                          D0300PA01X+015113Y+137179               S0      
317GND                          D0300PA01X+008963Y+158090               S0      
317GND                          D0300PA01X+010913Y+158090               S0      
317GND                          D0300PA01X+021713Y+176375               S0      
317GND                          D0300PA01X+004785Y+196142               S0      
317GND                          D0300PA01X+006695Y+196133               S0      
317GND                          D0300PA01X+087288Y+175625               S0      
317GND                          D0300PA01X+020088Y+003875               S0      
317GND                          D0300PA01X+015228Y+041285               S0      
317GND                          D0300PA01X+015228Y+081835               S0      
317GND                          D0300PA01X+015258Y+122385               S0      
317GND                          D0300PA01X+015378Y+162935               S0      
317GND                          D0300PA01X+009183Y+036275               S0      
317GND                          D0300PA01X+009183Y+076825               S0      
317GND                          D0300PA01X+009183Y+117415               S0      
317GND                          D0300PA01X+009112Y+157025               S0      
317GND                          D0300PA01X+006163Y+195425               S0      
327GND                                A01X+098380Y+141430X0650Y0500     S0      
317GND                          D0340PA01X+010870Y+081750               S0      
317GND                          D0340PA01X+014850Y+117430               S0      
317GND                          D0340PA01X+013670Y+157980               S0      
317GND                          D0340PA01X+086600Y+158030               S0      
317GND                          D0340PA01X+013100Y+005660               S0      
317GND                          D0340PA01X+086500Y+076870               S0      
317GND                          D0340PA01X+009760Y+122360               S0      
317GND                          D0340PA01X+014650Y+076790               S0      
317GND                          D0340PA01X+010840Y+041200               S0      
317GND                          D0340PA01X+011850Y+196740               S0      
317GND                          D0340PA01X+086550Y+036280               S0      
317GND                          D0340PA01X+014660Y+036310               S0      
317GND                          D0340PA01X+087450Y+117480               S0      
317GND                          D0340PA01X+084650Y+196730               S0      
317GND                          D0340PA01X+010860Y+162820               S0      
317GND                          D0340PA01X+003710Y+182730               S0      
317GND                          D0340PA01X+003710Y+183210               S0      
317GND                          D0340PA01X+095900Y+162160               S0      
317GND                          D0340PA01X+099050Y+141670               S0      
317GND                          D0340PA01X+087250Y+146480               S0      
317GND                          D0340PA01X+087250Y+105930               S0      
317GND                          D0340PA01X+087250Y+065380               S0      
317GND                          D0340PA01X+087250Y+024520               S0      
317GND                          D0340PA01X+087150Y+186980               S0      
317GND                          D0340PA01X+091050Y+171330               S0      
317GND                          D0340PA01X+096370Y+167100               S0      
317GND                          D0340PA01X+096370Y+166100               S0      
317GND                          D0340PA01X+032590Y+058340               S0      
317GND                          D0340PA01X+029760Y+139570               S0      
317GND                          D0340PA01X+029300Y+174620               S0      
317GND                          D0340PA01X+028800Y+174620               S0      
317GND                          D0340PA01X+010000Y+012480               S0      
317GND                          D0340PA01X+010000Y+093580               S0      
317GND                          D0340PA01X+010000Y+053080               S0      
317GND                          D0340PA01X+010000Y+134080               S0      
317GND                          D0340PA01X+010000Y+175530               S0      
317GND                          D0340PA01X+014400Y+065380               S0      
317GND                          D0340PA01X+014400Y+024730               S0      
317GND                          D0340PA01X+014400Y+105930               S0      
317GND                          D0340PA01X+014400Y+146380               S0      
317GND                          D0340PA01X+014400Y+186980               S0      
317GND                          D0240PA01X+099460Y+141750               S0      
317GND                          D0240PA01X+086250Y+195150               S0      
317GND                          D0240PA01X+009840Y+084470               S0      
317GND                          D0240PA01X+014580Y+114680               S0      
317GND                          D0240PA01X+014580Y+155050               S0      
317GND                          D0240PA01X+087420Y+155390               S0      
317GND                          D0240PA01X+011570Y+004360               S0      
317GND                          D0240PA01X+087410Y+074320               S0      
317GND                          D0240PA01X+009840Y+125020               S0      
317GND                          D0240PA01X+014580Y+074230               S0      
317GND                          D0240PA01X+009840Y+043920               S0      
317GND                          D0240PA01X+013320Y+195090               S0      
317GND                          D0240PA01X+087420Y+033670               S0      
317GND                          D0240PA01X+014570Y+033660               S0      
317GND                          D0240PA01X+087410Y+114770               S0      
317GND                          D0240PA01X+009890Y+165610               S0      
317GND                          D0240PA01X+003620Y+181970               S0      
317GND                          D0240PA01X+003620Y+182320               S0      
317GND                          D0240PA01X+008200Y+024729               S0      
317GND                          D0240PA01X+008200Y+065280               S0      
317GND                          D0240PA01X+008325Y+105644               S0      
317GND                          D0240PA01X+008275Y+146195               S0      
317GND                          D0240PA01X+007659Y+185427               S0      
317GND                          D0240PA01X+017589Y+013786               S0      
317GND                          D0240PA01X+015530Y+056950               S0      
317GND                          D0240PA01X+018200Y+095270               S0      
317GND                          D0240PA01X+017589Y+135300               S0      
317GND                          D0240PA01X+019461Y+177299               S0      
317GND                          D0240PA01X+090524Y+013646               S0      
317GND                          D0240PA01X+090424Y+054198               S0      
317GND                          D0240PA01X+090424Y+094749               S0      
317GND                          D0240PA01X+090424Y+135300               S0      
317GND                          D0240PA01X+090424Y+175851               S0      
317GND                          D0240PA01X+083120Y+020300               S0      
317GND                          D0240PA01X+083120Y+181700               S0      
317GND                          D0240PA01X+084150Y+169870               S0      
317GND                          D0240PA01X+088570Y+169800               S0      
317GND                          D0240PA01X+036850Y+036770               S0      
317GND                          D0240PA01X+039350Y+083330               S0      
317GND                          D0240PA01X+034450Y+040630               S0      
317GND                          D0240PA01X+034100Y+040630               S0      
317GND                          D0240PA01X+034650Y+041670               S0      
317GND                          D0240PA01X+034300Y+041670               S0      
317GND                          D0240PA01X+034450Y+083630               S0      
317GND                          D0240PA01X+034100Y+083630               S0      
317GND                          D0240PA01X+034650Y+084670               S0      
317GND                          D0240PA01X+034300Y+084670               S0      
317GND                          D0240PA01X+039560Y+120230               S0      
317GND                          D0240PA01X+037250Y+167020               S0      
317GND                          D0240PA01X+034450Y+120780               S0      
317GND                          D0240PA01X+034100Y+120780               S0      
317GND                          D0240PA01X+034650Y+121820               S0      
317GND                          D0240PA01X+034300Y+121820               S0      
317GND                          D0240PA01X+034450Y+170630               S0      
317GND                          D0240PA01X+034100Y+170630               S0      
317GND                          D0240PA01X+034650Y+171670               S0      
317GND                          D0240PA01X+034300Y+171670               S0      
317GND                          D0240PA01X+037200Y+036770               S0      
317GND                          D0240PA01X+039350Y+038380               S0      
317GND                          D0240PA01X+039350Y+041470               S0      
317GND                          D0240PA01X+037200Y+043280               S0      
317GND                          D0240PA01X+036550Y+080020               S0      
317GND                          D0240PA01X+039180Y+080650               S0      
317GND                          D0240PA01X+039350Y+084470               S0      
317GND                          D0240PA01X+037200Y+086180               S0      
317GND                          D0240PA01X+039350Y+122170               S0      
317GND                          D0240PA01X+037200Y+123330               S0      
317GND                          D0240PA01X+039350Y+118130               S0      
317GND                          D0240PA01X+037100Y+117120               S0      
317GND                          D0240PA01X+038980Y+172350               S0      
317GND                          D0240PA01X+037250Y+173130               S0      
317GND                          D0240PA01X+038880Y+167650               S0      
317GND                          D0240PA01X+037600Y+167020               S0      
317GND                          D0240PA01X+039180Y+035250               S0      
317GND                          D0240PA01X+034370Y+044750               S0      
317GND                          D0240PA01X+034370Y+087750               S0      
317GND                          D0240PA01X+034370Y+124900               S0      
317GND                          D0240PA01X+035630Y+165250               S0      
317GND                          D0240PA01X+037920Y+044750               S0      
317GND                          D0240PA01X+035630Y+035250               S0      
317GND                          D0240PA01X+037920Y+087750               S0      
317GND                          D0240PA01X+037920Y+124900               S0      
317GND                          D0240PA01X+034370Y+174750               S0      
317GND                          D0240PA01X+038530Y+078250               S0      
317GND                          D0240PA01X+039180Y+115400               S0      
317GND                          D0240PA01X+041750Y+082080               S0      
317GND                          D0240PA01X+041750Y+122330               S0      
317GND                          D0240PA01X+041750Y+172180               S0      
317GND                          D0240PA01X+037430Y+008460               S0      
317GND                          D0240PA01X+037350Y+010120               S0      
317GND                          D0240PA01X+036370Y+007650               S0      
317GND                          D0240PA01X+036850Y+043280               S0      
317GND                          D0240PA01X+039560Y+040170               S0      
317GND                          D0240PA01X+036200Y+080020               S0      
317GND                          D0240PA01X+036850Y+086180               S0      
317GND                          D0240PA01X+036850Y+123330               S0      
317GND                          D0240PA01X+036750Y+117120               S0      
317GND                          D0240PA01X+039570Y+170080               S0      
317GND                          D0240PA01X+036900Y+173130               S0      
317GND                          D0240PA01X+035720Y+011700               S0      
317GND                          D0240PA01X+035720Y+012050               S0      
317GND                          D0240PA01X+017720Y+055350               S0      
317GND                          D0240PA01X+012470Y+150200               S0      
317GND                          D0240PA01X+038380Y+035250               S0      
317GND                          D0240PA01X+035170Y+087750               S0      
317GND                          D0240PA01X+035170Y+044750               S0      
317GND                          D0240PA01X+035170Y+124900               S0      
317GND                          D0240PA01X+034830Y+165250               S0      
317GND                          D0240PA01X+038720Y+044750               S0      
317GND                          D0240PA01X+034830Y+035250               S0      
317GND                          D0240PA01X+038720Y+124900               S0      
317GND                          D0240PA01X+038720Y+087750               S0      
317GND                          D0240PA01X+035170Y+174750               S0      
317GND                          D0240PA01X+037730Y+078250               S0      
317GND                          D0240PA01X+038380Y+115400               S0      
317GND                          D0240PA01X+041750Y+081280               S0      
317GND                          D0240PA01X+041750Y+121530               S0      
317GND                          D0240PA01X+041750Y+171380               S0      
327GND                                A08X+099025Y+152698X0010Y0010     S0      
317GND                          D1767PA08X+100155Y+152256               S0      
327GND                                A08X+099025Y+153698X0010Y0010     S0      
327GND                                A08X+099025Y+154098X0010Y0010     S0      
327GND                                A08X+099025Y+156698X0010Y0010     S0      
317GND                          D1767PA08X+100155Y+156256               S0      
327GND                                A08X+099025Y+157798X0010Y0010     S0      
327GND                                A08X+099025Y+158298X0010Y0010     S0      
327GND                                A08X+100154Y+160232X3940Y1720     S0      
327GND                                A08X+100304Y+160598X0010Y0010     S0      
327GND                                A01X+100154Y+160598X0010Y0010     S0      
327GND                                A01X+100154Y+160232X3940Y1720     S0      
327GND                                A01X+098875Y+158298X0010Y0010     S0      
327GND                                A01X+098875Y+157798X0010Y0010     S0      
317GND                          D1767PA01X+100155Y+156256               S0      
327GND                                A01X+098875Y+156698X0010Y0010     S0      
327GND                                A01X+098875Y+154098X0010Y0010     S0      
327GND                                A01X+098875Y+153698X0010Y0010     S0      
317GND                          D1767PA01X+100155Y+152256               S0      
327GND                                A01X+098875Y+152698X0010Y0010     S0      
327GND                                A08X+100974Y+162110X2300Y0320     S0      
327GND                                A08X+100974Y+165610X2300Y0320     S0      
327GND                                A08X+100974Y+166610X2300Y0320     S0      
327GND                                A08X+100974Y+167610X2300Y0320     S0      
327GND                                A01X+100974Y+167610X2300Y0320     S0      
327GND                                A01X+100974Y+164610X2300Y0320     S0      
327GND                                A01X+100974Y+163110X2300Y0320     S0      
327GND                                A01X+100974Y+162610X2300Y0320     S0      
327GND                                A01X+088268Y+183382X0790Y0200     S0      
327GND                                A01X+088268Y+184327X0790Y0200     S0      
327GND                                A01X+088268Y+185272X0790Y0200     S0      
327GND                                A01X+088268Y+193146X0790Y0200     S0      
327GND                                A01X+088268Y+194091X0790Y0200     S0      
327GND                                A01X+089360Y+190097X0810Y0260     S0      
327GND                                A01X+089360Y+190596X0810Y0260     S0      
327GND                                A01X+089360Y+193596X0810Y0260     S0      
327GND                                A01X+089360Y+182597X0810Y0260     S0      
327GND                                A01X+089360Y+184097X0810Y0260     S0      
327GND                                A01X+089360Y+185596X0810Y0260     S0      
327GND                                A01X+088268Y+185902X0790Y0200     S0      
327GND                                A01X+088268Y+186846X0790Y0200     S0      
327GND                                A01X+088268Y+187791X0790Y0200     S0      
327GND                                A01X+088268Y+188421X0790Y0200     S0      
327GND                                A01X+088268Y+189366X0790Y0200     S0      
327GND                                A01X+088268Y+190311X0790Y0200     S0      
327GND                                A01X+088268Y+191256X0790Y0200     S0      
327GND                                A01X+088268Y+192201X0790Y0200     S0      
327GND                                A01X+088268Y+142831X0790Y0200     S0      
327GND                                A01X+088268Y+143776X0790Y0200     S0      
327GND                                A01X+088268Y+144721X0790Y0200     S0      
327GND                                A01X+088268Y+152595X0790Y0200     S0      
327GND                                A01X+088268Y+153539X0790Y0200     S0      
327GND                                A01X+089360Y+149545X0810Y0260     S0      
327GND                                A01X+089360Y+150045X0810Y0260     S0      
327GND                                A01X+089360Y+153045X0810Y0260     S0      
327GND                                A01X+089360Y+142045X0810Y0260     S0      
327GND                                A01X+089360Y+143545X0810Y0260     S0      
327GND                                A01X+089360Y+145045X0810Y0260     S0      
327GND                                A01X+088268Y+145350X0790Y0200     S0      
327GND                                A01X+088268Y+146295X0790Y0200     S0      
327GND                                A01X+088268Y+147240X0790Y0200     S0      
327GND                                A01X+088268Y+147870X0790Y0200     S0      
327GND                                A01X+088268Y+148815X0790Y0200     S0      
327GND                                A01X+088268Y+149760X0790Y0200     S0      
327GND                                A01X+088268Y+150705X0790Y0200     S0      
327GND                                A01X+088268Y+151650X0790Y0200     S0      
327GND                                A01X+088268Y+102280X0790Y0200     S0      
327GND                                A01X+088268Y+103224X0790Y0200     S0      
327GND                                A01X+088268Y+104169X0790Y0200     S0      
327GND                                A01X+088268Y+112043X0790Y0200     S0      
327GND                                A01X+088268Y+112988X0790Y0200     S0      
327GND                                A01X+089360Y+108994X0810Y0260     S0      
327GND                                A01X+089360Y+109494X0810Y0260     S0      
327GND                                A01X+089360Y+112494X0810Y0260     S0      
327GND                                A01X+089360Y+101494X0810Y0260     S0      
327GND                                A01X+089360Y+102994X0810Y0260     S0      
327GND                                A01X+089360Y+104494X0810Y0260     S0      
327GND                                A01X+088268Y+104799X0790Y0200     S0      
327GND                                A01X+088268Y+105744X0790Y0200     S0      
327GND                                A01X+088268Y+106689X0790Y0200     S0      
327GND                                A01X+088268Y+107319X0790Y0200     S0      
327GND                                A01X+088268Y+108264X0790Y0200     S0      
327GND                                A01X+088268Y+109209X0790Y0200     S0      
327GND                                A01X+088268Y+110154X0790Y0200     S0      
327GND                                A01X+088268Y+111098X0790Y0200     S0      
327GND                                A01X+088268Y+061728X0790Y0200     S0      
327GND                                A01X+088268Y+062673X0790Y0200     S0      
327GND                                A01X+088268Y+063618X0790Y0200     S0      
327GND                                A01X+088268Y+071492X0790Y0200     S0      
327GND                                A01X+088268Y+072437X0790Y0200     S0      
327GND                                A01X+089360Y+068443X0810Y0260     S0      
327GND                                A01X+089360Y+068943X0810Y0260     S0      
327GND                                A01X+089360Y+071943X0810Y0260     S0      
327GND                                A01X+089360Y+060943X0810Y0260     S0      
327GND                                A01X+089360Y+062443X0810Y0260     S0      
327GND                                A01X+089360Y+063943X0810Y0260     S0      
327GND                                A01X+088268Y+064248X0790Y0200     S0      
327GND                                A01X+088268Y+065193X0790Y0200     S0      
327GND                                A01X+088268Y+066138X0790Y0200     S0      
327GND                                A01X+088268Y+066768X0790Y0200     S0      
327GND                                A01X+088268Y+067713X0790Y0200     S0      
327GND                                A01X+088268Y+068658X0790Y0200     S0      
327GND                                A01X+088268Y+069602X0790Y0200     S0      
327GND                                A01X+088268Y+070547X0790Y0200     S0      
327GND                                A01X+088268Y+021177X0790Y0200     S0      
327GND                                A01X+088268Y+022122X0790Y0200     S0      
327GND                                A01X+088268Y+023067X0790Y0200     S0      
327GND                                A01X+088268Y+030941X0790Y0200     S0      
327GND                                A01X+088268Y+031886X0790Y0200     S0      
327GND                                A01X+089360Y+027892X0810Y0260     S0      
327GND                                A01X+089360Y+028392X0810Y0260     S0      
327GND                                A01X+089360Y+031392X0810Y0260     S0      
327GND                                A01X+089360Y+020392X0810Y0260     S0      
327GND                                A01X+089360Y+021892X0810Y0260     S0      
327GND                                A01X+089360Y+023392X0810Y0260     S0      
327GND                                A01X+088268Y+023697X0790Y0200     S0      
327GND                                A01X+088268Y+024642X0790Y0200     S0      
327GND                                A01X+088268Y+025587X0790Y0200     S0      
327GND                                A01X+088268Y+026216X0790Y0200     S0      
327GND                                A01X+088268Y+027161X0790Y0200     S0      
327GND                                A01X+088268Y+028106X0790Y0200     S0      
327GND                                A01X+088268Y+029051X0790Y0200     S0      
327GND                                A01X+088268Y+029996X0790Y0200     S0      
327GND                                A01X+015433Y+183382X0790Y0200     S0      
327GND                                A01X+015433Y+184327X0790Y0200     S0      
327GND                                A01X+015433Y+185272X0790Y0200     S0      
327GND                                A01X+015433Y+193146X0790Y0200     S0      
327GND                                A01X+015433Y+194091X0790Y0200     S0      
327GND                                A01X+016526Y+190097X0810Y0260     S0      
327GND                                A01X+016526Y+190596X0810Y0260     S0      
327GND                                A01X+016526Y+193596X0810Y0260     S0      
327GND                                A01X+016526Y+182597X0810Y0260     S0      
327GND                                A01X+016526Y+184097X0810Y0260     S0      
327GND                                A01X+016526Y+185596X0810Y0260     S0      
327GND                                A01X+015433Y+185902X0790Y0200     S0      
327GND                                A01X+015433Y+186846X0790Y0200     S0      
327GND                                A01X+015433Y+187791X0790Y0200     S0      
327GND                                A01X+015433Y+188421X0790Y0200     S0      
327GND                                A01X+015433Y+189366X0790Y0200     S0      
327GND                                A01X+015433Y+190311X0790Y0200     S0      
327GND                                A01X+015433Y+191256X0790Y0200     S0      
327GND                                A01X+015433Y+192201X0790Y0200     S0      
327GND                                A01X+015433Y+142831X0790Y0200     S0      
327GND                                A01X+015433Y+143776X0790Y0200     S0      
327GND                                A01X+015433Y+144721X0790Y0200     S0      
327GND                                A01X+015433Y+152595X0790Y0200     S0      
327GND                                A01X+015433Y+153539X0790Y0200     S0      
327GND                                A01X+016526Y+149545X0810Y0260     S0      
327GND                                A01X+016526Y+150045X0810Y0260     S0      
327GND                                A01X+016526Y+153045X0810Y0260     S0      
327GND                                A01X+016526Y+142045X0810Y0260     S0      
327GND                                A01X+016526Y+143545X0810Y0260     S0      
327GND                                A01X+016526Y+145045X0810Y0260     S0      
327GND                                A01X+015433Y+145350X0790Y0200     S0      
327GND                                A01X+015433Y+146295X0790Y0200     S0      
327GND                                A01X+015433Y+147240X0790Y0200     S0      
327GND                                A01X+015433Y+147870X0790Y0200     S0      
327GND                                A01X+015433Y+148815X0790Y0200     S0      
327GND                                A01X+015433Y+149760X0790Y0200     S0      
327GND                                A01X+015433Y+150705X0790Y0200     S0      
327GND                                A01X+015433Y+151650X0790Y0200     S0      
327GND                                A01X+015433Y+102280X0790Y0200     S0      
327GND                                A01X+015433Y+103224X0790Y0200     S0      
327GND                                A01X+015433Y+104169X0790Y0200     S0      
327GND                                A01X+015433Y+112043X0790Y0200     S0      
327GND                                A01X+015433Y+112988X0790Y0200     S0      
327GND                                A01X+016526Y+108994X0810Y0260     S0      
327GND                                A01X+016526Y+109494X0810Y0260     S0      
327GND                                A01X+016526Y+112494X0810Y0260     S0      
327GND                                A01X+016526Y+101494X0810Y0260     S0      
327GND                                A01X+016526Y+102994X0810Y0260     S0      
327GND                                A01X+016526Y+104494X0810Y0260     S0      
327GND                                A01X+015433Y+104799X0790Y0200     S0      
327GND                                A01X+015433Y+105744X0790Y0200     S0      
327GND                                A01X+015433Y+106689X0790Y0200     S0      
327GND                                A01X+015433Y+107319X0790Y0200     S0      
327GND                                A01X+015433Y+108264X0790Y0200     S0      
327GND                                A01X+015433Y+109209X0790Y0200     S0      
327GND                                A01X+015433Y+110154X0790Y0200     S0      
327GND                                A01X+015433Y+111098X0790Y0200     S0      
327GND                                A01X+015433Y+061728X0790Y0200     S0      
327GND                                A01X+015433Y+062673X0790Y0200     S0      
327GND                                A01X+015433Y+063618X0790Y0200     S0      
327GND                                A01X+015433Y+071492X0790Y0200     S0      
327GND                                A01X+015433Y+072437X0790Y0200     S0      
327GND                                A01X+016526Y+068443X0810Y0260     S0      
327GND                                A01X+016526Y+068943X0810Y0260     S0      
327GND                                A01X+016526Y+071943X0810Y0260     S0      
327GND                                A01X+016526Y+060943X0810Y0260     S0      
327GND                                A01X+016526Y+062443X0810Y0260     S0      
327GND                                A01X+016526Y+063943X0810Y0260     S0      
327GND                                A01X+015433Y+064248X0790Y0200     S0      
327GND                                A01X+015433Y+065193X0790Y0200     S0      
327GND                                A01X+015433Y+066138X0790Y0200     S0      
327GND                                A01X+015433Y+066768X0790Y0200     S0      
327GND                                A01X+015433Y+067713X0790Y0200     S0      
327GND                                A01X+015433Y+068658X0790Y0200     S0      
327GND                                A01X+015433Y+069602X0790Y0200     S0      
327GND                                A01X+015433Y+070547X0790Y0200     S0      
327GND                                A01X+015433Y+021177X0790Y0200     S0      
327GND                                A01X+015433Y+022122X0790Y0200     S0      
327GND                                A01X+015433Y+023067X0790Y0200     S0      
327GND                                A01X+015433Y+030941X0790Y0200     S0      
327GND                                A01X+015433Y+031886X0790Y0200     S0      
327GND                                A01X+016526Y+027892X0810Y0260     S0      
327GND                                A01X+016526Y+028392X0810Y0260     S0      
327GND                                A01X+016526Y+031392X0810Y0260     S0      
327GND                                A01X+016526Y+020392X0810Y0260     S0      
327GND                                A01X+016526Y+021892X0810Y0260     S0      
327GND                                A01X+016526Y+023392X0810Y0260     S0      
327GND                                A01X+015433Y+023697X0790Y0200     S0      
327GND                                A01X+015433Y+024642X0790Y0200     S0      
327GND                                A01X+015433Y+025587X0790Y0200     S0      
327GND                                A01X+015433Y+026216X0790Y0200     S0      
327GND                                A01X+015433Y+027161X0790Y0200     S0      
327GND                                A01X+015433Y+028106X0790Y0200     S0      
327GND                                A01X+015433Y+029051X0790Y0200     S0      
327GND                                A01X+015433Y+029996X0790Y0200     S0      
327GND                                A01X+008976Y+178036X0790Y0200     S0      
327GND                                A01X+008976Y+177091X0790Y0200     S0      
327GND                                A01X+008976Y+176146X0790Y0200     S0      
327GND                                A01X+008976Y+168272X0790Y0200     S0      
327GND                                A01X+008976Y+167327X0790Y0200     S0      
327GND                                A01X+007884Y+171321X0810Y0260     S0      
327GND                                A01X+007884Y+170821X0810Y0260     S0      
327GND                                A01X+007884Y+167821X0810Y0260     S0      
327GND                                A01X+007884Y+178821X0810Y0260     S0      
327GND                                A01X+007884Y+177321X0810Y0260     S0      
327GND                                A01X+007884Y+175821X0810Y0260     S0      
327GND                                A01X+008976Y+175516X0790Y0200     S0      
327GND                                A01X+008976Y+174571X0790Y0200     S0      
327GND                                A01X+008976Y+173626X0790Y0200     S0      
327GND                                A01X+008976Y+172996X0790Y0200     S0      
327GND                                A01X+008976Y+172051X0790Y0200     S0      
327GND                                A01X+008976Y+171106X0790Y0200     S0      
327GND                                A01X+008976Y+170162X0790Y0200     S0      
327GND                                A01X+008976Y+169217X0790Y0200     S0      
327GND                                A01X+008976Y+137484X0790Y0200     S0      
327GND                                A01X+008976Y+136539X0790Y0200     S0      
327GND                                A01X+008976Y+135594X0790Y0200     S0      
327GND                                A01X+008976Y+127721X0790Y0200     S0      
327GND                                A01X+008976Y+126776X0790Y0200     S0      
327GND                                A01X+007884Y+130770X0810Y0260     S0      
327GND                                A01X+007884Y+130270X0810Y0260     S0      
327GND                                A01X+007884Y+127270X0810Y0260     S0      
327GND                                A01X+007884Y+138270X0810Y0260     S0      
327GND                                A01X+007884Y+136770X0810Y0260     S0      
327GND                                A01X+007884Y+135270X0810Y0260     S0      
327GND                                A01X+008976Y+134965X0790Y0200     S0      
327GND                                A01X+008976Y+134020X0790Y0200     S0      
327GND                                A01X+008976Y+133075X0790Y0200     S0      
327GND                                A01X+008976Y+132445X0790Y0200     S0      
327GND                                A01X+008976Y+131500X0790Y0200     S0      
327GND                                A01X+008976Y+130555X0790Y0200     S0      
327GND                                A01X+008976Y+129610X0790Y0200     S0      
327GND                                A01X+008976Y+128665X0790Y0200     S0      
327GND                                A01X+008976Y+096933X0790Y0200     S0      
327GND                                A01X+008976Y+095988X0790Y0200     S0      
327GND                                A01X+008976Y+095043X0790Y0200     S0      
327GND                                A01X+008976Y+087169X0790Y0200     S0      
327GND                                A01X+008976Y+086224X0790Y0200     S0      
327GND                                A01X+007884Y+090219X0810Y0260     S0      
327GND                                A01X+007884Y+089719X0810Y0260     S0      
327GND                                A01X+007884Y+086718X0810Y0260     S0      
327GND                                A01X+007884Y+097719X0810Y0260     S0      
327GND                                A01X+007884Y+096219X0810Y0260     S0      
327GND                                A01X+007884Y+094719X0810Y0260     S0      
327GND                                A01X+008976Y+094413X0790Y0200     S0      
327GND                                A01X+008976Y+093469X0790Y0200     S0      
327GND                                A01X+008976Y+092524X0790Y0200     S0      
327GND                                A01X+008976Y+091894X0790Y0200     S0      
327GND                                A01X+008976Y+090949X0790Y0200     S0      
327GND                                A01X+008976Y+090004X0790Y0200     S0      
327GND                                A01X+008976Y+089059X0790Y0200     S0      
327GND                                A01X+008976Y+088114X0790Y0200     S0      
327GND                                A01X+008976Y+056382X0790Y0200     S0      
327GND                                A01X+008976Y+055437X0790Y0200     S0      
327GND                                A01X+008976Y+054492X0790Y0200     S0      
327GND                                A01X+008976Y+046618X0790Y0200     S0      
327GND                                A01X+008976Y+045673X0790Y0200     S0      
327GND                                A01X+007884Y+049667X0810Y0260     S0      
327GND                                A01X+007884Y+049167X0810Y0260     S0      
327GND                                A01X+007884Y+046167X0810Y0260     S0      
327GND                                A01X+007884Y+057167X0810Y0260     S0      
327GND                                A01X+007884Y+055667X0810Y0260     S0      
327GND                                A01X+007884Y+054167X0810Y0260     S0      
327GND                                A01X+008976Y+053862X0790Y0200     S0      
327GND                                A01X+008976Y+052917X0790Y0200     S0      
327GND                                A01X+008976Y+051972X0790Y0200     S0      
327GND                                A01X+008976Y+051343X0790Y0200     S0      
327GND                                A01X+008976Y+050398X0790Y0200     S0      
327GND                                A01X+008976Y+049453X0790Y0200     S0      
327GND                                A01X+008976Y+048508X0790Y0200     S0      
327GND                                A01X+008976Y+047563X0790Y0200     S0      
327GND                                A01X+008976Y+015831X0790Y0200     S0      
327GND                                A01X+008976Y+014886X0790Y0200     S0      
327GND                                A01X+008976Y+013941X0790Y0200     S0      
327GND                                A01X+008976Y+006067X0790Y0200     S0      
327GND                                A01X+008976Y+005122X0790Y0200     S0      
327GND                                A01X+007884Y+009116X0810Y0260     S0      
327GND                                A01X+007884Y+008616X0810Y0260     S0      
327GND                                A01X+007884Y+005616X0810Y0260     S0      
327GND                                A01X+007884Y+016616X0810Y0260     S0      
327GND                                A01X+007884Y+015116X0810Y0260     S0      
327GND                                A01X+007884Y+013616X0810Y0260     S0      
327GND                                A01X+008976Y+013311X0790Y0200     S0      
327GND                                A01X+008976Y+012366X0790Y0200     S0      
327GND                                A01X+008976Y+011421X0790Y0200     S0      
327GND                                A01X+008976Y+010791X0790Y0200     S0      
327GND                                A01X+008976Y+009846X0790Y0200     S0      
327GND                                A01X+008976Y+008902X0790Y0200     S0      
327GND                                A01X+008976Y+007957X0790Y0200     S0      
327GND                                A01X+008976Y+007012X0790Y0200     S0      
317GND              VIA        MD0280PA08X+068900Y+159250               S0      
317GND              VIA        MD0280PA08X+069850Y+181200               S0      
317GND              VIA        MD0280PA08X+071990Y+093920               S0      
317GND              VIA        MD0280PA08X+074046Y+149939               S0      
317GND              VIA        MD0280PA08X+094000Y+157000               S0      
317GND              VIA        MD0280PA08X+094000Y+160500               S0      
317GND              VIA        MD0280PA08X+095000Y+155000               S0      
317GND              VIA        MD0280PA08X+096000Y+154000               S0      
317GND              VIA        MD0280PA01X+027272Y+158480               S0      
317GND              VIA        MD0280PA01X+028795Y+009325               S0      
317GND              VIA        MD0280PA01X+034886Y+107010               S0      
317GND              VIA        MD0280PA01X+047430Y+042369               S0      
317GND              VIA        MD0280PA01X+048636Y+093279               S0      
317GND              VIA        MD0280PA01X+066864Y+013132               S0      
317GND              VIA        MD0280PA01X+085290Y+124903               S0      
317GND              VIA        MD0100PA00X+001002Y+000550               S0      
317GND              VIA        MD0100PA00X+010000Y+175900               S0      
317GND              VIA        MD0100PA00X+010000Y+178000               S0      
317GND              VIA        MD0100PA00X+010000Y+018000               S0      
317GND              VIA        MD0100PA00X+010000Y+192800               S0      
317GND              VIA        MD0100PA00X+100000Y+010000               S0      
317GND              VIA        MD0100PA00X+100000Y+100000               S0      
317GND              VIA        MD0100PA00X+100000Y+102000               S0      
317GND              VIA        MD0100PA00X+100000Y+104000               S0      
317GND              VIA        MD0100PA00X+100000Y+112000               S0      
317GND              VIA        MD0100PA00X+100000Y+114000               S0      
317GND              VIA        MD0100PA00X+100000Y+116000               S0      
317GND              VIA        MD0100PA00X+100000Y+118000               S0      
317GND              VIA        MD0100PA00X+100000Y+012000               S0      
317GND              VIA        MD0100PA00X+100000Y+120000               S0      
317GND              VIA        MD0100PA00X+100000Y+122000               S0      
317GND              VIA        MD0100PA00X+100000Y+124000               S0      
317GND              VIA        MD0100PA00X+100000Y+126000               S0      
317GND              VIA        MD0100PA00X+100000Y+128000               S0      
317GND              VIA        MD0100PA00X+100000Y+130000               S0      
317GND              VIA        MD0100PA00X+100000Y+132000               S0      
317GND              VIA        MD0100PA00X+100000Y+134000               S0      
317GND              VIA        MD0100PA00X+100000Y+136000               S0      
317GND              VIA        MD0100PA00X+100000Y+138000               S0      
317GND              VIA        MD0100PA00X+100000Y+140000               S0      
317GND              VIA        MD0100PA00X+100000Y+170000               S0      
317GND              VIA        MD0100PA00X+100000Y+172000               S0      
317GND              VIA        MD0100PA00X+100000Y+174000               S0      
317GND              VIA        MD0100PA00X+100000Y+176000               S0      
317GND              VIA        MD0100PA00X+100000Y+178000               S0      
317GND              VIA        MD0100PA00X+100000Y+180000               S0      
317GND              VIA        MD0100PA00X+100000Y+182000               S0      
317GND              VIA        MD0100PA00X+100000Y+184000               S0      
317GND              VIA        MD0100PA00X+100000Y+186000               S0      
317GND              VIA        MD0100PA00X+100000Y+194000               S0      
317GND              VIA        MD0100PA00X+100000Y+196000               S0      
317GND              VIA        MD0100PA00X+100000Y+198000               S0      
317GND              VIA        MD0100PA00X+100000Y+002000               S0      
317GND              VIA        MD0100PA00X+100000Y+020000               S0      
317GND              VIA        MD0100PA00X+100000Y+022000               S0      
317GND              VIA        MD0100PA00X+100000Y+024000               S0      
317GND              VIA        MD0100PA00X+100000Y+026000               S0      
317GND              VIA        MD0100PA00X+100000Y+028000               S0      
317GND              VIA        MD0100PA00X+100000Y+030000               S0      
317GND              VIA        MD0100PA00X+100000Y+032000               S0      
317GND              VIA        MD0100PA00X+100000Y+034000               S0      
317GND              VIA        MD0100PA00X+100000Y+036000               S0      
317GND              VIA        MD0100PA00X+100000Y+038000               S0      
317GND              VIA        MD0100PA00X+100000Y+004000               S0      
317GND              VIA        MD0100PA00X+100000Y+040000               S0      
317GND              VIA        MD0100PA00X+100000Y+042000               S0      
317GND              VIA        MD0100PA00X+100000Y+044000               S0      
317GND              VIA        MD0100PA00X+100000Y+046000               S0      
317GND              VIA        MD0100PA00X+100000Y+048000               S0      
317GND              VIA        MD0100PA00X+100000Y+050000               S0      
317GND              VIA        MD0100PA00X+100000Y+052000               S0      
317GND              VIA        MD0100PA00X+100000Y+054000               S0      
317GND              VIA        MD0100PA00X+100000Y+056000               S0      
317GND              VIA        MD0100PA00X+100000Y+058000               S0      
317GND              VIA        MD0100PA00X+100000Y+006000               S0      
317GND              VIA        MD0100PA00X+100000Y+060000               S0      
317GND              VIA        MD0100PA00X+100000Y+062000               S0      
317GND              VIA        MD0100PA00X+100000Y+064000               S0      
317GND              VIA        MD0100PA00X+100000Y+072000               S0      
317GND              VIA        MD0100PA00X+100000Y+074000               S0      
317GND              VIA        MD0100PA00X+100000Y+076000               S0      
317GND              VIA        MD0100PA00X+100000Y+078000               S0      
317GND              VIA        MD0100PA00X+100000Y+008000               S0      
317GND              VIA        MD0100PA00X+100000Y+080000               S0      
317GND              VIA        MD0100PA00X+100000Y+082000               S0      
317GND              VIA        MD0100PA00X+100000Y+084000               S0      
317GND              VIA        MD0100PA00X+100000Y+086000               S0      
317GND              VIA        MD0100PA00X+100000Y+088000               S0      
317GND              VIA        MD0100PA00X+100000Y+090000               S0      
317GND              VIA        MD0100PA00X+100000Y+092000               S0      
317GND              VIA        MD0100PA00X+100000Y+094000               S0      
317GND              VIA        MD0100PA00X+100000Y+096000               S0      
317GND              VIA        MD0100PA00X+100000Y+098000               S0      
317GND              VIA        MD0100PA00X+010010Y+189630               S0      
317GND              VIA        MD0100PA00X+010030Y+198090               S0      
317GND              VIA        MD0100PA00X+010040Y+040600               S0      
317GND              VIA        MD0100PA00X+010050Y+162250               S0      
317GND              VIA        MD0100PA00X+010060Y+081130               S0      
317GND              VIA        MD0100PA00X+101002Y+000550               S0      
317GND              VIA        MD0100PA00X+101256Y+198663               S0      
317GND              VIA        MD0100PA00X+102000Y+010000               S0      
317GND              VIA        MD0100PA00X+102000Y+100000               S0      
317GND              VIA        MD0100PA00X+102000Y+102000               S0      
317GND              VIA        MD0100PA00X+102000Y+104000               S0      
317GND              VIA        MD0100PA00X+102000Y+106000               S0      
317GND              VIA        MD0100PA00X+102000Y+108000               S0      
317GND              VIA        MD0100PA00X+102000Y+110000               S0      
317GND              VIA        MD0100PA00X+102000Y+112000               S0      
317GND              VIA        MD0100PA00X+102000Y+114000               S0      
317GND              VIA        MD0100PA00X+102000Y+116000               S0      
317GND              VIA        MD0100PA00X+102000Y+118000               S0      
317GND              VIA        MD0100PA00X+102000Y+012000               S0      
317GND              VIA        MD0100PA00X+102000Y+120000               S0      
317GND              VIA        MD0100PA00X+102000Y+122000               S0      
317GND              VIA        MD0100PA00X+102000Y+124000               S0      
317GND              VIA        MD0100PA00X+102000Y+126000               S0      
317GND              VIA        MD0100PA00X+102000Y+128000               S0      
317GND              VIA        MD0100PA00X+102000Y+130000               S0      
317GND              VIA        MD0100PA00X+102000Y+132000               S0      
317GND              VIA        MD0100PA00X+102000Y+134000               S0      
317GND              VIA        MD0100PA00X+102000Y+136000               S0      
317GND              VIA        MD0100PA00X+102000Y+138000               S0      
317GND              VIA        MD0100PA00X+102000Y+014000               S0      
317GND              VIA        MD0100PA00X+102000Y+140000               S0      
317GND              VIA        MD0100PA00X+102000Y+016000               S0      
317GND              VIA        MD0100PA00X+102000Y+172000               S0      
317GND              VIA        MD0100PA00X+102000Y+174000               S0      
317GND              VIA        MD0100PA00X+102000Y+176000               S0      
317GND              VIA        MD0100PA00X+102000Y+178000               S0      
317GND              VIA        MD0100PA00X+102000Y+018000               S0      
317GND              VIA        MD0100PA00X+102000Y+180000               S0      
317GND              VIA        MD0100PA00X+102000Y+182000               S0      
317GND              VIA        MD0100PA00X+102000Y+184000               S0      
317GND              VIA        MD0100PA00X+102000Y+186000               S0      
317GND              VIA        MD0100PA00X+102000Y+188000               S0      
317GND              VIA        MD0100PA00X+102000Y+190000               S0      
317GND              VIA        MD0100PA00X+102000Y+192000               S0      
317GND              VIA        MD0100PA00X+102000Y+194000               S0      
317GND              VIA        MD0100PA00X+102000Y+196000               S0      
317GND              VIA        MD0100PA00X+102000Y+198000               S0      
317GND              VIA        MD0100PA00X+102000Y+002000               S0      
317GND              VIA        MD0100PA00X+102000Y+020000               S0      
317GND              VIA        MD0100PA00X+102000Y+022000               S0      
317GND              VIA        MD0100PA00X+102000Y+024000               S0      
317GND              VIA        MD0100PA00X+102000Y+026000               S0      
317GND              VIA        MD0100PA00X+102000Y+028000               S0      
317GND              VIA        MD0100PA00X+102000Y+030000               S0      
317GND              VIA        MD0100PA00X+102000Y+032000               S0      
317GND              VIA        MD0100PA00X+102000Y+034000               S0      
317GND              VIA        MD0100PA00X+102000Y+036000               S0      
317GND              VIA        MD0100PA00X+102000Y+038000               S0      
317GND              VIA        MD0100PA00X+102000Y+004000               S0      
317GND              VIA        MD0100PA00X+102000Y+040000               S0      
317GND              VIA        MD0100PA00X+102000Y+042000               S0      
317GND              VIA        MD0100PA00X+102000Y+044000               S0      
317GND              VIA        MD0100PA00X+102000Y+046000               S0      
317GND              VIA        MD0100PA00X+102000Y+048000               S0      
317GND              VIA        MD0100PA00X+102000Y+050000               S0      
317GND              VIA        MD0100PA00X+102000Y+052000               S0      
317GND              VIA        MD0100PA00X+102000Y+054000               S0      
317GND              VIA        MD0100PA00X+102000Y+056000               S0      
317GND              VIA        MD0100PA00X+102000Y+058000               S0      
317GND              VIA        MD0100PA00X+102000Y+006000               S0      
317GND              VIA        MD0100PA00X+102000Y+060000               S0      
317GND              VIA        MD0100PA00X+102000Y+062000               S0      
317GND              VIA        MD0100PA00X+102000Y+064000               S0      
317GND              VIA        MD0100PA00X+102000Y+066000               S0      
317GND              VIA        MD0100PA00X+102000Y+068000               S0      
317GND              VIA        MD0100PA00X+102000Y+070000               S0      
317GND              VIA        MD0100PA00X+102000Y+072000               S0      
317GND              VIA        MD0100PA00X+102000Y+074000               S0      
317GND              VIA        MD0100PA00X+102000Y+076000               S0      
317GND              VIA        MD0100PA00X+102000Y+078000               S0      
317GND              VIA        MD0100PA00X+102000Y+008000               S0      
317GND              VIA        MD0100PA00X+102000Y+080000               S0      
317GND              VIA        MD0100PA00X+102000Y+082000               S0      
317GND              VIA        MD0100PA00X+102000Y+084000               S0      
317GND              VIA        MD0100PA00X+102000Y+086000               S0      
317GND              VIA        MD0100PA00X+102000Y+088000               S0      
317GND              VIA        MD0100PA00X+102000Y+090000               S0      
317GND              VIA        MD0100PA00X+102000Y+092000               S0      
317GND              VIA        MD0100PA00X+102000Y+094000               S0      
317GND              VIA        MD0100PA00X+102000Y+096000               S0      
317GND              VIA        MD0100PA00X+102000Y+098000               S0      
317GND              VIA        MD0100PA00X+010240Y+105821               S0      
317GND              VIA        MD0100PA00X+010250Y+073750               S0      
317GND              VIA        MD0100PA00X+103002Y+000550               S0      
317GND              VIA        MD0100PA00X+103190Y+100362               S0      
317GND              VIA        MD0100PA00X+103190Y+102362               S0      
317GND              VIA        MD0100PA00X+103190Y+010362               S0      
317GND              VIA        MD0100PA00X+103190Y+104362               S0      
317GND              VIA        MD0100PA00X+103190Y+106362               S0      
317GND              VIA        MD0100PA00X+103190Y+108362               S0      
317GND              VIA        MD0100PA00X+103190Y+110362               S0      
317GND              VIA        MD0100PA00X+103190Y+112362               S0      
317GND              VIA        MD0100PA00X+103190Y+114362               S0      
317GND              VIA        MD0100PA00X+103190Y+116362               S0      
317GND              VIA        MD0100PA00X+103190Y+118362               S0      
317GND              VIA        MD0100PA00X+103190Y+120362               S0      
317GND              VIA        MD0100PA00X+103190Y+122362               S0      
317GND              VIA        MD0100PA00X+103190Y+012362               S0      
317GND              VIA        MD0100PA00X+103190Y+124362               S0      
317GND              VIA        MD0100PA00X+103190Y+126362               S0      
317GND              VIA        MD0100PA00X+103190Y+128362               S0      
317GND              VIA        MD0100PA00X+103190Y+130362               S0      
317GND              VIA        MD0100PA00X+103190Y+132362               S0      
317GND              VIA        MD0100PA00X+103190Y+134362               S0      
317GND              VIA        MD0100PA00X+103190Y+136362               S0      
317GND              VIA        MD0100PA00X+103190Y+138362               S0      
317GND              VIA        MD0100PA00X+103190Y+014362               S0      
317GND              VIA        MD0100PA00X+103190Y+016362               S0      
317GND              VIA        MD0100PA00X+103190Y+172597               S0      
317GND              VIA        MD0100PA00X+103190Y+174597               S0      
317GND              VIA        MD0100PA00X+103190Y+176597               S0      
317GND              VIA        MD0100PA00X+103190Y+178597               S0      
317GND              VIA        MD0100PA00X+103190Y+180597               S0      
317GND              VIA        MD0100PA00X+103190Y+182597               S0      
317GND              VIA        MD0100PA00X+103190Y+018362               S0      
317GND              VIA        MD0100PA00X+103190Y+184597               S0      
317GND              VIA        MD0100PA00X+103190Y+186597               S0      
317GND              VIA        MD0100PA00X+103190Y+188597               S0      
317GND              VIA        MD0100PA00X+103190Y+190597               S0      
317GND              VIA        MD0100PA00X+103190Y+192597               S0      
317GND              VIA        MD0100PA00X+103190Y+194597               S0      
317GND              VIA        MD0100PA00X+103190Y+196597               S0      
317GND              VIA        MD0100PA00X+103190Y+198597               S0      
317GND              VIA        MD0100PA00X+103190Y+020362               S0      
317GND              VIA        MD0100PA00X+103190Y+022362               S0      
317GND              VIA        MD0100PA00X+103190Y+002362               S0      
317GND              VIA        MD0100PA00X+103190Y+024362               S0      
317GND              VIA        MD0100PA00X+103190Y+026362               S0      
317GND              VIA        MD0100PA00X+103190Y+028362               S0      
317GND              VIA        MD0100PA00X+103190Y+030362               S0      
317GND              VIA        MD0100PA00X+103190Y+032362               S0      
317GND              VIA        MD0100PA00X+103190Y+034362               S0      
317GND              VIA        MD0100PA00X+103190Y+036362               S0      
317GND              VIA        MD0100PA00X+103190Y+038362               S0      
317GND              VIA        MD0100PA00X+103190Y+040362               S0      
317GND              VIA        MD0100PA00X+103190Y+042362               S0      
317GND              VIA        MD0100PA00X+103190Y+004362               S0      
317GND              VIA        MD0100PA00X+103190Y+044362               S0      
317GND              VIA        MD0100PA00X+103190Y+046362               S0      
317GND              VIA        MD0100PA00X+103190Y+048362               S0      
317GND              VIA        MD0100PA00X+103190Y+050362               S0      
317GND              VIA        MD0100PA00X+103190Y+052362               S0      
317GND              VIA        MD0100PA00X+103190Y+054362               S0      
317GND              VIA        MD0100PA00X+103190Y+056362               S0      
317GND              VIA        MD0100PA00X+103190Y+058362               S0      
317GND              VIA        MD0100PA00X+103190Y+060362               S0      
317GND              VIA        MD0100PA00X+103190Y+062362               S0      
317GND              VIA        MD0100PA00X+103190Y+006362               S0      
317GND              VIA        MD0100PA00X+103190Y+064362               S0      
317GND              VIA        MD0100PA00X+103190Y+066362               S0      
317GND              VIA        MD0100PA00X+103190Y+068362               S0      
317GND              VIA        MD0100PA00X+103190Y+070362               S0      
317GND              VIA        MD0100PA00X+103190Y+072362               S0      
317GND              VIA        MD0100PA00X+103190Y+074362               S0      
317GND              VIA        MD0100PA00X+103190Y+076362               S0      
317GND              VIA        MD0100PA00X+103190Y+078362               S0      
317GND              VIA        MD0100PA00X+103190Y+080362               S0      
317GND              VIA        MD0100PA00X+103190Y+082362               S0      
317GND              VIA        MD0100PA00X+103190Y+008362               S0      
317GND              VIA        MD0100PA00X+103190Y+084362               S0      
317GND              VIA        MD0100PA00X+103190Y+086362               S0      
317GND              VIA        MD0100PA00X+103190Y+088362               S0      
317GND              VIA        MD0100PA00X+103190Y+090362               S0      
317GND              VIA        MD0100PA00X+103190Y+092362               S0      
317GND              VIA        MD0100PA00X+103190Y+094362               S0      
317GND              VIA        MD0100PA00X+103190Y+096362               S0      
317GND              VIA        MD0100PA00X+103190Y+098362               S0      
317GND              VIA        MD0100PA00X+010320Y+104250               S0      
317GND              VIA        MD0100PA00X+010330Y+197410               S0      
317GND              VIA        MD0100PA00X+010400Y+012500               S0      
317GND              VIA        MD0100PA00X+010400Y+134100               S0      
317GND              VIA        MD0100PA00X+010400Y+053100               S0      
317GND              VIA        MD0100PA00X+010400Y+093600               S0      
317GND              VIA        MD0100PA00X+010440Y+040600               S0      
317GND              VIA        MD0100PA00X+010450Y+121700               S0      
317GND              VIA        MD0100PA00X+010450Y+162250               S0      
317GND              VIA        MD0100PA00X+010460Y+081130               S0      
317GND              VIA        MD0100PA00X+010570Y+154820               S0      
317GND              VIA        MD0100PA00X+010700Y+197410               S0      
317GND              VIA        MD0100PA00X+010740Y+099400               S0      
317GND              VIA        MD0100PA00X+010754Y+189802               S0      
317GND              VIA        MD0100PA00X+010790Y+040600               S0      
317GND              VIA        MD0100PA00X+010800Y+121700               S0      
317GND              VIA        MD0100PA00X+010800Y+162250               S0      
317GND              VIA        MD0100PA00X+010810Y+081130               S0      
317GND              VIA        MD0100PA00X+010892Y+015019               S0      
317GND              VIA        MD0100PA00X+010892Y+015698               S0      
317GND              VIA        MD0100PA00X+010892Y+055570               S0      
317GND              VIA        MD0100PA00X+010892Y+056249               S0      
317GND              VIA        MD0100PA00X+010900Y+129764               S0      
317GND              VIA        MD0100PA00X+010900Y+130401               S0      
317GND              VIA        MD0100PA00X+010900Y+136672               S0      
317GND              VIA        MD0100PA00X+010900Y+137351               S0      
317GND              VIA        MD0100PA00X+010900Y+170315               S0      
317GND              VIA        MD0100PA00X+010900Y+170952               S0      
317GND              VIA        MD0100PA00X+010900Y+048662               S0      
317GND              VIA        MD0100PA00X+010900Y+049299               S0      
317GND              VIA        MD0100PA00X+010900Y+008111               S0      
317GND              VIA        MD0100PA00X+010900Y+008748               S0      
317GND              VIA        MD0100PA00X+010900Y+089213               S0      
317GND              VIA        MD0100PA00X+010900Y+089850               S0      
317GND              VIA        MD0100PA00X+010900Y+096121               S0      
317GND              VIA        MD0100PA00X+010900Y+096800               S0      
317GND              VIA        MD0100PA00X+010903Y+177252               S0      
317GND              VIA        MD0100PA00X+010903Y+177874               S0      
317GND              VIA        MD0100PA00X+010904Y+006231               S0      
317GND              VIA        MD0100PA00X+010904Y+006848               S0      
317GND              VIA        MD0100PA00X+010904Y+127885               S0      
317GND              VIA        MD0100PA00X+010904Y+128501               S0      
317GND              VIA        MD0100PA00X+010904Y+168436               S0      
317GND              VIA        MD0100PA00X+010904Y+169052               S0      
317GND              VIA        MD0100PA00X+010904Y+087333               S0      
317GND              VIA        MD0100PA00X+010904Y+087950               S0      
317GND              VIA        MD0100PA00X+010904Y+046782               S0      
317GND              VIA        MD0100PA00X+010904Y+047399               S0      
317GND              VIA        MD0100PA00X+010913Y+131694               S0      
317GND              VIA        MD0100PA00X+010913Y+132251               S0      
317GND              VIA        MD0100PA00X+010914Y+172245               S0      
317GND              VIA        MD0100PA00X+010914Y+172802               S0      
317GND              VIA        MD0100PA00X+010914Y+050591               S0      
317GND              VIA        MD0100PA00X+010914Y+051149               S0      
317GND              VIA        MD0100PA00X+010916Y+010048               S0      
317GND              VIA        MD0100PA00X+010916Y+010590               S0      
317GND              VIA        MD0100PA00X+010919Y+091142               S0      
317GND              VIA        MD0100PA00X+010919Y+091700               S0      
317GND              VIA        MD0100PA00X+010950Y+148600               S0      
317GND              VIA        MD0100PA00X+011002Y+000550               S0      
317GND              VIA        MD0100PA00X+011070Y+197410               S0      
317GND              VIA        MD0100PA00X+011100Y+187957               S0      
317GND              VIA        MD0100PA00X+011150Y+114500               S0      
317GND              VIA        MD0100PA00X+011150Y+027600               S0      
317GND              VIA        MD0100PA00X+011250Y+084520               S0      
317GND              VIA        MD0100PA00X+011250Y+084870               S0      
317GND              VIA        MD0100PA00X+011256Y+198663               S0      
317GND              VIA        MD0100PA00X+011260Y+125080               S0      
317GND              VIA        MD0100PA00X+011260Y+125430               S0      
317GND              VIA        MD0100PA00X+011260Y+043900               S0      
317GND              VIA        MD0100PA00X+011260Y+044250               S0      
317GND              VIA        MD0100PA00X+011320Y+165630               S0      
317GND              VIA        MD0100PA00X+011320Y+165980               S0      
317GND              VIA        MD0100PA00X+011384Y+158090               S0      
317GND              VIA        MD0100PA00X+011400Y+147000               S0      
317GND              VIA        MD0100PA00X+011420Y+197410               S0      
317GND              VIA        MD0100PA00X+011523Y+187977               S0      
317GND              VIA        MD0100PA00X+011600Y+081450               S0      
317GND              VIA        MD0100PA00X+011650Y+150550               S0      
317GND              VIA        MD0100PA00X+011660Y+004680               S0      
317GND              VIA        MD0100PA00X+011700Y+165460               S0      
317GND              VIA        MD0100PA00X+011730Y+169650               S0      
317GND              VIA        MD0100PA00X+011769Y+139717               S0      
317GND              VIA        MD0100PA00X+011825Y+125205               S0      
317GND              VIA        MD0100PA00X+011850Y+197140               S0      
317GND              VIA        MD0100PA00X+011916Y+040510               S0      
317GND              VIA        MD0100PA00X+011953Y+121648               S0      
317GND              VIA        MD0100PA00X+011953Y+162198               S0      
317GND              VIA        MD0100PA00X+011953Y+081098               S0      
317GND              VIA        MD0100PA00X+012000Y+122000               S0      
317GND              VIA        MD0100PA00X+012000Y+128000               S0      
317GND              VIA        MD0100PA00X+012000Y+167800               S0      
317GND              VIA        MD0100PA00X+012000Y+046000               S0      
317GND              VIA        MD0100PA00X+012080Y+043800               S0      
317GND              VIA        MD0100PA00X+012132Y+142540               S0      
317GND              VIA        MD0100PA00X+012160Y+005470               S0      
317GND              VIA        MD0100PA00X+012170Y+165480               S0      
317GND              VIA        MD0100PA00X+012200Y+147000               S0      
317GND              VIA        MD0100PA00X+012225Y+084240               S0      
317GND              VIA        MD0100PA00X+012240Y+114920               S0      
317GND              VIA        MD0100PA00X+012245Y+074380               S0      
317GND              VIA        MD0100PA00X+012250Y+110700               S0      
317GND              VIA        MD0100PA00X+012300Y+170200               S0      
317GND              VIA        MD0100PA00X+012320Y+194725               S0      
317GND              VIA        MD0100PA00X+012340Y+152260               S0      
317GND              VIA        MD0100PA00X+012350Y+112350               S0      
317GND              VIA        MD0100PA00X+012350Y+150520               S0      
317GND              VIA        MD0100PA00X+012400Y+012406               S0      
317GND              VIA        MD0100PA00X+012400Y+013586               S0      
317GND              VIA        MD0100PA00X+012400Y+052957               S0      
317GND              VIA        MD0100PA00X+012400Y+054137               S0      
317GND              VIA        MD0100PA00X+012410Y+118103               S0      
317GND              VIA        MD0100PA00X+012447Y+037003               S0      
317GND              VIA        MD0100PA00X+012497Y+077553               S0      
317GND              VIA        MD0100PA00X+001256Y+198663               S0      
317GND              VIA        MD0100PA00X+012500Y+174603               S0      
317GND              VIA        MD0100PA00X+012500Y+175783               S0      
317GND              VIA        MD0100PA00X+012500Y+031200               S0      
317GND              VIA        MD0100PA00X+012550Y+026550               S0      
317GND              VIA        MD0100PA00X+012550Y+071900               S0      
317GND              VIA        MD0100PA00X+012600Y+029300               S0      
317GND              VIA        MD0100PA00X+012645Y+033830               S0      
317GND              VIA        MD0100PA00X+012692Y+144736               S0      
317GND              VIA        MD0100PA00X+012820Y+190030               S0      
317GND              VIA        MD0100PA00X+012820Y+006130               S0      
317GND              VIA        MD0100PA00X+012850Y+024800               S0      
317GND              VIA        MD0100PA00X+012880Y+185400               S0      
317GND              VIA        MD0100PA00X+012880Y+192130               S0      
317GND              VIA        MD0100PA00X+012900Y+105150               S0      
317GND              VIA        MD0100PA00X+012950Y+108450               S0      
317GND              VIA        MD0100PA00X+012950Y+134052               S0      
317GND              VIA        MD0100PA00X+012950Y+135232               S0      
317GND              VIA        MD0100PA00X+012950Y+188350               S0      
317GND              VIA        MD0100PA00X+013000Y+147000               S0      
317GND              VIA        MD0100PA00X+013050Y+194620               S0      
317GND              VIA        MD0100PA00X+013060Y+154910               S0      
317GND              VIA        MD0100PA00X+013130Y+033240               S0      
317GND              VIA        MD0100PA00X+013130Y+033590               S0      
317GND              VIA        MD0100PA00X+013140Y+073820               S0      
317GND              VIA        MD0100PA00X+013140Y+074170               S0      
317GND              VIA        MD0100PA00X+013150Y+114320               S0      
317GND              VIA        MD0100PA00X+013150Y+114670               S0      
317GND              VIA        MD0100PA00X+013150Y+061050               S0      
317GND              VIA        MD0100PA00X+013170Y+006130               S0      
317GND              VIA        MD0100PA00X+013235Y+056375               S0      
317GND              VIA        MD0100PA00X+013250Y+023600               S0      
317GND              VIA        MD0100PA00X+013256Y+198663               S0      
317GND              VIA        MD0100PA00X+013300Y+197710               S0      
317GND              VIA        MD0100PA00X+013490Y+188615               S0      
317GND              VIA        MD0100PA00X+013490Y+189165               S0      
317GND              VIA        MD0100PA00X+013490Y+190502               S0      
317GND              VIA        MD0100PA00X+013490Y+191065               S0      
317GND              VIA        MD0100PA00X+013494Y+148071               S0      
317GND              VIA        MD0100PA00X+013494Y+148614               S0      
317GND              VIA        MD0100PA00X+013494Y+107520               S0      
317GND              VIA        MD0100PA00X+013494Y+108063               S0      
317GND              VIA        MD0100PA00X+013494Y+026418               S0      
317GND              VIA        MD0100PA00X+013494Y+026960               S0      
317GND              VIA        MD0100PA00X+013494Y+066969               S0      
317GND              VIA        MD0100PA00X+013494Y+067511               S0      
317GND              VIA        MD0100PA00X+013499Y+070728               S0      
317GND              VIA        MD0100PA00X+013499Y+071311               S0      
317GND              VIA        MD0100PA00X+013500Y+151830               S0      
317GND              VIA        MD0100PA00X+013500Y+152414               S0      
317GND              VIA        MD0100PA00X+013500Y+192365               S0      
317GND              VIA        MD0100PA00X+013500Y+192965               S0      
317GND              VIA        MD0100PA00X+013500Y+030177               S0      
317GND              VIA        MD0100PA00X+013500Y+030760               S0      
317GND              VIA        MD0100PA00X+013500Y+111279               S0      
317GND              VIA        MD0100PA00X+013500Y+111863               S0      
317GND              VIA        MD0100PA00X+013506Y+021339               S0      
317GND              VIA        MD0100PA00X+013506Y+021960               S0      
317GND              VIA        MD0100PA00X+013506Y+183544               S0      
317GND              VIA        MD0100PA00X+013506Y+184165               S0      
317GND              VIA        MD0100PA00X+013510Y+102413               S0      
317GND              VIA        MD0100PA00X+013510Y+103091               S0      
317GND              VIA        MD0100PA00X+013510Y+109363               S0      
317GND              VIA        MD0100PA00X+013510Y+110000               S0      
317GND              VIA        MD0100PA00X+013510Y+142964               S0      
317GND              VIA        MD0100PA00X+013510Y+143643               S0      
317GND              VIA        MD0100PA00X+013510Y+149914               S0      
317GND              VIA        MD0100PA00X+013510Y+150551               S0      
317GND              VIA        MD0100PA00X+013510Y+028260               S0      
317GND              VIA        MD0100PA00X+013510Y+028897               S0      
317GND              VIA        MD0100PA00X+013510Y+061861               S0      
317GND              VIA        MD0100PA00X+013510Y+062540               S0      
317GND              VIA        MD0100PA00X+013510Y+068811               S0      
317GND              VIA        MD0100PA00X+013510Y+069448               S0      
317GND              VIA        MD0100PA00X+013530Y+158510               S0      
317GND              VIA        MD0100PA00X+013550Y+020050               S0      
317GND              VIA        MD0100PA00X+013600Y+118040               S0      
317GND              VIA        MD0100PA00X+013600Y+037000               S0      
317GND              VIA        MD0100PA00X+013610Y+077560               S0      
317GND              VIA        MD0100PA00X+013650Y+181150               S0      
317GND              VIA        MD0100PA00X+013660Y+168190               S0      
317GND              VIA        MD0100PA00X+013670Y+172010               S0      
317GND              VIA        MD0100PA00X+013700Y+166650               S0      
317GND              VIA        MD0100PA00X+013820Y+006490               S0      
317GND              VIA        MD0100PA00X+013880Y+158510               S0      
317GND              VIA        MD0100PA00X+013910Y+197710               S0      
317GND              VIA        MD0100PA00X+013950Y+118040               S0      
317GND              VIA        MD0100PA00X+013950Y+037000               S0      
317GND              VIA        MD0100PA00X+013950Y+060040               S0      
317GND              VIA        MD0100PA00X+013960Y+077560               S0      
317GND              VIA        MD0100PA00X+014000Y+105950               S0      
317GND              VIA        MD0100PA00X+014000Y+128000               S0      
317GND              VIA        MD0100PA00X+014000Y+130000               S0      
317GND              VIA        MD0100PA00X+014000Y+134000               S0      
317GND              VIA        MD0100PA00X+014000Y+146400               S0      
317GND              VIA        MD0100PA00X+014000Y+182000               S0      
317GND              VIA        MD0100PA00X+014000Y+187000               S0      
317GND              VIA        MD0100PA00X+014000Y+024750               S0      
317GND              VIA        MD0100PA00X+014000Y+044000               S0      
317GND              VIA        MD0100PA00X+014000Y+046000               S0      
317GND              VIA        MD0100PA00X+014000Y+048000               S0      
317GND              VIA        MD0100PA00X+014000Y+065400               S0      
317GND              VIA        MD0100PA00X+014000Y+008000               S0      
317GND              VIA        MD0100PA00X+014000Y+090000               S0      
317GND              VIA        MD0100PA00X+014170Y+006490               S0      
317GND              VIA        MD0100PA00X+014300Y+165600               S0      
317GND              VIA        MD0100PA00X+014309Y+140362               S0      
317GND              VIA        MD0100PA00X+014330Y+158690               S0      
317GND              VIA        MD0100PA00X+014350Y+118040               S0      
317GND              VIA        MD0100PA00X+014350Y+162550               S0      
317GND              VIA        MD0100PA00X+014350Y+037000               S0      
317GND              VIA        MD0100PA00X+014360Y+077560               S0      
317GND              VIA        MD0100PA00X+014420Y+154550               S0      
317GND              VIA        MD0100PA00X+014550Y+180750               S0      
317GND              VIA        MD0100PA00X+014580Y+033240               S0      
317GND              VIA        MD0100PA00X+014580Y+073710               S0      
317GND              VIA        MD0100PA00X+014590Y+040850               S0      
317GND              VIA        MD0100PA00X+014670Y+121960               S0      
317GND              VIA        MD0100PA00X+014680Y+158690               S0      
317GND              VIA        MD0100PA00X+014700Y+118040               S0      
317GND              VIA        MD0100PA00X+014700Y+037000               S0      
317GND              VIA        MD0100PA00X+014710Y+077560               S0      
317GND              VIA        MD0100PA00X+014710Y+081420               S0      
317GND              VIA        MD0100PA00X+014713Y+016050               S0      
317GND              VIA        MD0100PA00X+014770Y+154550               S0      
317GND              VIA        MD0100PA00X+014780Y+114000               S0      
317GND              VIA        MD0100PA00X+014800Y+178700               S0      
317GND              VIA        MD0100PA00X+014810Y+102280               S0      
317GND              VIA        MD0100PA00X+014810Y+103224               S0      
317GND              VIA        MD0100PA00X+014810Y+104169               S0      
317GND              VIA        MD0100PA00X+014810Y+104799               S0      
317GND              VIA        MD0100PA00X+014810Y+105744               S0      
317GND              VIA        MD0100PA00X+014810Y+106689               S0      
317GND              VIA        MD0100PA00X+014810Y+107319               S0      
317GND              VIA        MD0100PA00X+014810Y+108264               S0      
317GND              VIA        MD0100PA00X+014810Y+109209               S0      
317GND              VIA        MD0100PA00X+014810Y+110154               S0      
317GND              VIA        MD0100PA00X+014810Y+111098               S0      
317GND              VIA        MD0100PA00X+014810Y+112043               S0      
317GND              VIA        MD0100PA00X+014810Y+112988               S0      
317GND              VIA        MD0100PA00X+014810Y+142831               S0      
317GND              VIA        MD0100PA00X+014810Y+143776               S0      
317GND              VIA        MD0100PA00X+014810Y+144721               S0      
317GND              VIA        MD0100PA00X+014810Y+145350               S0      
317GND              VIA        MD0100PA00X+014810Y+146295               S0      
317GND              VIA        MD0100PA00X+014810Y+147240               S0      
317GND              VIA        MD0100PA00X+014810Y+147870               S0      
317GND              VIA        MD0100PA00X+014810Y+148815               S0      
317GND              VIA        MD0100PA00X+014810Y+149760               S0      
317GND              VIA        MD0100PA00X+014810Y+150705               S0      
317GND              VIA        MD0100PA00X+014810Y+151650               S0      
317GND              VIA        MD0100PA00X+014810Y+152595               S0      
317GND              VIA        MD0100PA00X+014810Y+153539               S0      
317GND              VIA        MD0100PA00X+014810Y+183382               S0      
317GND              VIA        MD0100PA00X+014810Y+184327               S0      
317GND              VIA        MD0100PA00X+014810Y+185272               S0      
317GND              VIA        MD0100PA00X+014810Y+185902               S0      
317GND              VIA        MD0100PA00X+014810Y+186846               S0      
317GND              VIA        MD0100PA00X+014810Y+187791               S0      
317GND              VIA        MD0100PA00X+014810Y+188421               S0      
317GND              VIA        MD0100PA00X+014810Y+189366               S0      
317GND              VIA        MD0100PA00X+014810Y+190311               S0      
317GND              VIA        MD0100PA00X+014810Y+191256               S0      
317GND              VIA        MD0100PA00X+014810Y+192201               S0      
317GND              VIA        MD0100PA00X+014810Y+193146               S0      
317GND              VIA        MD0100PA00X+014810Y+194091               S0      
317GND              VIA        MD0100PA00X+014810Y+021177               S0      
317GND              VIA        MD0100PA00X+014810Y+022122               S0      
317GND              VIA        MD0100PA00X+014810Y+023067               S0      
317GND              VIA        MD0100PA00X+014810Y+023697               S0      
317GND              VIA        MD0100PA00X+014810Y+024642               S0      
317GND              VIA        MD0100PA00X+014810Y+025587               S0      
317GND              VIA        MD0100PA00X+014810Y+026216               S0      
317GND              VIA        MD0100PA00X+014810Y+027161               S0      
317GND              VIA        MD0100PA00X+014810Y+028106               S0      
317GND              VIA        MD0100PA00X+014810Y+029051               S0      
317GND              VIA        MD0100PA00X+014810Y+029996               S0      
317GND              VIA        MD0100PA00X+014810Y+030941               S0      
317GND              VIA        MD0100PA00X+014810Y+031886               S0      
317GND              VIA        MD0100PA00X+014810Y+061728               S0      
317GND              VIA        MD0100PA00X+014810Y+062673               S0      
317GND              VIA        MD0100PA00X+014810Y+063618               S0      
317GND              VIA        MD0100PA00X+014810Y+064248               S0      
317GND              VIA        MD0100PA00X+014810Y+065193               S0      
317GND              VIA        MD0100PA00X+014810Y+066138               S0      
317GND              VIA        MD0100PA00X+014810Y+066768               S0      
317GND              VIA        MD0100PA00X+014810Y+067713               S0      
317GND              VIA        MD0100PA00X+014810Y+068658               S0      
317GND              VIA        MD0100PA00X+014810Y+069602               S0      
317GND              VIA        MD0100PA00X+014810Y+070547               S0      
317GND              VIA        MD0100PA00X+014810Y+071492               S0      
317GND              VIA        MD0100PA00X+014810Y+072437               S0      
317GND              VIA        MD0100PA00X+014860Y+081870               S0      
317GND              VIA        MD0100PA00X+014870Y+041340               S0      
317GND              VIA        MD0100PA00X+015020Y+006500               S0      
317GND              VIA        MD0100PA00X+015113Y+137661               S0      
317GND              VIA        MD0100PA00X+015256Y+198663               S0      
317GND              VIA        MD0100PA00X+015370Y+163360               S0      
317GND              VIA        MD0100PA00X+015470Y+006500               S0      
317GND              VIA        MD0100PA00X+015502Y+000550               S0      
317GND              VIA        MD0100PA00X+015733Y+122385               S0      
317GND              VIA        MD0100PA00X+015750Y+055120               S0      
317GND              VIA        MD0100PA00X+015830Y+013520               S0      
317GND              VIA        MD0100PA00X+015850Y+056950               S0      
317GND              VIA        MD0100PA00X+015980Y+173000               S0      
317GND              VIA        MD0100PA00X+001600Y+093100               S0      
317GND              VIA        MD0100PA00X+016000Y+128000               S0      
317GND              VIA        MD0100PA00X+016000Y+130000               S0      
317GND              VIA        MD0100PA00X+016000Y+134000               S0      
317GND              VIA        MD0100PA00X+016000Y+136000               S0      
317GND              VIA        MD0100PA00X+016000Y+170000               S0      
317GND              VIA        MD0100PA00X+016000Y+172000               S0      
317GND              VIA        MD0100PA00X+016000Y+180000               S0      
317GND              VIA        MD0100PA00X+016000Y+044000               S0      
317GND              VIA        MD0100PA00X+016000Y+052000               S0      
317GND              VIA        MD0100PA00X+016000Y+008000               S0      
317GND              VIA        MD0100PA00X+016000Y+088000               S0      
317GND              VIA        MD0100PA00X+016020Y+171030               S0      
317GND              VIA        MD0100PA00X+016350Y+042300               S0      
317GND              VIA        MD0100PA00X+001642Y+131158               S0      
317GND              VIA        MD0100PA00X+001650Y+109426               S0      
317GND              VIA        MD0100PA00X+001650Y+110223               S0      
317GND              VIA        MD0100PA00X+001650Y+110823               S0      
317GND              VIA        MD0100PA00X+001650Y+111483               S0      
317GND              VIA        MD0100PA00X+001650Y+112083               S0      
317GND              VIA        MD0100PA00X+001650Y+113350               S0      
317GND              VIA        MD0100PA00X+001650Y+114002               S0      
317GND              VIA        MD0100PA00X+001650Y+114602               S0      
317GND              VIA        MD0100PA00X+001650Y+115262               S0      
317GND              VIA        MD0100PA00X+001650Y+115862               S0      
317GND              VIA        MD0100PA00X+001650Y+116522               S0      
317GND              VIA        MD0100PA00X+001650Y+117122               S0      
317GND              VIA        MD0100PA00X+001650Y+117782               S0      
317GND              VIA        MD0100PA00X+001650Y+118382               S0      
317GND              VIA        MD0100PA00X+001650Y+119042               S0      
317GND              VIA        MD0100PA00X+001650Y+119642               S0      
317GND              VIA        MD0100PA00X+001650Y+120302               S0      
317GND              VIA        MD0100PA00X+001650Y+120902               S0      
317GND              VIA        MD0100PA00X+001650Y+121562               S0      
317GND              VIA        MD0100PA00X+001650Y+122162               S0      
317GND              VIA        MD0100PA00X+001650Y+122850               S0      
317GND              VIA        MD0100PA00X+001650Y+124772               S0      
317GND              VIA        MD0100PA00X+001650Y+125311               S0      
317GND              VIA        MD0100PA00X+001650Y+125971               S0      
317GND              VIA        MD0100PA00X+001650Y+126571               S0      
317GND              VIA        MD0100PA00X+001650Y+127231               S0      
317GND              VIA        MD0100PA00X+001650Y+127831               S0      
317GND              VIA        MD0100PA00X+001650Y+128491               S0      
317GND              VIA        MD0100PA00X+001650Y+129091               S0      
317GND              VIA        MD0100PA00X+001650Y+129751               S0      
317GND              VIA        MD0100PA00X+001650Y+130351               S0      
317GND              VIA        MD0100PA00X+001650Y+131955               S0      
317GND              VIA        MD0100PA00X+001650Y+132555               S0      
317GND              VIA        MD0100PA00X+001650Y+133215               S0      
317GND              VIA        MD0100PA00X+001650Y+133815               S0      
317GND              VIA        MD0100PA00X+001650Y+134475               S0      
317GND              VIA        MD0100PA00X+001650Y+135075               S0      
317GND              VIA        MD0100PA00X+001650Y+135735               S0      
317GND              VIA        MD0100PA00X+001650Y+136335               S0      
317GND              VIA        MD0100PA00X+001650Y+136995               S0      
317GND              VIA        MD0100PA00X+001650Y+137595               S0      
317GND              VIA        MD0100PA00X+001650Y+138254               S0      
317GND              VIA        MD0100PA00X+001650Y+138854               S0      
317GND              VIA        MD0100PA00X+001650Y+139514               S0      
317GND              VIA        MD0100PA00X+001650Y+140114               S0      
317GND              VIA        MD0100PA00X+001650Y+140774               S0      
317GND              VIA        MD0100PA00X+001650Y+141374               S0      
317GND              VIA        MD0100PA00X+001650Y+151250               S0      
317GND              VIA        MD0100PA00X+001650Y+152103               S0      
317GND              VIA        MD0100PA00X+001650Y+152900               S0      
317GND              VIA        MD0100PA00X+001650Y+153500               S0      
317GND              VIA        MD0100PA00X+001650Y+154150               S0      
317GND              VIA        MD0100PA00X+001650Y+154800               S0      
317GND              VIA        MD0100PA00X+001650Y+155400               S0      
317GND              VIA        MD0100PA00X+001650Y+156050               S0      
317GND              VIA        MD0100PA00X+001650Y+156650               S0      
317GND              VIA        MD0100PA00X+001650Y+157300               S0      
317GND              VIA        MD0100PA00X+001650Y+158250               S0      
317GND              VIA        MD0100PA00X+001650Y+158850               S0      
317GND              VIA        MD0100PA00X+001650Y+159500               S0      
317GND              VIA        MD0100PA00X+001650Y+160150               S0      
317GND              VIA        MD0100PA00X+001650Y+160750               S0      
317GND              VIA        MD0100PA00X+001650Y+161400               S0      
317GND              VIA        MD0100PA00X+001650Y+162000               S0      
317GND              VIA        MD0100PA00X+001650Y+162650               S0      
317GND              VIA        MD0100PA00X+001650Y+163300               S0      
317GND              VIA        MD0100PA00X+001650Y+163985               S0      
317GND              VIA        MD0100PA00X+001650Y+164474               S0      
317GND              VIA        MD0100PA00X+001650Y+166504               S0      
317GND              VIA        MD0100PA00X+001650Y+166993               S0      
317GND              VIA        MD0100PA00X+001650Y+167700               S0      
317GND              VIA        MD0100PA00X+001650Y+168317               S0      
317GND              VIA        MD0100PA00X+001650Y+168950               S0      
317GND              VIA        MD0100PA00X+001650Y+169600               S0      
317GND              VIA        MD0100PA00X+001650Y+170250               S0      
317GND              VIA        MD0100PA00X+001650Y+171200               S0      
317GND              VIA        MD0100PA00X+001650Y+171746               S0      
317GND              VIA        MD0100PA00X+001650Y+172400               S0      
317GND              VIA        MD0100PA00X+001650Y+173066               S0      
317GND              VIA        MD0100PA00X+001650Y+173650               S0      
317GND              VIA        MD0100PA00X+001650Y+174336               S0      
317GND              VIA        MD0100PA00X+001650Y+174900               S0      
317GND              VIA        MD0100PA00X+001650Y+175605               S0      
317GND              VIA        MD0100PA00X+001650Y+176500               S0      
317GND              VIA        MD0100PA00X+001650Y+177450               S0      
317GND              VIA        MD0100PA00X+001650Y+178400               S0      
317GND              VIA        MD0100PA00X+001650Y+179050               S0      
317GND              VIA        MD0100PA00X+001650Y+059820               S0      
317GND              VIA        MD0100PA00X+001650Y+060617               S0      
317GND              VIA        MD0100PA00X+001650Y+061217               S0      
317GND              VIA        MD0100PA00X+001650Y+061877               S0      
317GND              VIA        MD0100PA00X+001650Y+062477               S0      
317GND              VIA        MD0100PA00X+001650Y+063136               S0      
317GND              VIA        MD0100PA00X+001650Y+063736               S0      
317GND              VIA        MD0100PA00X+001650Y+064453               S0      
317GND              VIA        MD0100PA00X+001650Y+064950               S0      
317GND              VIA        MD0100PA00X+001650Y+065700               S0      
317GND              VIA        MD0100PA00X+001650Y+066223               S0      
317GND              VIA        MD0100PA00X+001650Y+066916               S0      
317GND              VIA        MD0100PA00X+001650Y+067516               S0      
317GND              VIA        MD0100PA00X+001650Y+068176               S0      
317GND              VIA        MD0100PA00X+001650Y+068776               S0      
317GND              VIA        MD0100PA00X+001650Y+069435               S0      
317GND              VIA        MD0100PA00X+001650Y+070036               S0      
317GND              VIA        MD0100PA00X+001650Y+070695               S0      
317GND              VIA        MD0100PA00X+001650Y+071295               S0      
317GND              VIA        MD0100PA00X+001650Y+071955               S0      
317GND              VIA        MD0100PA00X+001650Y+072555               S0      
317GND              VIA        MD0100PA00X+001650Y+073250               S0      
317GND              VIA        MD0100PA00X+001650Y+075166               S0      
317GND              VIA        MD0100PA00X+001650Y+075705               S0      
317GND              VIA        MD0100PA00X+001650Y+076365               S0      
317GND              VIA        MD0100PA00X+001650Y+076965               S0      
317GND              VIA        MD0100PA00X+001650Y+077773               S0      
317GND              VIA        MD0100PA00X+001650Y+078569               S0      
317GND              VIA        MD0100PA00X+001650Y+079169               S0      
317GND              VIA        MD0100PA00X+001650Y+079829               S0      
317GND              VIA        MD0100PA00X+001650Y+080429               S0      
317GND              VIA        MD0100PA00X+001650Y+081089               S0      
317GND              VIA        MD0100PA00X+001650Y+081689               S0      
317GND              VIA        MD0100PA00X+001650Y+082349               S0      
317GND              VIA        MD0100PA00X+001650Y+082949               S0      
317GND              VIA        MD0100PA00X+001650Y+083609               S0      
317GND              VIA        MD0100PA00X+001650Y+084209               S0      
317GND              VIA        MD0100PA00X+001650Y+084869               S0      
317GND              VIA        MD0100PA00X+001650Y+085469               S0      
317GND              VIA        MD0100PA00X+001650Y+086128               S0      
317GND              VIA        MD0100PA00X+001650Y+086728               S0      
317GND              VIA        MD0100PA00X+001650Y+087388               S0      
317GND              VIA        MD0100PA00X+001650Y+087988               S0      
317GND              VIA        MD0100PA00X+001650Y+088950               S0      
317GND              VIA        MD0100PA00X+001650Y+089908               S0      
317GND              VIA        MD0100PA00X+001650Y+090508               S0      
317GND              VIA        MD0100PA00X+001650Y+091168               S0      
317GND              VIA        MD0100PA00X+001650Y+091768               S0      
317GND              VIA        MD0100PA00X+016514Y+053650               S0      
317GND              VIA        MD0100PA00X+016700Y+093591               S0      
317GND              VIA        MD0100PA00X+016700Y+094591               S0      
317GND              VIA        MD0100PA00X+017002Y+000550               S0      
317GND              VIA        MD0100PA00X+017003Y+003148               S0      
317GND              VIA        MD0100PA00X+017150Y+161350               S0      
317GND              VIA        MD0100PA00X+017160Y+101494               S0      
317GND              VIA        MD0100PA00X+017160Y+102994               S0      
317GND              VIA        MD0100PA00X+017160Y+104494               S0      
317GND              VIA        MD0100PA00X+017160Y+108994               S0      
317GND              VIA        MD0100PA00X+017160Y+109494               S0      
317GND              VIA        MD0100PA00X+017160Y+142045               S0      
317GND              VIA        MD0100PA00X+017160Y+143545               S0      
317GND              VIA        MD0100PA00X+017160Y+149545               S0      
317GND              VIA        MD0100PA00X+017160Y+150045               S0      
317GND              VIA        MD0100PA00X+017160Y+182597               S0      
317GND              VIA        MD0100PA00X+017160Y+184097               S0      
317GND              VIA        MD0100PA00X+017160Y+185596               S0      
317GND              VIA        MD0100PA00X+017160Y+190097               S0      
317GND              VIA        MD0100PA00X+017160Y+190596               S0      
317GND              VIA        MD0100PA00X+017160Y+020392               S0      
317GND              VIA        MD0100PA00X+017160Y+021892               S0      
317GND              VIA        MD0100PA00X+017160Y+023392               S0      
317GND              VIA        MD0100PA00X+017160Y+027892               S0      
317GND              VIA        MD0100PA00X+017160Y+028392               S0      
317GND              VIA        MD0100PA00X+017160Y+060943               S0      
317GND              VIA        MD0100PA00X+017160Y+062443               S0      
317GND              VIA        MD0100PA00X+017160Y+068443               S0      
317GND              VIA        MD0100PA00X+017160Y+068943               S0      
317GND              VIA        MD0100PA00X+017190Y+145045               S0      
317GND              VIA        MD0100PA00X+017190Y+063943               S0      
317GND              VIA        MD0100PA00X+017200Y+159500               S0      
317GND              VIA        MD0100PA00X+017256Y+198663               S0      
317GND              VIA        MD0100PA00X+017300Y+112350               S0      
317GND              VIA        MD0100PA00X+017300Y+152900               S0      
317GND              VIA        MD0100PA00X+017300Y+193450               S0      
317GND              VIA        MD0100PA00X+017300Y+031250               S0      
317GND              VIA        MD0100PA00X+017300Y+071800               S0      
317GND              VIA        MD0100PA00X+017400Y+055350               S0      
317GND              VIA        MD0100PA00X+017649Y+104213               S0      
317GND              VIA        MD0100PA00X+017649Y+144763               S0      
317GND              VIA        MD0100PA00X+017649Y+185315               S0      
317GND              VIA        MD0100PA00X+017649Y+023110               S0      
317GND              VIA        MD0100PA00X+017649Y+063662               S0      
317GND              VIA        MD0100PA00X+017915Y+135305               S0      
317GND              VIA        MD0100PA00X+017915Y+013791               S0      
317GND              VIA        MD0100PA00X+018000Y+100000               S0      
317GND              VIA        MD0100PA00X+018000Y+108000               S0      
317GND              VIA        MD0100PA00X+018000Y+110000               S0      
317GND              VIA        MD0100PA00X+018000Y+112000               S0      
317GND              VIA        MD0100PA00X+018000Y+114000               S0      
317GND              VIA        MD0100PA00X+018000Y+122000               S0      
317GND              VIA        MD0100PA00X+018000Y+128000               S0      
317GND              VIA        MD0100PA00X+018000Y+130000               S0      
317GND              VIA        MD0100PA00X+018000Y+134000               S0      
317GND              VIA        MD0100PA00X+018000Y+140000               S0      
317GND              VIA        MD0100PA00X+018000Y+142000               S0      
317GND              VIA        MD0100PA00X+018000Y+144000               S0      
317GND              VIA        MD0100PA00X+018000Y+150000               S0      
317GND              VIA        MD0100PA00X+018000Y+152000               S0      
317GND              VIA        MD0100PA00X+018000Y+168000               S0      
317GND              VIA        MD0100PA00X+018000Y+170000               S0      
317GND              VIA        MD0100PA00X+018000Y+018000               S0      
317GND              VIA        MD0100PA00X+018000Y+180000               S0      
317GND              VIA        MD0100PA00X+018000Y+184000               S0      
317GND              VIA        MD0100PA00X+018000Y+188000               S0      
317GND              VIA        MD0100PA00X+018000Y+190000               S0      
317GND              VIA        MD0100PA00X+018000Y+194000               S0      
317GND              VIA        MD0100PA00X+018000Y+046000               S0      
317GND              VIA        MD0100PA00X+018000Y+048000               S0      
317GND              VIA        MD0100PA00X+018000Y+052000               S0      
317GND              VIA        MD0100PA00X+018000Y+058000               S0      
317GND              VIA        MD0100PA00X+018000Y+060000               S0      
317GND              VIA        MD0100PA00X+018000Y+062000               S0      
317GND              VIA        MD0100PA00X+018000Y+072000               S0      
317GND              VIA        MD0100PA00X+018000Y+008000               S0      
317GND              VIA        MD0100PA00X+018000Y+098000               S0      
317GND              VIA        MD0100PA00X+018010Y+023110               S0      
317GND              VIA        MD0100PA00X+018031Y+104213               S0      
317GND              VIA        MD0100PA00X+018031Y+144763               S0      
317GND              VIA        MD0100PA00X+018031Y+185315               S0      
317GND              VIA        MD0100PA00X+018031Y+063662               S0      
317GND              VIA        MD0100PA00X+018150Y+164150               S0      
317GND              VIA        MD0100PA00X+018200Y+094900               S0      
317GND              VIA        MD0100PA00X+018250Y+162250               S0      
317GND              VIA        MD0100PA00X+018930Y+157720               S0      
317GND              VIA        MD0100PA00X+019002Y+000550               S0      
317GND              VIA        MD0100PA00X+019040Y+145074               S0      
317GND              VIA        MD0100PA00X+019040Y+146254               S0      
317GND              VIA        MD0100PA00X+019050Y+063971               S0      
317GND              VIA        MD0100PA00X+019050Y+065151               S0      
317GND              VIA        MD0100PA00X+019060Y+104523               S0      
317GND              VIA        MD0100PA00X+019060Y+105702               S0      
317GND              VIA        MD0100PA00X+019135Y+177294               S0      
317GND              VIA        MD0100PA00X+019256Y+198663               S0      
317GND              VIA        MD0100PA00X+019420Y+098590               S0      
317GND              VIA        MD0100PA00X+019450Y+023690               S0      
317GND              VIA        MD0100PA00X+019450Y+024330               S0      
317GND              VIA        MD0100PA00X+019462Y+185930               S0      
317GND              VIA        MD0100PA00X+019462Y+186500               S0      
317GND              VIA        MD0100PA00X+019550Y+053125               S0      
317GND              VIA        MD0100PA00X+019550Y+053875               S0      
317GND              VIA        MD0100PA00X+019550Y+054625               S0      
317GND              VIA        MD0100PA00X+019550Y+094975               S0      
317GND              VIA        MD0100PA00X+019667Y+003559               S0      
317GND              VIA        MD0100PA00X+001997Y+194397               S0      
317GND              VIA        MD0100PA00X+002000Y+010000               S0      
317GND              VIA        MD0100PA00X+002000Y+012000               S0      
317GND              VIA        MD0100PA00X+002000Y+014000               S0      
317GND              VIA        MD0100PA00X+002000Y+016000               S0      
317GND              VIA        MD0100PA00X+002000Y+018000               S0      
317GND              VIA        MD0100PA00X+002000Y+196000               S0      
317GND              VIA        MD0100PA00X+002000Y+198000               S0      
317GND              VIA        MD0100PA00X+002000Y+002000               S0      
317GND              VIA        MD0100PA00X+002000Y+020000               S0      
317GND              VIA        MD0100PA00X+002000Y+022000               S0      
317GND              VIA        MD0100PA00X+002000Y+024000               S0      
317GND              VIA        MD0100PA00X+002000Y+034000               S0      
317GND              VIA        MD0100PA00X+002000Y+038000               S0      
317GND              VIA        MD0100PA00X+002000Y+004000               S0      
317GND              VIA        MD0100PA00X+002000Y+040000               S0      
317GND              VIA        MD0100PA00X+002000Y+042000               S0      
317GND              VIA        MD0100PA00X+002000Y+044000               S0      
317GND              VIA        MD0100PA00X+002000Y+046000               S0      
317GND              VIA        MD0100PA00X+002000Y+048000               S0      
317GND              VIA        MD0100PA00X+002000Y+050000               S0      
317GND              VIA        MD0100PA00X+002000Y+052000               S0      
317GND              VIA        MD0100PA00X+002000Y+054000               S0      
317GND              VIA        MD0100PA00X+002000Y+006000               S0      
317GND              VIA        MD0100PA00X+002000Y+008000               S0      
317GND              VIA        MD0100PA00X+002000Y+094000               S0      
317GND              VIA        MD0100PA00X+002000Y+096000               S0      
317GND              VIA        MD0100PA00X+002000Y+098000               S0      
317GND              VIA        MD0100PA00X+020000Y+108000               S0      
317GND              VIA        MD0100PA00X+020000Y+110000               S0      
317GND              VIA        MD0100PA00X+020000Y+112000               S0      
317GND              VIA        MD0100PA00X+020000Y+114000               S0      
317GND              VIA        MD0100PA00X+020000Y+116000               S0      
317GND              VIA        MD0100PA00X+020000Y+120000               S0      
317GND              VIA        MD0100PA00X+020000Y+128000               S0      
317GND              VIA        MD0100PA00X+020000Y+130000               S0      
317GND              VIA        MD0100PA00X+020000Y+134000               S0      
317GND              VIA        MD0100PA00X+020000Y+144000               S0      
317GND              VIA        MD0100PA00X+020000Y+146000               S0      
317GND              VIA        MD0100PA00X+020000Y+148000               S0      
317GND              VIA        MD0100PA00X+020000Y+150000               S0      
317GND              VIA        MD0100PA00X+020000Y+152000               S0      
317GND              VIA        MD0100PA00X+020000Y+156000               S0      
317GND              VIA        MD0100PA00X+020000Y+166000               S0      
317GND              VIA        MD0100PA00X+020000Y+168000               S0      
317GND              VIA        MD0100PA00X+020000Y+018000               S0      
317GND              VIA        MD0100PA00X+020000Y+180000               S0      
317GND              VIA        MD0100PA00X+020000Y+188000               S0      
317GND              VIA        MD0100PA00X+020000Y+190000               S0      
317GND              VIA        MD0100PA00X+020000Y+192000               S0      
317GND              VIA        MD0100PA00X+020000Y+194000               S0      
317GND              VIA        MD0100PA00X+020000Y+196000               S0      
317GND              VIA        MD0100PA00X+020000Y+198000               S0      
317GND              VIA        MD0100PA00X+020000Y+020000               S0      
317GND              VIA        MD0100PA00X+020000Y+026000               S0      
317GND              VIA        MD0100PA00X+020000Y+028000               S0      
317GND              VIA        MD0100PA00X+020000Y+030000               S0      
317GND              VIA        MD0100PA00X+020000Y+032000               S0      
317GND              VIA        MD0100PA00X+020000Y+034000               S0      
317GND              VIA        MD0100PA00X+020000Y+036000               S0      
317GND              VIA        MD0100PA00X+020000Y+042000               S0      
317GND              VIA        MD0100PA00X+020000Y+044000               S0      
317GND              VIA        MD0100PA00X+020000Y+046000               S0      
317GND              VIA        MD0100PA00X+020000Y+048000               S0      
317GND              VIA        MD0100PA00X+020000Y+052000               S0      
317GND              VIA        MD0100PA00X+020000Y+058000               S0      
317GND              VIA        MD0100PA00X+020000Y+066000               S0      
317GND              VIA        MD0100PA00X+020000Y+068000               S0      
317GND              VIA        MD0100PA00X+020000Y+070000               S0      
317GND              VIA        MD0100PA00X+020000Y+072000               S0      
317GND              VIA        MD0100PA00X+020000Y+074000               S0      
317GND              VIA        MD0100PA00X+020000Y+076000               S0      
317GND              VIA        MD0100PA00X+020000Y+008000               S0      
317GND              VIA        MD0100PA00X+020000Y+090000               S0      
317GND              VIA        MD0100PA00X+020113Y+095720               S0      
317GND              VIA        MD0100PA00X+020200Y+153400               S0      
317GND              VIA        MD0100PA00X+020350Y+161850               S0      
317GND              VIA        MD0100PA00X+020563Y+003875               S0      
317GND              VIA        MD0100PA00X+020600Y+173500               S0      
317GND              VIA        MD0100PA00X+020760Y+177750               S0      
317GND              VIA        MD0100PA00X+020850Y+119000               S0      
317GND              VIA        MD0100PA00X+002100Y+142450               S0      
317GND              VIA        MD0100PA00X+021002Y+000550               S0      
317GND              VIA        MD0100PA00X+021256Y+198663               S0      
317GND              VIA        MD0100PA00X+021500Y+136800               S0      
317GND              VIA        MD0100PA00X+002200Y+148700               S0      
317GND              VIA        MD0100PA00X+022000Y+102000               S0      
317GND              VIA        MD0100PA00X+022000Y+104000               S0      
317GND              VIA        MD0100PA00X+022000Y+106000               S0      
317GND              VIA        MD0100PA00X+022000Y+108000               S0      
317GND              VIA        MD0100PA00X+022000Y+110000               S0      
317GND              VIA        MD0100PA00X+022000Y+112000               S0      
317GND              VIA        MD0100PA00X+022000Y+114000               S0      
317GND              VIA        MD0100PA00X+022000Y+122000               S0      
317GND              VIA        MD0100PA00X+022000Y+128000               S0      
317GND              VIA        MD0100PA00X+022000Y+130000               S0      
317GND              VIA        MD0100PA00X+022000Y+134000               S0      
317GND              VIA        MD0100PA00X+022000Y+014000               S0      
317GND              VIA        MD0100PA00X+022000Y+152000               S0      
317GND              VIA        MD0100PA00X+022000Y+156000               S0      
317GND              VIA        MD0100PA00X+022000Y+158000               S0      
317GND              VIA        MD0100PA00X+022000Y+016000               S0      
317GND              VIA        MD0100PA00X+022000Y+166000               S0      
317GND              VIA        MD0100PA00X+022000Y+168000               S0      
317GND              VIA        MD0100PA00X+022000Y+172000               S0      
317GND              VIA        MD0100PA00X+022000Y+173450               S0      
317GND              VIA        MD0100PA00X+022000Y+018000               S0      
317GND              VIA        MD0100PA00X+022000Y+180000               S0      
317GND              VIA        MD0100PA00X+022000Y+184000               S0      
317GND              VIA        MD0100PA00X+022000Y+190000               S0      
317GND              VIA        MD0100PA00X+022000Y+192000               S0      
317GND              VIA        MD0100PA00X+022000Y+194000               S0      
317GND              VIA        MD0100PA00X+022000Y+196000               S0      
317GND              VIA        MD0100PA00X+022000Y+198000               S0      
317GND              VIA        MD0100PA00X+022000Y+020000               S0      
317GND              VIA        MD0100PA00X+022000Y+022000               S0      
317GND              VIA        MD0100PA00X+022000Y+026000               S0      
317GND              VIA        MD0100PA00X+022000Y+028000               S0      
317GND              VIA        MD0100PA00X+022000Y+030000               S0      
317GND              VIA        MD0100PA00X+022000Y+032000               S0      
317GND              VIA        MD0100PA00X+022000Y+034000               S0      
317GND              VIA        MD0100PA00X+022000Y+036000               S0      
317GND              VIA        MD0100PA00X+022000Y+042000               S0      
317GND              VIA        MD0100PA00X+022000Y+046000               S0      
317GND              VIA        MD0100PA00X+022000Y+048000               S0      
317GND              VIA        MD0100PA00X+022000Y+052000               S0      
317GND              VIA        MD0100PA00X+022000Y+062000               S0      
317GND              VIA        MD0100PA00X+022000Y+064000               S0      
317GND              VIA        MD0100PA00X+022000Y+066000               S0      
317GND              VIA        MD0100PA00X+022000Y+068000               S0      
317GND              VIA        MD0100PA00X+022000Y+070000               S0      
317GND              VIA        MD0100PA00X+022000Y+072000               S0      
317GND              VIA        MD0100PA00X+022000Y+074000               S0      
317GND              VIA        MD0100PA00X+022000Y+008000               S0      
317GND              VIA        MD0100PA00X+022000Y+086000               S0      
317GND              VIA        MD0100PA00X+022000Y+088000               S0      
317GND              VIA        MD0100PA00X+022000Y+094000               S0      
317GND              VIA        MD0100PA00X+022020Y+174090               S0      
317GND              VIA        MD0100PA00X+022080Y+176375               S0      
317GND              VIA        MD0100PA00X+002222Y+176832               S0      
317GND              VIA        MD0100PA00X+022700Y+135950               S0      
317GND              VIA        MD0100PA00X+022950Y+161450               S0      
317GND              VIA        MD0100PA00X+023002Y+000550               S0      
317GND              VIA        MD0100PA00X+023256Y+198663               S0      
317GND              VIA        MD0100PA00X+024000Y+100000               S0      
317GND              VIA        MD0100PA00X+024000Y+102000               S0      
317GND              VIA        MD0100PA00X+024000Y+104000               S0      
317GND              VIA        MD0100PA00X+024000Y+106000               S0      
317GND              VIA        MD0100PA00X+024000Y+108000               S0      
317GND              VIA        MD0100PA00X+024000Y+110000               S0      
317GND              VIA        MD0100PA00X+024000Y+112000               S0      
317GND              VIA        MD0100PA00X+024000Y+118000               S0      
317GND              VIA        MD0100PA00X+024000Y+120000               S0      
317GND              VIA        MD0100PA00X+024000Y+122000               S0      
317GND              VIA        MD0100PA00X+024000Y+128000               S0      
317GND              VIA        MD0100PA00X+024000Y+130000               S0      
317GND              VIA        MD0100PA00X+024000Y+134000               S0      
317GND              VIA        MD0100PA00X+024000Y+136750               S0      
317GND              VIA        MD0100PA00X+024000Y+014000               S0      
317GND              VIA        MD0100PA00X+024000Y+140000               S0      
317GND              VIA        MD0100PA00X+024000Y+142000               S0      
317GND              VIA        MD0100PA00X+024000Y+144000               S0      
317GND              VIA        MD0100PA00X+024000Y+146000               S0      
317GND              VIA        MD0100PA00X+024000Y+148000               S0      
317GND              VIA        MD0100PA00X+024000Y+150000               S0      
317GND              VIA        MD0100PA00X+024000Y+152000               S0      
317GND              VIA        MD0100PA00X+024000Y+156000               S0      
317GND              VIA        MD0100PA00X+024000Y+016000               S0      
317GND              VIA        MD0100PA00X+024000Y+166000               S0      
317GND              VIA        MD0100PA00X+024000Y+168000               S0      
317GND              VIA        MD0100PA00X+024000Y+018000               S0      
317GND              VIA        MD0100PA00X+024000Y+180000               S0      
317GND              VIA        MD0100PA00X+024000Y+184000               S0      
317GND              VIA        MD0100PA00X+024000Y+188000               S0      
317GND              VIA        MD0100PA00X+024000Y+192000               S0      
317GND              VIA        MD0100PA00X+024000Y+194000               S0      
317GND              VIA        MD0100PA00X+024000Y+196000               S0      
317GND              VIA        MD0100PA00X+024000Y+198000               S0      
317GND              VIA        MD0100PA00X+024000Y+002000               S0      
317GND              VIA        MD0100PA00X+024000Y+020000               S0      
317GND              VIA        MD0100PA00X+024000Y+022000               S0      
317GND              VIA        MD0100PA00X+024000Y+026000               S0      
317GND              VIA        MD0100PA00X+024000Y+028000               S0      
317GND              VIA        MD0100PA00X+024000Y+030000               S0      
317GND              VIA        MD0100PA00X+024000Y+032000               S0      
317GND              VIA        MD0100PA00X+024000Y+034000               S0      
317GND              VIA        MD0100PA00X+024000Y+036000               S0      
317GND              VIA        MD0100PA00X+024000Y+004000               S0      
317GND              VIA        MD0100PA00X+024000Y+058000               S0      
317GND              VIA        MD0100PA00X+024000Y+060000               S0      
317GND              VIA        MD0100PA00X+024000Y+076000               S0      
317GND              VIA        MD0100PA00X+024000Y+008000               S0      
317GND              VIA        MD0100PA00X+024000Y+086000               S0      
317GND              VIA        MD0100PA00X+024000Y+088000               S0      
317GND              VIA        MD0100PA00X+024000Y+094000               S0      
317GND              VIA        MD0100PA00X+024250Y+170250               S0      
317GND              VIA        MD0100PA00X+002450Y+109577               S0      
317GND              VIA        MD0100PA00X+002450Y+110260               S0      
317GND              VIA        MD0100PA00X+002450Y+110837               S0      
317GND              VIA        MD0100PA00X+002450Y+111520               S0      
317GND              VIA        MD0100PA00X+002450Y+113337               S0      
317GND              VIA        MD0100PA00X+002450Y+114020               S0      
317GND              VIA        MD0100PA00X+002450Y+114596               S0      
317GND              VIA        MD0100PA00X+002450Y+115279               S0      
317GND              VIA        MD0100PA00X+002450Y+115856               S0      
317GND              VIA        MD0100PA00X+002450Y+116539               S0      
317GND              VIA        MD0100PA00X+002450Y+117116               S0      
317GND              VIA        MD0100PA00X+002450Y+117799               S0      
317GND              VIA        MD0100PA00X+002450Y+118376               S0      
317GND              VIA        MD0100PA00X+002450Y+119059               S0      
317GND              VIA        MD0100PA00X+002450Y+119636               S0      
317GND              VIA        MD0100PA00X+002450Y+120319               S0      
317GND              VIA        MD0100PA00X+002450Y+120895               S0      
317GND              VIA        MD0100PA00X+002450Y+121579               S0      
317GND              VIA        MD0100PA00X+002450Y+122155               S0      
317GND              VIA        MD0100PA00X+002450Y+122839               S0      
317GND              VIA        MD0100PA00X+002450Y+125305               S0      
317GND              VIA        MD0100PA00X+002450Y+125988               S0      
317GND              VIA        MD0100PA00X+002450Y+126565               S0      
317GND              VIA        MD0100PA00X+002450Y+127248               S0      
317GND              VIA        MD0100PA00X+002450Y+127825               S0      
317GND              VIA        MD0100PA00X+002450Y+128508               S0      
317GND              VIA        MD0100PA00X+002450Y+129085               S0      
317GND              VIA        MD0100PA00X+002450Y+129768               S0      
317GND              VIA        MD0100PA00X+002450Y+131309               S0      
317GND              VIA        MD0100PA00X+002450Y+131992               S0      
317GND              VIA        MD0100PA00X+002450Y+132569               S0      
317GND              VIA        MD0100PA00X+002450Y+133252               S0      
317GND              VIA        MD0100PA00X+002450Y+133829               S0      
317GND              VIA        MD0100PA00X+002450Y+134512               S0      
317GND              VIA        MD0100PA00X+002450Y+135089               S0      
317GND              VIA        MD0100PA00X+002450Y+135772               S0      
317GND              VIA        MD0100PA00X+002450Y+136329               S0      
317GND              VIA        MD0100PA00X+002450Y+137012               S0      
317GND              VIA        MD0100PA00X+002450Y+137588               S0      
317GND              VIA        MD0100PA00X+002450Y+138272               S0      
317GND              VIA        MD0100PA00X+002450Y+138848               S0      
317GND              VIA        MD0100PA00X+002450Y+139532               S0      
317GND              VIA        MD0100PA00X+002450Y+140108               S0      
317GND              VIA        MD0100PA00X+002450Y+140791               S0      
317GND              VIA        MD0100PA00X+002450Y+152240               S0      
317GND              VIA        MD0100PA00X+002450Y+152911               S0      
317GND              VIA        MD0100PA00X+002450Y+153500               S0      
317GND              VIA        MD0100PA00X+002450Y+154171               S0      
317GND              VIA        MD0100PA00X+002450Y+154760               S0      
317GND              VIA        MD0100PA00X+002450Y+155431               S0      
317GND              VIA        MD0100PA00X+002450Y+156020               S0      
317GND              VIA        MD0100PA00X+002450Y+156691               S0      
317GND              VIA        MD0100PA00X+002450Y+158224               S0      
317GND              VIA        MD0100PA00X+002450Y+158895               S0      
317GND              VIA        MD0100PA00X+002450Y+159484               S0      
317GND              VIA        MD0100PA00X+002450Y+160155               S0      
317GND              VIA        MD0100PA00X+002450Y+160744               S0      
317GND              VIA        MD0100PA00X+002450Y+161415               S0      
317GND              VIA        MD0100PA00X+002450Y+162004               S0      
317GND              VIA        MD0100PA00X+002450Y+162675               S0      
317GND              VIA        MD0100PA00X+002450Y+163264               S0      
317GND              VIA        MD0100PA00X+002450Y+163935               S0      
317GND              VIA        MD0100PA00X+002450Y+167062               S0      
317GND              VIA        MD0100PA00X+002450Y+167733               S0      
317GND              VIA        MD0100PA00X+002450Y+168322               S0      
317GND              VIA        MD0100PA00X+002450Y+168993               S0      
317GND              VIA        MD0100PA00X+002450Y+169582               S0      
317GND              VIA        MD0100PA00X+002450Y+170253               S0      
317GND              VIA        MD0100PA00X+002450Y+171787               S0      
317GND              VIA        MD0100PA00X+002450Y+172458               S0      
317GND              VIA        MD0100PA00X+002450Y+173047               S0      
317GND              VIA        MD0100PA00X+002450Y+173718               S0      
317GND              VIA        MD0100PA00X+002450Y+174307               S0      
317GND              VIA        MD0100PA00X+002450Y+174978               S0      
317GND              VIA        MD0100PA00X+002450Y+175566               S0      
317GND              VIA        MD0100PA00X+002450Y+176237               S0      
317GND              VIA        MD0100PA00X+002450Y+059970               S0      
317GND              VIA        MD0100PA00X+002450Y+060654               S0      
317GND              VIA        MD0100PA00X+002450Y+061225               S0      
317GND              VIA        MD0100PA00X+002450Y+061909               S0      
317GND              VIA        MD0100PA00X+002450Y+062490               S0      
317GND              VIA        MD0100PA00X+002450Y+063174               S0      
317GND              VIA        MD0100PA00X+002450Y+063750               S0      
317GND              VIA        MD0100PA00X+002450Y+064434               S0      
317GND              VIA        MD0100PA00X+002450Y+066269               S0      
317GND              VIA        MD0100PA00X+002450Y+066954               S0      
317GND              VIA        MD0100PA00X+002450Y+067529               S0      
317GND              VIA        MD0100PA00X+002450Y+068214               S0      
317GND              VIA        MD0100PA00X+002450Y+068789               S0      
317GND              VIA        MD0100PA00X+002450Y+069473               S0      
317GND              VIA        MD0100PA00X+002450Y+070049               S0      
317GND              VIA        MD0100PA00X+002450Y+070733               S0      
317GND              VIA        MD0100PA00X+002450Y+071289               S0      
317GND              VIA        MD0100PA00X+002450Y+071973               S0      
317GND              VIA        MD0100PA00X+002450Y+072549               S0      
317GND              VIA        MD0100PA00X+002450Y+073233               S0      
317GND              VIA        MD0100PA00X+002450Y+075698               S0      
317GND              VIA        MD0100PA00X+002450Y+076383               S0      
317GND              VIA        MD0100PA00X+002450Y+076958               S0      
317GND              VIA        MD0100PA00X+002450Y+077642               S0      
317GND              VIA        MD0100PA00X+002450Y+079163               S0      
317GND              VIA        MD0100PA00X+002450Y+079847               S0      
317GND              VIA        MD0100PA00X+002450Y+080422               S0      
317GND              VIA        MD0100PA00X+002450Y+081107               S0      
317GND              VIA        MD0100PA00X+002450Y+081682               S0      
317GND              VIA        MD0100PA00X+002450Y+082367               S0      
317GND              VIA        MD0100PA00X+002450Y+082942               S0      
317GND              VIA        MD0100PA00X+002450Y+083627               S0      
317GND              VIA        MD0100PA00X+002450Y+084182               S0      
317GND              VIA        MD0100PA00X+002450Y+084866               S0      
317GND              VIA        MD0100PA00X+002450Y+085442               S0      
317GND              VIA        MD0100PA00X+002450Y+086126               S0      
317GND              VIA        MD0100PA00X+002450Y+086702               S0      
317GND              VIA        MD0100PA00X+002450Y+087386               S0      
317GND              VIA        MD0100PA00X+002450Y+087967               S0      
317GND              VIA        MD0100PA00X+002450Y+088651               S0      
317GND              VIA        MD0100PA00X+002450Y+089241               S0      
317GND              VIA        MD0100PA00X+002450Y+089926               S0      
317GND              VIA        MD0100PA00X+002450Y+090501               S0      
317GND              VIA        MD0100PA00X+002450Y+091186               S0      
317GND              VIA        MD0100PA00X+025002Y+000550               S0      
317GND              VIA        MD0100PA00X+025180Y+171840               S0      
317GND              VIA        MD0100PA00X+025256Y+198663               S0      
317GND              VIA        MD0100PA00X+025567Y+109947               S0      
317GND              VIA        MD0100PA00X+025600Y+174550               S0      
317GND              VIA        MD0100PA00X+025650Y+188000               S0      
317GND              VIA        MD0100PA00X+025655Y+189837               S0      
317GND              VIA        MD0100PA00X+025859Y+150839               S0      
317GND              VIA        MD0100PA00X+025900Y+170250               S0      
317GND              VIA        MD0100PA00X+026000Y+010000               S0      
317GND              VIA        MD0100PA00X+026000Y+102000               S0      
317GND              VIA        MD0100PA00X+026000Y+104000               S0      
317GND              VIA        MD0100PA00X+026000Y+106000               S0      
317GND              VIA        MD0100PA00X+026000Y+112000               S0      
317GND              VIA        MD0100PA00X+026000Y+116000               S0      
317GND              VIA        MD0100PA00X+026000Y+120000               S0      
317GND              VIA        MD0100PA00X+026000Y+122000               S0      
317GND              VIA        MD0100PA00X+026000Y+126000               S0      
317GND              VIA        MD0100PA00X+026000Y+128000               S0      
317GND              VIA        MD0100PA00X+026000Y+130000               S0      
317GND              VIA        MD0100PA00X+026000Y+134000               S0      
317GND              VIA        MD0100PA00X+026000Y+140000               S0      
317GND              VIA        MD0100PA00X+026000Y+142000               S0      
317GND              VIA        MD0100PA00X+026000Y+144000               S0      
317GND              VIA        MD0100PA00X+026000Y+152000               S0      
317GND              VIA        MD0100PA00X+026000Y+156000               S0      
317GND              VIA        MD0100PA00X+026000Y+016000               S0      
317GND              VIA        MD0100PA00X+026000Y+160000               S0      
317GND              VIA        MD0100PA00X+026000Y+162000               S0      
317GND              VIA        MD0100PA00X+026000Y+166000               S0      
317GND              VIA        MD0100PA00X+026000Y+168000               S0      
317GND              VIA        MD0100PA00X+026000Y+174000               S0      
317GND              VIA        MD0100PA00X+026000Y+018000               S0      
317GND              VIA        MD0100PA00X+026000Y+180000               S0      
317GND              VIA        MD0100PA00X+026000Y+184000               S0      
317GND              VIA        MD0100PA00X+026000Y+194000               S0      
317GND              VIA        MD0100PA00X+026000Y+196000               S0      
317GND              VIA        MD0100PA00X+026000Y+198000               S0      
317GND              VIA        MD0100PA00X+026000Y+002000               S0      
317GND              VIA        MD0100PA00X+026000Y+020000               S0      
317GND              VIA        MD0100PA00X+026000Y+022000               S0      
317GND              VIA        MD0100PA00X+026000Y+030000               S0      
317GND              VIA        MD0100PA00X+026000Y+032000               S0      
317GND              VIA        MD0100PA00X+026000Y+034000               S0      
317GND              VIA        MD0100PA00X+026000Y+036000               S0      
317GND              VIA        MD0100PA00X+026000Y+004000               S0      
317GND              VIA        MD0100PA00X+026000Y+042000               S0      
317GND              VIA        MD0100PA00X+026000Y+044000               S0      
317GND              VIA        MD0100PA00X+026000Y+046000               S0      
317GND              VIA        MD0100PA00X+026000Y+048000               S0      
317GND              VIA        MD0100PA00X+026000Y+052000               S0      
317GND              VIA        MD0100PA00X+026000Y+056000               S0      
317GND              VIA        MD0100PA00X+026000Y+060000               S0      
317GND              VIA        MD0100PA00X+026000Y+062000               S0      
317GND              VIA        MD0100PA00X+026000Y+064000               S0      
317GND              VIA        MD0100PA00X+026000Y+070000               S0      
317GND              VIA        MD0100PA00X+026000Y+072000               S0      
317GND              VIA        MD0100PA00X+026000Y+008000               S0      
317GND              VIA        MD0100PA00X+026000Y+086000               S0      
317GND              VIA        MD0100PA00X+026000Y+088000               S0      
317GND              VIA        MD0100PA00X+026000Y+094000               S0      
317GND              VIA        MD0100PA00X+026000Y+098000               S0      
317GND              VIA        MD0100PA00X+026880Y+177460               S0      
317GND              VIA        MD0100PA00X+002700Y+044000               S0      
317GND              VIA        MD0100PA00X+027002Y+000550               S0      
317GND              VIA        MD0100PA00X+027150Y+179500               S0      
317GND              VIA        MD0100PA00X+027256Y+198663               S0      
317GND              VIA        MD0100PA00X+027350Y+140750               S0      
317GND              VIA        MD0100PA00X+002750Y+038000               S0      
317GND              VIA        MD0100PA00X+002750Y+054000               S0      
317GND              VIA        MD0100PA00X+002750Y+055350               S0      
317GND              VIA        MD0100PA00X+027950Y+179500               S0      
317GND              VIA        MD0100PA00X+028000Y+010000               S0      
317GND              VIA        MD0100PA00X+028000Y+100000               S0      
317GND              VIA        MD0100PA00X+028000Y+102000               S0      
317GND              VIA        MD0100PA00X+028000Y+104000               S0      
317GND              VIA        MD0100PA00X+028000Y+112000               S0      
317GND              VIA        MD0100PA00X+028000Y+118000               S0      
317GND              VIA        MD0100PA00X+028000Y+012000               S0      
317GND              VIA        MD0100PA00X+028000Y+120000               S0      
317GND              VIA        MD0100PA00X+028000Y+122000               S0      
317GND              VIA        MD0100PA00X+028000Y+126000               S0      
317GND              VIA        MD0100PA00X+028000Y+128000               S0      
317GND              VIA        MD0100PA00X+028000Y+130000               S0      
317GND              VIA        MD0100PA00X+028000Y+134000               S0      
317GND              VIA        MD0100PA00X+028000Y+138000               S0      
317GND              VIA        MD0100PA00X+028000Y+152000               S0      
317GND              VIA        MD0100PA00X+028000Y+156000               S0      
317GND              VIA        MD0100PA00X+028000Y+160000               S0      
317GND              VIA        MD0100PA00X+028000Y+162000               S0      
317GND              VIA        MD0100PA00X+028000Y+018000               S0      
317GND              VIA        MD0100PA00X+028000Y+184000               S0      
317GND              VIA        MD0100PA00X+028000Y+194000               S0      
317GND              VIA        MD0100PA00X+028000Y+196000               S0      
317GND              VIA        MD0100PA00X+028000Y+198000               S0      
317GND              VIA        MD0100PA00X+028000Y+002000               S0      
317GND              VIA        MD0100PA00X+028000Y+020000               S0      
317GND              VIA        MD0100PA00X+028000Y+022000               S0      
317GND              VIA        MD0100PA00X+028000Y+032000               S0      
317GND              VIA        MD0100PA00X+028000Y+034000               S0      
317GND              VIA        MD0100PA00X+028000Y+036000               S0      
317GND              VIA        MD0100PA00X+028000Y+004000               S0      
317GND              VIA        MD0100PA00X+028000Y+042000               S0      
317GND              VIA        MD0100PA00X+028000Y+044000               S0      
317GND              VIA        MD0100PA00X+028000Y+046000               S0      
317GND              VIA        MD0100PA00X+028000Y+048000               S0      
317GND              VIA        MD0100PA00X+028000Y+062000               S0      
317GND              VIA        MD0100PA00X+028000Y+064000               S0      
317GND              VIA        MD0100PA00X+028000Y+008000               S0      
317GND              VIA        MD0100PA00X+028000Y+082000               S0      
317GND              VIA        MD0100PA00X+028000Y+086000               S0      
317GND              VIA        MD0100PA00X+028000Y+088000               S0      
317GND              VIA        MD0100PA00X+028000Y+094000               S0      
317GND              VIA        MD0100PA00X+028000Y+098000               S0      
317GND              VIA        MD0100PA00X+028007Y+192467               S0      
317GND              VIA        MD0100PA00X+028400Y+173125               S0      
317GND              VIA        MD0100PA00X+028750Y+179500               S0      
317GND              VIA        MD0100PA00X+028800Y+174250               S0      
317GND              VIA        MD0100PA00X+028800Y+058648               S0      
317GND              VIA        MD0100PA00X+028930Y+169620               S0      
317GND              VIA        MD0100PA00X+028930Y+170180               S0      
317GND              VIA        MD0100PA00X+029002Y+000550               S0      
317GND              VIA        MD0100PA00X+029220Y+168890               S0      
317GND              VIA        MD0100PA00X+029256Y+198663               S0      
317GND              VIA        MD0100PA00X+029300Y+174250               S0      
317GND              VIA        MD0100PA00X+029540Y+117266               S0      
317GND              VIA        MD0100PA00X+029580Y+168890               S0      
317GND              VIA        MD0100PA00X+029601Y+118547               S0      
317GND              VIA        MD0100PA00X+029760Y+139200               S0      
317GND              VIA        MD0100PA00X+029784Y+080455               S0      
317GND              VIA        MD0100PA00X+029820Y+072000               S0      
317GND              VIA        MD0100PA00X+029850Y+066020               S0      
317GND              VIA        MD0100PA00X+029850Y+068020               S0      
317GND              VIA        MD0100PA00X+003002Y+000550               S0      
317GND              VIA        MD0100PA00X+030000Y+010000               S0      
317GND              VIA        MD0100PA00X+030000Y+100000               S0      
317GND              VIA        MD0100PA00X+030000Y+102000               S0      
317GND              VIA        MD0100PA00X+030000Y+104000               S0      
317GND              VIA        MD0100PA00X+030000Y+106000               S0      
317GND              VIA        MD0100PA00X+030000Y+108000               S0      
317GND              VIA        MD0100PA00X+030000Y+110000               S0      
317GND              VIA        MD0100PA00X+030000Y+112000               S0      
317GND              VIA        MD0100PA00X+030000Y+012000               S0      
317GND              VIA        MD0100PA00X+030000Y+124000               S0      
317GND              VIA        MD0100PA00X+030000Y+126000               S0      
317GND              VIA        MD0100PA00X+030000Y+128000               S0      
317GND              VIA        MD0100PA00X+030000Y+130000               S0      
317GND              VIA        MD0100PA00X+030000Y+014000               S0      
317GND              VIA        MD0100PA00X+030000Y+152000               S0      
317GND              VIA        MD0100PA00X+030000Y+156000               S0      
317GND              VIA        MD0100PA00X+030000Y+160000               S0      
317GND              VIA        MD0100PA00X+030000Y+162000               S0      
317GND              VIA        MD0100PA00X+030000Y+180000               S0      
317GND              VIA        MD0100PA00X+030000Y+184000               S0      
317GND              VIA        MD0100PA00X+030000Y+186000               S0      
317GND              VIA        MD0100PA00X+030000Y+188000               S0      
317GND              VIA        MD0100PA00X+030000Y+190000               S0      
317GND              VIA        MD0100PA00X+030000Y+192000               S0      
317GND              VIA        MD0100PA00X+030000Y+194000               S0      
317GND              VIA        MD0100PA00X+030000Y+196000               S0      
317GND              VIA        MD0100PA00X+030000Y+198000               S0      
317GND              VIA        MD0100PA00X+030000Y+002000               S0      
317GND              VIA        MD0100PA00X+030000Y+020000               S0      
317GND              VIA        MD0100PA00X+030000Y+022000               S0      
317GND              VIA        MD0100PA00X+030000Y+028000               S0      
317GND              VIA        MD0100PA00X+030000Y+032000               S0      
317GND              VIA        MD0100PA00X+030000Y+034000               S0      
317GND              VIA        MD0100PA00X+030000Y+004000               S0      
317GND              VIA        MD0100PA00X+030000Y+044000               S0      
317GND              VIA        MD0100PA00X+030000Y+046000               S0      
317GND              VIA        MD0100PA00X+030000Y+048000               S0      
317GND              VIA        MD0100PA00X+030000Y+006000               S0      
317GND              VIA        MD0100PA00X+030000Y+064000               S0      
317GND              VIA        MD0100PA00X+030000Y+008000               S0      
317GND              VIA        MD0100PA00X+030000Y+088000               S0      
317GND              VIA        MD0100PA00X+030000Y+094000               S0      
317GND              VIA        MD0100PA00X+030000Y+098000               S0      
317GND              VIA        MD0100PA00X+030098Y+143350               S0      
317GND              VIA        MD0100PA00X+030130Y+082255               S0      
317GND              VIA        MD0100PA00X+030350Y+138900               S0      
317GND              VIA        MD0100PA00X+030440Y+041620               S0      
317GND              VIA        MD0100PA00X+030440Y+084670               S0      
317GND              VIA        MD0100PA00X+030450Y+121750               S0      
317GND              VIA        MD0100PA00X+030450Y+083670               S0      
317GND              VIA        MD0100PA00X+030455Y+037408               S0      
317GND              VIA        MD0100PA00X+003050Y+146350               S0      
317GND              VIA        MD0100PA00X+030510Y+040770               S0      
317GND              VIA        MD0100PA00X+030520Y+120830               S0      
317GND              VIA        MD0100PA00X+030530Y+171570               S0      
317GND              VIA        MD0100PA00X+030620Y+168940               S0      
317GND              VIA        MD0100PA00X+030620Y+170960               S0      
317GND              VIA        MD0100PA00X+030900Y+116650               S0      
317GND              VIA        MD0100PA00X+030900Y+036500               S0      
317GND              VIA        MD0100PA00X+030900Y+079500               S0      
317GND              VIA        MD0100PA00X+031002Y+000550               S0      
317GND              VIA        MD0100PA00X+031150Y+138900               S0      
317GND              VIA        MD0100PA00X+031256Y+198663               S0      
317GND              VIA        MD0100PA00X+031300Y+055900               S0      
317GND              VIA        MD0100PA00X+031350Y+118750               S0      
317GND              VIA        MD0100PA00X+031350Y+036200               S0      
317GND              VIA        MD0100PA00X+031350Y+038600               S0      
317GND              VIA        MD0100PA00X+031350Y+079200               S0      
317GND              VIA        MD0100PA00X+003171Y+108600               S0      
317GND              VIA        MD0100PA00X+003198Y+176832               S0      
317GND              VIA        MD0100PA00X+032000Y+010000               S0      
317GND              VIA        MD0100PA00X+032000Y+100000               S0      
317GND              VIA        MD0100PA00X+032000Y+102000               S0      
317GND              VIA        MD0100PA00X+032000Y+104000               S0      
317GND              VIA        MD0100PA00X+032000Y+106000               S0      
317GND              VIA        MD0100PA00X+032000Y+108000               S0      
317GND              VIA        MD0100PA00X+032000Y+110000               S0      
317GND              VIA        MD0100PA00X+032000Y+114000               S0      
317GND              VIA        MD0100PA00X+032000Y+116100               S0      
317GND              VIA        MD0100PA00X+032000Y+012000               S0      
317GND              VIA        MD0100PA00X+032000Y+126000               S0      
317GND              VIA        MD0100PA00X+032000Y+128000               S0      
317GND              VIA        MD0100PA00X+032000Y+014000               S0      
317GND              VIA        MD0100PA00X+032000Y+154000               S0      
317GND              VIA        MD0100PA00X+032000Y+156000               S0      
317GND              VIA        MD0100PA00X+032000Y+016000               S0      
317GND              VIA        MD0100PA00X+032000Y+160000               S0      
317GND              VIA        MD0100PA00X+032000Y+176000               S0      
317GND              VIA        MD0100PA00X+032000Y+178000               S0      
317GND              VIA        MD0100PA00X+032000Y+182000               S0      
317GND              VIA        MD0100PA00X+032000Y+184000               S0      
317GND              VIA        MD0100PA00X+032000Y+186000               S0      
317GND              VIA        MD0100PA00X+032000Y+188000               S0      
317GND              VIA        MD0100PA00X+032000Y+190000               S0      
317GND              VIA        MD0100PA00X+032000Y+192000               S0      
317GND              VIA        MD0100PA00X+032000Y+194000               S0      
317GND              VIA        MD0100PA00X+032000Y+196000               S0      
317GND              VIA        MD0100PA00X+032000Y+198000               S0      
317GND              VIA        MD0100PA00X+032000Y+002000               S0      
317GND              VIA        MD0100PA00X+032000Y+022000               S0      
317GND              VIA        MD0100PA00X+032000Y+024000               S0      
317GND              VIA        MD0100PA00X+032000Y+028000               S0      
317GND              VIA        MD0100PA00X+032000Y+032000               S0      
317GND              VIA        MD0100PA00X+032000Y+034000               S0      
317GND              VIA        MD0100PA00X+032000Y+035950               S0      
317GND              VIA        MD0100PA00X+032000Y+004000               S0      
317GND              VIA        MD0100PA00X+032000Y+046000               S0      
317GND              VIA        MD0100PA00X+032000Y+054000               S0      
317GND              VIA        MD0100PA00X+032000Y+006000               S0      
317GND              VIA        MD0100PA00X+032000Y+064000               S0      
317GND              VIA        MD0100PA00X+032000Y+070000               S0      
317GND              VIA        MD0100PA00X+032000Y+072000               S0      
317GND              VIA        MD0100PA00X+032000Y+078950               S0      
317GND              VIA        MD0100PA00X+032000Y+008000               S0      
317GND              VIA        MD0100PA00X+032150Y+121450               S0      
317GND              VIA        MD0100PA00X+032150Y+171300               S0      
317GND              VIA        MD0100PA00X+032150Y+041300               S0      
317GND              VIA        MD0100PA00X+032150Y+080700               S0      
317GND              VIA        MD0100PA00X+032150Y+084300               S0      
317GND              VIA        MD0100PA00X+032300Y+081950               S0      
317GND              VIA        MD0100PA00X+003256Y+198663               S0      
317GND              VIA        MD0100PA00X+032505Y+078265               S0      
317GND              VIA        MD0100PA00X+032750Y+117450               S0      
317GND              VIA        MD0100PA00X+032750Y+167300               S0      
317GND              VIA        MD0100PA00X+032750Y+037300               S0      
317GND              VIA        MD0100PA00X+032750Y+080300               S0      
317GND              VIA        MD0100PA00X+003280Y+152162               S0      
317GND              VIA        MD0100PA00X+032960Y+058320               S0      
317GND              VIA        MD0100PA00X+033002Y+000550               S0      
317GND              VIA        MD0100PA00X+033150Y+119450               S0      
317GND              VIA        MD0100PA00X+033150Y+169500               S0      
317GND              VIA        MD0100PA00X+033150Y+039300               S0      
317GND              VIA        MD0100PA00X+033150Y+082300               S0      
317GND              VIA        MD0100PA00X+033250Y+058900               S0      
317GND              VIA        MD0100PA00X+033250Y+059700               S0      
317GND              VIA        MD0100PA00X+033256Y+198663               S0      
317GND              VIA        MD0100PA00X+033450Y+165000               S0      
317GND              VIA        MD0100PA00X+033450Y+166500               S0      
317GND              VIA        MD0100PA00X+033582Y+094033               S0      
317GND              VIA        MD0100PA00X+003370Y+196030               S0      
317GND              VIA        MD0100PA00X+033750Y+120775               S0      
317GND              VIA        MD0100PA00X+033750Y+170625               S0      
317GND              VIA        MD0100PA00X+033750Y+040625               S0      
317GND              VIA        MD0100PA00X+033750Y+083625               S0      
317GND              VIA        MD0100PA00X+033950Y+121825               S0      
317GND              VIA        MD0100PA00X+033950Y+171675               S0      
317GND              VIA        MD0100PA00X+033950Y+041675               S0      
317GND              VIA        MD0100PA00X+033950Y+084675               S0      
317GND              VIA        MD0100PA00X+003400Y+132100               S0      
317GND              VIA        MD0100PA00X+034000Y+010000               S0      
317GND              VIA        MD0100PA00X+034000Y+100000               S0      
317GND              VIA        MD0100PA00X+034000Y+102000               S0      
317GND              VIA        MD0100PA00X+034000Y+104000               S0      
317GND              VIA        MD0100PA00X+034000Y+106000               S0      
317GND              VIA        MD0100PA00X+034000Y+108000               S0      
317GND              VIA        MD0100PA00X+034000Y+110000               S0      
317GND              VIA        MD0100PA00X+034000Y+114000               S0      
317GND              VIA        MD0100PA00X+034000Y+116000               S0      
317GND              VIA        MD0100PA00X+034000Y+012000               S0      
317GND              VIA        MD0100PA00X+034000Y+134000               S0      
317GND              VIA        MD0100PA00X+034000Y+136000               S0      
317GND              VIA        MD0100PA00X+034000Y+138000               S0      
317GND              VIA        MD0100PA00X+034000Y+014000               S0      
317GND              VIA        MD0100PA00X+034000Y+146000               S0      
317GND              VIA        MD0100PA00X+034000Y+148000               S0      
317GND              VIA        MD0100PA00X+034000Y+016000               S0      
317GND              VIA        MD0100PA00X+034000Y+018000               S0      
317GND              VIA        MD0100PA00X+034000Y+180000               S0      
317GND              VIA        MD0100PA00X+034000Y+182000               S0      
317GND              VIA        MD0100PA00X+034000Y+184000               S0      
317GND              VIA        MD0100PA00X+034000Y+186000               S0      
317GND              VIA        MD0100PA00X+034000Y+188000               S0      
317GND              VIA        MD0100PA00X+034000Y+190000               S0      
317GND              VIA        MD0100PA00X+034000Y+192000               S0      
317GND              VIA        MD0100PA00X+034000Y+194000               S0      
317GND              VIA        MD0100PA00X+034000Y+196000               S0      
317GND              VIA        MD0100PA00X+034000Y+198000               S0      
317GND              VIA        MD0100PA00X+034000Y+002000               S0      
317GND              VIA        MD0100PA00X+034000Y+024000               S0      
317GND              VIA        MD0100PA00X+034000Y+026000               S0      
317GND              VIA        MD0100PA00X+034000Y+004000               S0      
317GND              VIA        MD0100PA00X+034000Y+054000               S0      
317GND              VIA        MD0100PA00X+034000Y+056000               S0      
317GND              VIA        MD0100PA00X+034000Y+006000               S0      
317GND              VIA        MD0100PA00X+034000Y+060000               S0      
317GND              VIA        MD0100PA00X+034000Y+062000               S0      
317GND              VIA        MD0100PA00X+034000Y+066000               S0      
317GND              VIA        MD0100PA00X+034000Y+068000               S0      
317GND              VIA        MD0100PA00X+034000Y+070000               S0      
317GND              VIA        MD0100PA00X+034000Y+072000               S0      
317GND              VIA        MD0100PA00X+034000Y+074000               S0      
317GND              VIA        MD0100PA00X+034000Y+078000               S0      
317GND              VIA        MD0100PA00X+034000Y+008000               S0      
317GND              VIA        MD0100PA00X+034000Y+096000               S0      
317GND              VIA        MD0100PA00X+034000Y+098000               S0      
317GND              VIA        MD0100PA00X+034371Y+174419               S0      
317GND              VIA        MD0100PA00X+034375Y+124572               S0      
317GND              VIA        MD0100PA00X+034375Y+087430               S0      
317GND              VIA        MD0100PA00X+034375Y+045100               S0      
317GND              VIA        MD0100PA00X+003450Y+092500               S0      
317GND              VIA        MD0100PA00X+034825Y+164900               S0      
317GND              VIA        MD0100PA00X+034971Y+035569               S0      
317GND              VIA        MD0100PA00X+035002Y+000550               S0      
317GND              VIA        MD0100PA00X+035024Y+044438               S0      
317GND              VIA        MD0100PA00X+035174Y+088072               S0      
317GND              VIA        MD0100PA00X+035175Y+175100               S0      
317GND              VIA        MD0100PA00X+035177Y+125221               S0      
317GND              VIA        MD0100PA00X+035250Y+006850               S0      
317GND              VIA        MD0100PA00X+035256Y+198663               S0      
317GND              VIA        MD0100PA00X+035423Y+116423               S0      
317GND              VIA        MD0100PA00X+035562Y+091986               S0      
317GND              VIA        MD0100PA00X+035624Y+165572               S0      
317GND              VIA        MD0100PA00X+035625Y+034900               S0      
317GND              VIA        MD0100PA00X+035725Y+012400               S0      
317GND              VIA        MD0100PA00X+035800Y+079400               S0      
317GND              VIA        MD0100PA00X+035850Y+009350               S0      
317GND              VIA        MD0100PA00X+003600Y+096000               S0      
317GND              VIA        MD0100PA00X+036000Y+100000               S0      
317GND              VIA        MD0100PA00X+036000Y+102000               S0      
317GND              VIA        MD0100PA00X+036000Y+104000               S0      
317GND              VIA        MD0100PA00X+036000Y+106000               S0      
317GND              VIA        MD0100PA00X+036000Y+108000               S0      
317GND              VIA        MD0100PA00X+036000Y+110000               S0      
317GND              VIA        MD0100PA00X+036000Y+114000               S0      
317GND              VIA        MD0100PA00X+036000Y+132000               S0      
317GND              VIA        MD0100PA00X+036000Y+134000               S0      
317GND              VIA        MD0100PA00X+036000Y+136000               S0      
317GND              VIA        MD0100PA00X+036000Y+138000               S0      
317GND              VIA        MD0100PA00X+036000Y+014000               S0      
317GND              VIA        MD0100PA00X+036000Y+150000               S0      
317GND              VIA        MD0100PA00X+036000Y+152000               S0      
317GND              VIA        MD0100PA00X+036000Y+154000               S0      
317GND              VIA        MD0100PA00X+036000Y+156000               S0      
317GND              VIA        MD0100PA00X+036000Y+016000               S0      
317GND              VIA        MD0100PA00X+036000Y+018000               S0      
317GND              VIA        MD0100PA00X+036000Y+180000               S0      
317GND              VIA        MD0100PA00X+036000Y+182000               S0      
317GND              VIA        MD0100PA00X+036000Y+184000               S0      
317GND              VIA        MD0100PA00X+036000Y+186000               S0      
317GND              VIA        MD0100PA00X+036000Y+188000               S0      
317GND              VIA        MD0100PA00X+036000Y+190000               S0      
317GND              VIA        MD0100PA00X+036000Y+192000               S0      
317GND              VIA        MD0100PA00X+036000Y+194000               S0      
317GND              VIA        MD0100PA00X+036000Y+196000               S0      
317GND              VIA        MD0100PA00X+036000Y+198000               S0      
317GND              VIA        MD0100PA00X+036000Y+002000               S0      
317GND              VIA        MD0100PA00X+036000Y+026000               S0      
317GND              VIA        MD0100PA00X+036000Y+028000               S0      
317GND              VIA        MD0100PA00X+036000Y+004000               S0      
317GND              VIA        MD0100PA00X+036000Y+058000               S0      
317GND              VIA        MD0100PA00X+036000Y+064000               S0      
317GND              VIA        MD0100PA00X+036000Y+066000               S0      
317GND              VIA        MD0100PA00X+036000Y+068000               S0      
317GND              VIA        MD0100PA00X+036000Y+070000               S0      
317GND              VIA        MD0100PA00X+036000Y+072000               S0      
317GND              VIA        MD0100PA00X+036000Y+094000               S0      
317GND              VIA        MD0100PA00X+036000Y+096000               S0      
317GND              VIA        MD0100PA00X+036000Y+098000               S0      
317GND              VIA        MD0100PA00X+036200Y+079700               S0      
317GND              VIA        MD0100PA00X+036350Y+116500               S0      
317GND              VIA        MD0100PA00X+036375Y+006525               S0      
317GND              VIA        MD0100PA00X+036375Y+007330               S0      
317GND              VIA        MD0100PA00X+003640Y+152162               S0      
317GND              VIA        MD0100PA00X+003650Y+099950               S0      
317GND              VIA        MD0100PA00X+036540Y+173440               S0      
317GND              VIA        MD0100PA00X+036550Y+079700               S0      
317GND              VIA        MD0100PA00X+036750Y+116800               S0      
317GND              VIA        MD0100PA00X+036850Y+123650               S0      
317GND              VIA        MD0100PA00X+036850Y+166400               S0      
317GND              VIA        MD0100PA00X+036850Y+176800               S0      
317GND              VIA        MD0100PA00X+036850Y+036450               S0      
317GND              VIA        MD0100PA00X+036850Y+043600               S0      
317GND              VIA        MD0100PA00X+036850Y+086500               S0      
317GND              VIA        MD0100PA00X+036900Y+173450               S0      
317GND              VIA        MD0100PA00X+003700Y+144350               S0      
317GND              VIA        MD0100PA00X+037002Y+000550               S0      
317GND              VIA        MD0100PA00X+037013Y+036134               S0      
317GND              VIA        MD0100PA00X+037020Y+123970               S0      
317GND              VIA        MD0100PA00X+037040Y+043912               S0      
317GND              VIA        MD0100PA00X+037100Y+116800               S0      
317GND              VIA        MD0100PA00X+037106Y+090335               S0      
317GND              VIA        MD0100PA00X+037200Y+123650               S0      
317GND              VIA        MD0100PA00X+037200Y+036450               S0      
317GND              VIA        MD0100PA00X+037200Y+043600               S0      
317GND              VIA        MD0100PA00X+037200Y+086500               S0      
317GND              VIA        MD0100PA00X+037250Y+166700               S0      
317GND              VIA        MD0100PA00X+037250Y+173450               S0      
317GND              VIA        MD0100PA00X+037256Y+198663               S0      
317GND              VIA        MD0100PA00X+037350Y+009800               S0      
317GND              VIA        MD0100PA00X+037430Y+008140               S0      
317GND              VIA        MD0100PA00X+037600Y+166700               S0      
317GND              VIA        MD0100PA00X+037725Y+077900               S0      
317GND              VIA        MD0100PA00X+037750Y+009800               S0      
317GND              VIA        MD0100PA00X+037810Y+008150               S0      
317GND              VIA        MD0100PA00X+037923Y+087428               S0      
317GND              VIA        MD0100PA00X+037925Y+124578               S0      
317GND              VIA        MD0100PA00X+037925Y+045100               S0      
317GND              VIA        MD0100PA00X+038000Y+100000               S0      
317GND              VIA        MD0100PA00X+038000Y+102000               S0      
317GND              VIA        MD0100PA00X+038000Y+104000               S0      
317GND              VIA        MD0100PA00X+038000Y+106000               S0      
317GND              VIA        MD0100PA00X+038000Y+108000               S0      
317GND              VIA        MD0100PA00X+038000Y+110000               S0      
317GND              VIA        MD0100PA00X+038000Y+130000               S0      
317GND              VIA        MD0100PA00X+038000Y+132000               S0      
317GND              VIA        MD0100PA00X+038000Y+134000               S0      
317GND              VIA        MD0100PA00X+038000Y+136000               S0      
317GND              VIA        MD0100PA00X+038000Y+138000               S0      
317GND              VIA        MD0100PA00X+038000Y+014000               S0      
317GND              VIA        MD0100PA00X+038000Y+140000               S0      
317GND              VIA        MD0100PA00X+038000Y+142000               S0      
317GND              VIA        MD0100PA00X+038000Y+144000               S0      
317GND              VIA        MD0100PA00X+038000Y+150000               S0      
317GND              VIA        MD0100PA00X+038000Y+152000               S0      
317GND              VIA        MD0100PA00X+038000Y+154000               S0      
317GND              VIA        MD0100PA00X+038000Y+158000               S0      
317GND              VIA        MD0100PA00X+038000Y+016000               S0      
317GND              VIA        MD0100PA00X+038000Y+166000               S0      
317GND              VIA        MD0100PA00X+038000Y+018000               S0      
317GND              VIA        MD0100PA00X+038000Y+180000               S0      
317GND              VIA        MD0100PA00X+038000Y+182000               S0      
317GND              VIA        MD0100PA00X+038000Y+184000               S0      
317GND              VIA        MD0100PA00X+038000Y+186000               S0      
317GND              VIA        MD0100PA00X+038000Y+188000               S0      
317GND              VIA        MD0100PA00X+038000Y+190000               S0      
317GND              VIA        MD0100PA00X+038000Y+192000               S0      
317GND              VIA        MD0100PA00X+038000Y+194000               S0      
317GND              VIA        MD0100PA00X+038000Y+196000               S0      
317GND              VIA        MD0100PA00X+038000Y+198000               S0      
317GND              VIA        MD0100PA00X+038000Y+002000               S0      
317GND              VIA        MD0100PA00X+038000Y+020000               S0      
317GND              VIA        MD0100PA00X+038000Y+004000               S0      
317GND              VIA        MD0100PA00X+038000Y+050000               S0      
317GND              VIA        MD0100PA00X+038000Y+054000               S0      
317GND              VIA        MD0100PA00X+038000Y+056000               S0      
317GND              VIA        MD0100PA00X+038000Y+062000               S0      
317GND              VIA        MD0100PA00X+038000Y+064000               S0      
317GND              VIA        MD0100PA00X+038000Y+066000               S0      
317GND              VIA        MD0100PA00X+038000Y+092000               S0      
317GND              VIA        MD0100PA00X+038000Y+094000               S0      
317GND              VIA        MD0100PA00X+038000Y+096000               S0      
317GND              VIA        MD0100PA00X+038000Y+098000               S0      
317GND              VIA        MD0100PA00X+003820Y+188380               S0      
317GND              VIA        MD0100PA00X+003830Y+185905               S0      
317GND              VIA        MD0100PA00X+038375Y+115050               S0      
317GND              VIA        MD0100PA00X+038375Y+034900               S0      
317GND              VIA        MD0100PA00X+003840Y+184675               S0      
317GND              VIA        MD0100PA00X+003850Y+187135               S0      
317GND              VIA        MD0100PA00X+038525Y+078570               S0      
317GND              VIA        MD0100PA00X+038590Y+044427               S0      
317GND              VIA        MD0100PA00X+038721Y+125221               S0      
317GND              VIA        MD0100PA00X+038725Y+088100               S0      
317GND              VIA        MD0100PA00X+038875Y+167300               S0      
317GND              VIA        MD0100PA00X+039002Y+000550               S0      
317GND              VIA        MD0100PA00X+039150Y+121850               S0      
317GND              VIA        MD0100PA00X+039177Y+115785               S0      
317GND              VIA        MD0100PA00X+039180Y+035580               S0      
317GND              VIA        MD0100PA00X+039256Y+198663               S0      
317GND              VIA        MD0100PA00X+039300Y+172350               S0      
317GND              VIA        MD0100PA00X+003940Y+181990               S0      
317GND              VIA        MD0100PA00X+003950Y+182330               S0      
317GND              VIA        MD0100PA00X+039500Y+080650               S0      
317GND              VIA        MD0100PA00X+039675Y+118125               S0      
317GND              VIA        MD0100PA00X+039700Y+038375               S0      
317GND              VIA        MD0100PA00X+039700Y+041475               S0      
317GND              VIA        MD0100PA00X+039700Y+084475               S0      
317GND              VIA        MD0100PA00X+004000Y+010000               S0      
317GND              VIA        MD0100PA00X+004000Y+012000               S0      
317GND              VIA        MD0100PA00X+004000Y+014000               S0      
317GND              VIA        MD0100PA00X+004000Y+016000               S0      
317GND              VIA        MD0100PA00X+004000Y+018000               S0      
317GND              VIA        MD0100PA00X+004000Y+194000               S0      
317GND              VIA        MD0100PA00X+004000Y+198000               S0      
317GND              VIA        MD0100PA00X+004000Y+002000               S0      
317GND              VIA        MD0100PA00X+004000Y+020000               S0      
317GND              VIA        MD0100PA00X+004000Y+022000               S0      
317GND              VIA        MD0100PA00X+004000Y+024000               S0      
317GND              VIA        MD0100PA00X+004000Y+004000               S0      
317GND              VIA        MD0100PA00X+004000Y+006000               S0      
317GND              VIA        MD0100PA00X+004000Y+008000               S0      
317GND              VIA        MD0100PA00X+040000Y+010000               S0      
317GND              VIA        MD0100PA00X+040000Y+100000               S0      
317GND              VIA        MD0100PA00X+040000Y+102000               S0      
317GND              VIA        MD0100PA00X+040000Y+104000               S0      
317GND              VIA        MD0100PA00X+040000Y+106000               S0      
317GND              VIA        MD0100PA00X+040000Y+108000               S0      
317GND              VIA        MD0100PA00X+040000Y+012000               S0      
317GND              VIA        MD0100PA00X+040000Y+126000               S0      
317GND              VIA        MD0100PA00X+040000Y+128000               S0      
317GND              VIA        MD0100PA00X+040000Y+130000               S0      
317GND              VIA        MD0100PA00X+040000Y+132000               S0      
317GND              VIA        MD0100PA00X+040000Y+134000               S0      
317GND              VIA        MD0100PA00X+040000Y+136000               S0      
317GND              VIA        MD0100PA00X+040000Y+138000               S0      
317GND              VIA        MD0100PA00X+040000Y+014000               S0      
317GND              VIA        MD0100PA00X+040000Y+140000               S0      
317GND              VIA        MD0100PA00X+040000Y+142000               S0      
317GND              VIA        MD0100PA00X+040000Y+144000               S0      
317GND              VIA        MD0100PA00X+040000Y+146000               S0      
317GND              VIA        MD0100PA00X+040000Y+152000               S0      
317GND              VIA        MD0100PA00X+040000Y+154000               S0      
317GND              VIA        MD0100PA00X+040000Y+158000               S0      
317GND              VIA        MD0100PA00X+040000Y+016000               S0      
317GND              VIA        MD0100PA00X+040000Y+166000               S0      
317GND              VIA        MD0100PA00X+040000Y+176000               S0      
317GND              VIA        MD0100PA00X+040000Y+018000               S0      
317GND              VIA        MD0100PA00X+040000Y+180000               S0      
317GND              VIA        MD0100PA00X+040000Y+182000               S0      
317GND              VIA        MD0100PA00X+040000Y+184000               S0      
317GND              VIA        MD0100PA00X+040000Y+186000               S0      
317GND              VIA        MD0100PA00X+040000Y+188000               S0      
317GND              VIA        MD0100PA00X+040000Y+190000               S0      
317GND              VIA        MD0100PA00X+040000Y+192000               S0      
317GND              VIA        MD0100PA00X+040000Y+194000               S0      
317GND              VIA        MD0100PA00X+040000Y+196000               S0      
317GND              VIA        MD0100PA00X+040000Y+198000               S0      
317GND              VIA        MD0100PA00X+040000Y+002000               S0      
317GND              VIA        MD0100PA00X+040000Y+020000               S0      
317GND              VIA        MD0100PA00X+040000Y+022000               S0      
317GND              VIA        MD0100PA00X+040000Y+004000               S0      
317GND              VIA        MD0100PA00X+040000Y+044000               S0      
317GND              VIA        MD0100PA00X+040000Y+046000               S0      
317GND              VIA        MD0100PA00X+040000Y+048000               S0      
317GND              VIA        MD0100PA00X+040000Y+052000               S0      
317GND              VIA        MD0100PA00X+040000Y+054000               S0      
317GND              VIA        MD0100PA00X+040000Y+056000               S0      
317GND              VIA        MD0100PA00X+040000Y+006000               S0      
317GND              VIA        MD0100PA00X+040000Y+062000               S0      
317GND              VIA        MD0100PA00X+040000Y+064000               S0      
317GND              VIA        MD0100PA00X+040000Y+068000               S0      
317GND              VIA        MD0100PA00X+040000Y+070000               S0      
317GND              VIA        MD0100PA00X+040000Y+072000               S0      
317GND              VIA        MD0100PA00X+040000Y+074000               S0      
317GND              VIA        MD0100PA00X+040000Y+078000               S0      
317GND              VIA        MD0100PA00X+040000Y+008000               S0      
317GND              VIA        MD0100PA00X+040000Y+090000               S0      
317GND              VIA        MD0100PA00X+040000Y+092000               S0      
317GND              VIA        MD0100PA00X+040000Y+094000               S0      
317GND              VIA        MD0100PA00X+040000Y+096000               S0      
317GND              VIA        MD0100PA00X+040000Y+098000               S0      
317GND              VIA        MD0100PA00X+040150Y+040150               S0      
317GND              VIA        MD0100PA00X+040150Y+083600               S0      
317GND              VIA        MD0100PA00X+040200Y+120250               S0      
317GND              VIA        MD0100PA00X+040200Y+170100               S0      
317GND              VIA        MD0100PA00X+004050Y+160850               S0      
317GND              VIA        MD0100PA00X+004056Y+191707               S0      
317GND              VIA        MD0100PA00X+040650Y+173650               S0      
317GND              VIA        MD0100PA00X+004080Y+182730               S0      
317GND              VIA        MD0100PA00X+004080Y+183230               S0      
317GND              VIA        MD0100PA00X+041002Y+000550               S0      
317GND              VIA        MD0100PA00X+041256Y+198663               S0      
317GND              VIA        MD0100PA00X+041427Y+122325               S0      
317GND              VIA        MD0100PA00X+041428Y+082075               S0      
317GND              VIA        MD0100PA00X+041430Y+172175               S0      
317GND              VIA        MD0100PA00X+004150Y+116550               S0      
317GND              VIA        MD0100PA00X+004150Y+117800               S0      
317GND              VIA        MD0100PA00X+004170Y+188370               S0      
317GND              VIA        MD0100PA00X+042000Y+010000               S0      
317GND              VIA        MD0100PA00X+042000Y+100000               S0      
317GND              VIA        MD0100PA00X+042000Y+102000               S0      
317GND              VIA        MD0100PA00X+042000Y+104000               S0      
317GND              VIA        MD0100PA00X+042000Y+106000               S0      
317GND              VIA        MD0100PA00X+042000Y+116000               S0      
317GND              VIA        MD0100PA00X+042000Y+118000               S0      
317GND              VIA        MD0100PA00X+042000Y+012000               S0      
317GND              VIA        MD0100PA00X+042000Y+120000               S0      
317GND              VIA        MD0100PA00X+042000Y+124000               S0      
317GND              VIA        MD0100PA00X+042000Y+126000               S0      
317GND              VIA        MD0100PA00X+042000Y+128000               S0      
317GND              VIA        MD0100PA00X+042000Y+130000               S0      
317GND              VIA        MD0100PA00X+042000Y+132000               S0      
317GND              VIA        MD0100PA00X+042000Y+134000               S0      
317GND              VIA        MD0100PA00X+042000Y+136000               S0      
317GND              VIA        MD0100PA00X+042000Y+138000               S0      
317GND              VIA        MD0100PA00X+042000Y+014000               S0      
317GND              VIA        MD0100PA00X+042000Y+140000               S0      
317GND              VIA        MD0100PA00X+042000Y+142000               S0      
317GND              VIA        MD0100PA00X+042000Y+144000               S0      
317GND              VIA        MD0100PA00X+042000Y+146000               S0      
317GND              VIA        MD0100PA00X+042000Y+148000               S0      
317GND              VIA        MD0100PA00X+042000Y+154000               S0      
317GND              VIA        MD0100PA00X+042000Y+158000               S0      
317GND              VIA        MD0100PA00X+042000Y+016000               S0      
317GND              VIA        MD0100PA00X+042000Y+166000               S0      
317GND              VIA        MD0100PA00X+042000Y+168000               S0      
317GND              VIA        MD0100PA00X+042000Y+170000               S0      
317GND              VIA        MD0100PA00X+042000Y+176000               S0      
317GND              VIA        MD0100PA00X+042000Y+018000               S0      
317GND              VIA        MD0100PA00X+042000Y+182000               S0      
317GND              VIA        MD0100PA00X+042000Y+184000               S0      
317GND              VIA        MD0100PA00X+042000Y+186000               S0      
317GND              VIA        MD0100PA00X+042000Y+188000               S0      
317GND              VIA        MD0100PA00X+042000Y+190000               S0      
317GND              VIA        MD0100PA00X+042000Y+192000               S0      
317GND              VIA        MD0100PA00X+042000Y+194000               S0      
317GND              VIA        MD0100PA00X+042000Y+196000               S0      
317GND              VIA        MD0100PA00X+042000Y+198000               S0      
317GND              VIA        MD0100PA00X+042000Y+002000               S0      
317GND              VIA        MD0100PA00X+042000Y+020000               S0      
317GND              VIA        MD0100PA00X+042000Y+022000               S0      
317GND              VIA        MD0100PA00X+042000Y+024000               S0      
317GND              VIA        MD0100PA00X+042000Y+026000               S0      
317GND              VIA        MD0100PA00X+042000Y+004000               S0      
317GND              VIA        MD0100PA00X+042000Y+050000               S0      
317GND              VIA        MD0100PA00X+042000Y+052000               S0      
317GND              VIA        MD0100PA00X+042000Y+054000               S0      
317GND              VIA        MD0100PA00X+042000Y+056000               S0      
317GND              VIA        MD0100PA00X+042000Y+006000               S0      
317GND              VIA        MD0100PA00X+042000Y+060000               S0      
317GND              VIA        MD0100PA00X+042000Y+062000               S0      
317GND              VIA        MD0100PA00X+042000Y+066000               S0      
317GND              VIA        MD0100PA00X+042000Y+068000               S0      
317GND              VIA        MD0100PA00X+042000Y+070000               S0      
317GND              VIA        MD0100PA00X+042000Y+072000               S0      
317GND              VIA        MD0100PA00X+042000Y+074000               S0      
317GND              VIA        MD0100PA00X+042000Y+076000               S0      
317GND              VIA        MD0100PA00X+042000Y+078000               S0      
317GND              VIA        MD0100PA00X+042000Y+008000               S0      
317GND              VIA        MD0100PA00X+042000Y+084000               S0      
317GND              VIA        MD0100PA00X+042000Y+086000               S0      
317GND              VIA        MD0100PA00X+042000Y+088000               S0      
317GND              VIA        MD0100PA00X+042000Y+090000               S0      
317GND              VIA        MD0100PA00X+042000Y+092000               S0      
317GND              VIA        MD0100PA00X+042000Y+094000               S0      
317GND              VIA        MD0100PA00X+042000Y+096000               S0      
317GND              VIA        MD0100PA00X+042000Y+098000               S0      
317GND              VIA        MD0100PA00X+042074Y+121527               S0      
317GND              VIA        MD0100PA00X+004210Y+187135               S0      
317GND              VIA        MD0100PA00X+042100Y+171375               S0      
317GND              VIA        MD0100PA00X+042100Y+081275               S0      
317GND              VIA        MD0100PA00X+004220Y+185905               S0      
317GND              VIA        MD0100PA00X+004230Y+184675               S0      
317GND              VIA        MD0100PA00X+043002Y+000550               S0      
317GND              VIA        MD0100PA00X+043256Y+198663               S0      
317GND              VIA        MD0100PA00X+004394Y+195722               S0      
317GND              VIA        MD0100PA00X+004400Y+190000               S0      
317GND              VIA        MD0100PA00X+044000Y+010000               S0      
317GND              VIA        MD0100PA00X+044000Y+100000               S0      
317GND              VIA        MD0100PA00X+044000Y+102000               S0      
317GND              VIA        MD0100PA00X+044000Y+104000               S0      
317GND              VIA        MD0100PA00X+044000Y+112000               S0      
317GND              VIA        MD0100PA00X+044000Y+116000               S0      
317GND              VIA        MD0100PA00X+044000Y+118000               S0      
317GND              VIA        MD0100PA00X+044000Y+012000               S0      
317GND              VIA        MD0100PA00X+044000Y+120000               S0      
317GND              VIA        MD0100PA00X+044000Y+124000               S0      
317GND              VIA        MD0100PA00X+044000Y+126000               S0      
317GND              VIA        MD0100PA00X+044000Y+128000               S0      
317GND              VIA        MD0100PA00X+044000Y+130000               S0      
317GND              VIA        MD0100PA00X+044000Y+132000               S0      
317GND              VIA        MD0100PA00X+044000Y+134000               S0      
317GND              VIA        MD0100PA00X+044000Y+136000               S0      
317GND              VIA        MD0100PA00X+044000Y+138000               S0      
317GND              VIA        MD0100PA00X+044000Y+014000               S0      
317GND              VIA        MD0100PA00X+044000Y+140000               S0      
317GND              VIA        MD0100PA00X+044000Y+142000               S0      
317GND              VIA        MD0100PA00X+044000Y+144000               S0      
317GND              VIA        MD0100PA00X+044000Y+146000               S0      
317GND              VIA        MD0100PA00X+044000Y+148000               S0      
317GND              VIA        MD0100PA00X+044000Y+150000               S0      
317GND              VIA        MD0100PA00X+044000Y+158000               S0      
317GND              VIA        MD0100PA00X+044000Y+016000               S0      
317GND              VIA        MD0100PA00X+044000Y+168000               S0      
317GND              VIA        MD0100PA00X+044000Y+176000               S0      
317GND              VIA        MD0100PA00X+044000Y+178000               S0      
317GND              VIA        MD0100PA00X+044000Y+018000               S0      
317GND              VIA        MD0100PA00X+044000Y+184000               S0      
317GND              VIA        MD0100PA00X+044000Y+186000               S0      
317GND              VIA        MD0100PA00X+044000Y+188000               S0      
317GND              VIA        MD0100PA00X+044000Y+190000               S0      
317GND              VIA        MD0100PA00X+044000Y+192000               S0      
317GND              VIA        MD0100PA00X+044000Y+194000               S0      
317GND              VIA        MD0100PA00X+044000Y+196000               S0      
317GND              VIA        MD0100PA00X+044000Y+198000               S0      
317GND              VIA        MD0100PA00X+044000Y+002000               S0      
317GND              VIA        MD0100PA00X+044000Y+020000               S0      
317GND              VIA        MD0100PA00X+044000Y+022000               S0      
317GND              VIA        MD0100PA00X+044000Y+024000               S0      
317GND              VIA        MD0100PA00X+044000Y+026000               S0      
317GND              VIA        MD0100PA00X+044000Y+028000               S0      
317GND              VIA        MD0100PA00X+044000Y+032000               S0      
317GND              VIA        MD0100PA00X+044000Y+034000               S0      
317GND              VIA        MD0100PA00X+044000Y+036000               S0      
317GND              VIA        MD0100PA00X+044000Y+038000               S0      
317GND              VIA        MD0100PA00X+044000Y+004000               S0      
317GND              VIA        MD0100PA00X+044000Y+040000               S0      
317GND              VIA        MD0100PA00X+044000Y+042000               S0      
317GND              VIA        MD0100PA00X+044000Y+044000               S0      
317GND              VIA        MD0100PA00X+044000Y+046000               S0      
317GND              VIA        MD0100PA00X+044000Y+048000               S0      
317GND              VIA        MD0100PA00X+044000Y+052000               S0      
317GND              VIA        MD0100PA00X+044000Y+054000               S0      
317GND              VIA        MD0100PA00X+044000Y+058000               S0      
317GND              VIA        MD0100PA00X+044000Y+006000               S0      
317GND              VIA        MD0100PA00X+044000Y+060000               S0      
317GND              VIA        MD0100PA00X+044000Y+008000               S0      
317GND              VIA        MD0100PA00X+044000Y+084000               S0      
317GND              VIA        MD0100PA00X+044000Y+086000               S0      
317GND              VIA        MD0100PA00X+044000Y+088000               S0      
317GND              VIA        MD0100PA00X+044000Y+090000               S0      
317GND              VIA        MD0100PA00X+044000Y+092000               S0      
317GND              VIA        MD0100PA00X+044000Y+094000               S0      
317GND              VIA        MD0100PA00X+044000Y+096000               S0      
317GND              VIA        MD0100PA00X+044000Y+098000               S0      
317GND              VIA        MD0100PA00X+045000Y+180350               S0      
317GND              VIA        MD0100PA00X+045002Y+000550               S0      
317GND              VIA        MD0100PA00X+004510Y+185080               S0      
317GND              VIA        MD0100PA00X+004520Y+183930               S0      
317GND              VIA        MD0100PA00X+004520Y+184330               S0      
317GND              VIA        MD0100PA00X+004520Y+185470               S0      
317GND              VIA        MD0100PA00X+045256Y+198663               S0      
317GND              VIA        MD0100PA00X+046000Y+010000               S0      
317GND              VIA        MD0100PA00X+046000Y+100000               S0      
317GND              VIA        MD0100PA00X+046000Y+102000               S0      
317GND              VIA        MD0100PA00X+046000Y+108000               S0      
317GND              VIA        MD0100PA00X+046000Y+112000               S0      
317GND              VIA        MD0100PA00X+046000Y+116000               S0      
317GND              VIA        MD0100PA00X+046000Y+118000               S0      
317GND              VIA        MD0100PA00X+046000Y+012000               S0      
317GND              VIA        MD0100PA00X+046000Y+120000               S0      
317GND              VIA        MD0100PA00X+046000Y+124000               S0      
317GND              VIA        MD0100PA00X+046000Y+126000               S0      
317GND              VIA        MD0100PA00X+046000Y+128000               S0      
317GND              VIA        MD0100PA00X+046000Y+130000               S0      
317GND              VIA        MD0100PA00X+046000Y+132000               S0      
317GND              VIA        MD0100PA00X+046000Y+134000               S0      
317GND              VIA        MD0100PA00X+046000Y+136000               S0      
317GND              VIA        MD0100PA00X+046000Y+138000               S0      
317GND              VIA        MD0100PA00X+046000Y+014000               S0      
317GND              VIA        MD0100PA00X+046000Y+140000               S0      
317GND              VIA        MD0100PA00X+046000Y+142000               S0      
317GND              VIA        MD0100PA00X+046000Y+144000               S0      
317GND              VIA        MD0100PA00X+046000Y+146000               S0      
317GND              VIA        MD0100PA00X+046000Y+148000               S0      
317GND              VIA        MD0100PA00X+046000Y+150000               S0      
317GND              VIA        MD0100PA00X+046000Y+152000               S0      
317GND              VIA        MD0100PA00X+046000Y+158000               S0      
317GND              VIA        MD0100PA00X+046000Y+016000               S0      
317GND              VIA        MD0100PA00X+046000Y+166000               S0      
317GND              VIA        MD0100PA00X+046000Y+168000               S0      
317GND              VIA        MD0100PA00X+046000Y+176000               S0      
317GND              VIA        MD0100PA00X+046000Y+178000               S0      
317GND              VIA        MD0100PA00X+046000Y+018000               S0      
317GND              VIA        MD0100PA00X+046000Y+184000               S0      
317GND              VIA        MD0100PA00X+046000Y+186000               S0      
317GND              VIA        MD0100PA00X+046000Y+188000               S0      
317GND              VIA        MD0100PA00X+046000Y+190000               S0      
317GND              VIA        MD0100PA00X+046000Y+192000               S0      
317GND              VIA        MD0100PA00X+046000Y+194000               S0      
317GND              VIA        MD0100PA00X+046000Y+196000               S0      
317GND              VIA        MD0100PA00X+046000Y+198000               S0      
317GND              VIA        MD0100PA00X+046000Y+002000               S0      
317GND              VIA        MD0100PA00X+046000Y+020000               S0      
317GND              VIA        MD0100PA00X+046000Y+022000               S0      
317GND              VIA        MD0100PA00X+046000Y+024000               S0      
317GND              VIA        MD0100PA00X+046000Y+026000               S0      
317GND              VIA        MD0100PA00X+046000Y+028000               S0      
317GND              VIA        MD0100PA00X+046000Y+030000               S0      
317GND              VIA        MD0100PA00X+046000Y+032000               S0      
317GND              VIA        MD0100PA00X+046000Y+034000               S0      
317GND              VIA        MD0100PA00X+046000Y+036000               S0      
317GND              VIA        MD0100PA00X+046000Y+038000               S0      
317GND              VIA        MD0100PA00X+046000Y+004000               S0      
317GND              VIA        MD0100PA00X+046000Y+040000               S0      
317GND              VIA        MD0100PA00X+046000Y+042000               S0      
317GND              VIA        MD0100PA00X+046000Y+044000               S0      
317GND              VIA        MD0100PA00X+046000Y+046000               S0      
317GND              VIA        MD0100PA00X+046000Y+048000               S0      
317GND              VIA        MD0100PA00X+046000Y+050000               S0      
317GND              VIA        MD0100PA00X+046000Y+052000               S0      
317GND              VIA        MD0100PA00X+046000Y+058000               S0      
317GND              VIA        MD0100PA00X+046000Y+006000               S0      
317GND              VIA        MD0100PA00X+046000Y+066000               S0      
317GND              VIA        MD0100PA00X+046000Y+068000               S0      
317GND              VIA        MD0100PA00X+046000Y+070000               S0      
317GND              VIA        MD0100PA00X+046000Y+072000               S0      
317GND              VIA        MD0100PA00X+046000Y+076000               S0      
317GND              VIA        MD0100PA00X+046000Y+078000               S0      
317GND              VIA        MD0100PA00X+046000Y+008000               S0      
317GND              VIA        MD0100PA00X+046000Y+080000               S0      
317GND              VIA        MD0100PA00X+046000Y+082000               S0      
317GND              VIA        MD0100PA00X+046000Y+084000               S0      
317GND              VIA        MD0100PA00X+046000Y+086000               S0      
317GND              VIA        MD0100PA00X+046000Y+088000               S0      
317GND              VIA        MD0100PA00X+046000Y+090000               S0      
317GND              VIA        MD0100PA00X+046000Y+092000               S0      
317GND              VIA        MD0100PA00X+046000Y+094000               S0      
317GND              VIA        MD0100PA00X+046000Y+096000               S0      
317GND              VIA        MD0100PA00X+046000Y+098000               S0      
317GND              VIA        MD0100PA00X+004649Y+036040               S0      
317GND              VIA        MD0100PA00X+047002Y+000550               S0      
317GND              VIA        MD0100PA00X+047256Y+198663               S0      
317GND              VIA        MD0100PA00X+004800Y+148200               S0      
317GND              VIA        MD0100PA00X+004800Y+150550               S0      
317GND              VIA        MD0100PA00X+048000Y+010000               S0      
317GND              VIA        MD0100PA00X+048000Y+100000               S0      
317GND              VIA        MD0100PA00X+048000Y+106000               S0      
317GND              VIA        MD0100PA00X+048000Y+108000               S0      
317GND              VIA        MD0100PA00X+048000Y+112000               S0      
317GND              VIA        MD0100PA00X+048000Y+116000               S0      
317GND              VIA        MD0100PA00X+048000Y+118000               S0      
317GND              VIA        MD0100PA00X+048000Y+012000               S0      
317GND              VIA        MD0100PA00X+048000Y+120000               S0      
317GND              VIA        MD0100PA00X+048000Y+124000               S0      
317GND              VIA        MD0100PA00X+048000Y+126000               S0      
317GND              VIA        MD0100PA00X+048000Y+128000               S0      
317GND              VIA        MD0100PA00X+048000Y+130000               S0      
317GND              VIA        MD0100PA00X+048000Y+132000               S0      
317GND              VIA        MD0100PA00X+048000Y+134000               S0      
317GND              VIA        MD0100PA00X+048000Y+136000               S0      
317GND              VIA        MD0100PA00X+048000Y+138000               S0      
317GND              VIA        MD0100PA00X+048000Y+014000               S0      
317GND              VIA        MD0100PA00X+048000Y+140000               S0      
317GND              VIA        MD0100PA00X+048000Y+142000               S0      
317GND              VIA        MD0100PA00X+048000Y+144000               S0      
317GND              VIA        MD0100PA00X+048000Y+146000               S0      
317GND              VIA        MD0100PA00X+048000Y+148000               S0      
317GND              VIA        MD0100PA00X+048000Y+150000               S0      
317GND              VIA        MD0100PA00X+048000Y+152000               S0      
317GND              VIA        MD0100PA00X+048000Y+158000               S0      
317GND              VIA        MD0100PA00X+048000Y+016000               S0      
317GND              VIA        MD0100PA00X+048000Y+166000               S0      
317GND              VIA        MD0100PA00X+048000Y+168000               S0      
317GND              VIA        MD0100PA00X+048000Y+170000               S0      
317GND              VIA        MD0100PA00X+048000Y+172000               S0      
317GND              VIA        MD0100PA00X+048000Y+174000               S0      
317GND              VIA        MD0100PA00X+048000Y+176000               S0      
317GND              VIA        MD0100PA00X+048000Y+178000               S0      
317GND              VIA        MD0100PA00X+048000Y+018000               S0      
317GND              VIA        MD0100PA00X+048000Y+182000               S0      
317GND              VIA        MD0100PA00X+048000Y+186000               S0      
317GND              VIA        MD0100PA00X+048000Y+188000               S0      
317GND              VIA        MD0100PA00X+048000Y+190000               S0      
317GND              VIA        MD0100PA00X+048000Y+192000               S0      
317GND              VIA        MD0100PA00X+048000Y+194000               S0      
317GND              VIA        MD0100PA00X+048000Y+196000               S0      
317GND              VIA        MD0100PA00X+048000Y+198000               S0      
317GND              VIA        MD0100PA00X+048000Y+002000               S0      
317GND              VIA        MD0100PA00X+048000Y+020000               S0      
317GND              VIA        MD0100PA00X+048000Y+022000               S0      
317GND              VIA        MD0100PA00X+048000Y+024000               S0      
317GND              VIA        MD0100PA00X+048000Y+028000               S0      
317GND              VIA        MD0100PA00X+048000Y+030000               S0      
317GND              VIA        MD0100PA00X+048000Y+032000               S0      
317GND              VIA        MD0100PA00X+048000Y+034000               S0      
317GND              VIA        MD0100PA00X+048000Y+036000               S0      
317GND              VIA        MD0100PA00X+048000Y+038000               S0      
317GND              VIA        MD0100PA00X+048000Y+004000               S0      
317GND              VIA        MD0100PA00X+048000Y+040000               S0      
317GND              VIA        MD0100PA00X+048000Y+042000               S0      
317GND              VIA        MD0100PA00X+048000Y+044000               S0      
317GND              VIA        MD0100PA00X+048000Y+046000               S0      
317GND              VIA        MD0100PA00X+048000Y+048000               S0      
317GND              VIA        MD0100PA00X+048000Y+050000               S0      
317GND              VIA        MD0100PA00X+048000Y+056000               S0      
317GND              VIA        MD0100PA00X+048000Y+006000               S0      
317GND              VIA        MD0100PA00X+048000Y+064000               S0      
317GND              VIA        MD0100PA00X+048000Y+066000               S0      
317GND              VIA        MD0100PA00X+048000Y+068000               S0      
317GND              VIA        MD0100PA00X+048000Y+070000               S0      
317GND              VIA        MD0100PA00X+048000Y+072000               S0      
317GND              VIA        MD0100PA00X+048000Y+076000               S0      
317GND              VIA        MD0100PA00X+048000Y+078000               S0      
317GND              VIA        MD0100PA00X+048000Y+008000               S0      
317GND              VIA        MD0100PA00X+048000Y+080000               S0      
317GND              VIA        MD0100PA00X+048000Y+082000               S0      
317GND              VIA        MD0100PA00X+048000Y+084000               S0      
317GND              VIA        MD0100PA00X+048000Y+086000               S0      
317GND              VIA        MD0100PA00X+048000Y+088000               S0      
317GND              VIA        MD0100PA00X+048000Y+090000               S0      
317GND              VIA        MD0100PA00X+048000Y+092000               S0      
317GND              VIA        MD0100PA00X+048000Y+094000               S0      
317GND              VIA        MD0100PA00X+048000Y+096000               S0      
317GND              VIA        MD0100PA00X+048000Y+098000               S0      
317GND              VIA        MD0100PA00X+004882Y+039392               S0      
317GND              VIA        MD0100PA00X+004900Y+063800               S0      
317GND              VIA        MD0100PA00X+049002Y+000550               S0      
317GND              VIA        MD0100PA00X+049256Y+198663               S0      
317GND              VIA        MD0100PA00X+005002Y+000550               S0      
317GND              VIA        MD0100PA00X+050000Y+010000               S0      
317GND              VIA        MD0100PA00X+050000Y+104000               S0      
317GND              VIA        MD0100PA00X+050000Y+106000               S0      
317GND              VIA        MD0100PA00X+050000Y+108000               S0      
317GND              VIA        MD0100PA00X+050000Y+112000               S0      
317GND              VIA        MD0100PA00X+050000Y+116000               S0      
317GND              VIA        MD0100PA00X+050000Y+118000               S0      
317GND              VIA        MD0100PA00X+050000Y+012000               S0      
317GND              VIA        MD0100PA00X+050000Y+120000               S0      
317GND              VIA        MD0100PA00X+050000Y+124000               S0      
317GND              VIA        MD0100PA00X+050000Y+126000               S0      
317GND              VIA        MD0100PA00X+050000Y+128000               S0      
317GND              VIA        MD0100PA00X+050000Y+130000               S0      
317GND              VIA        MD0100PA00X+050000Y+132000               S0      
317GND              VIA        MD0100PA00X+050000Y+134000               S0      
317GND              VIA        MD0100PA00X+050000Y+136000               S0      
317GND              VIA        MD0100PA00X+050000Y+138000               S0      
317GND              VIA        MD0100PA00X+050000Y+014000               S0      
317GND              VIA        MD0100PA00X+050000Y+140000               S0      
317GND              VIA        MD0100PA00X+050000Y+142000               S0      
317GND              VIA        MD0100PA00X+050000Y+144000               S0      
317GND              VIA        MD0100PA00X+050000Y+146000               S0      
317GND              VIA        MD0100PA00X+050000Y+148000               S0      
317GND              VIA        MD0100PA00X+050000Y+150000               S0      
317GND              VIA        MD0100PA00X+050000Y+152000               S0      
317GND              VIA        MD0100PA00X+050000Y+156000               S0      
317GND              VIA        MD0100PA00X+050000Y+016000               S0      
317GND              VIA        MD0100PA00X+050000Y+166000               S0      
317GND              VIA        MD0100PA00X+050000Y+168000               S0      
317GND              VIA        MD0100PA00X+050000Y+170000               S0      
317GND              VIA        MD0100PA00X+050000Y+172000               S0      
317GND              VIA        MD0100PA00X+050000Y+174000               S0      
317GND              VIA        MD0100PA00X+050000Y+176000               S0      
317GND              VIA        MD0100PA00X+050000Y+178000               S0      
317GND              VIA        MD0100PA00X+050000Y+018000               S0      
317GND              VIA        MD0100PA00X+050000Y+182000               S0      
317GND              VIA        MD0100PA00X+050000Y+184000               S0      
317GND              VIA        MD0100PA00X+050000Y+188000               S0      
317GND              VIA        MD0100PA00X+050000Y+190000               S0      
317GND              VIA        MD0100PA00X+050000Y+192000               S0      
317GND              VIA        MD0100PA00X+050000Y+194000               S0      
317GND              VIA        MD0100PA00X+050000Y+196000               S0      
317GND              VIA        MD0100PA00X+050000Y+198000               S0      
317GND              VIA        MD0100PA00X+050000Y+002000               S0      
317GND              VIA        MD0100PA00X+050000Y+020000               S0      
317GND              VIA        MD0100PA00X+050000Y+022000               S0      
317GND              VIA        MD0100PA00X+050000Y+024000               S0      
317GND              VIA        MD0100PA00X+050000Y+026000               S0      
317GND              VIA        MD0100PA00X+050000Y+028000               S0      
317GND              VIA        MD0100PA00X+050000Y+030000               S0      
317GND              VIA        MD0100PA00X+050000Y+032000               S0      
317GND              VIA        MD0100PA00X+050000Y+034000               S0      
317GND              VIA        MD0100PA00X+050000Y+036000               S0      
317GND              VIA        MD0100PA00X+050000Y+004000               S0      
317GND              VIA        MD0100PA00X+050000Y+040000               S0      
317GND              VIA        MD0100PA00X+050000Y+042000               S0      
317GND              VIA        MD0100PA00X+050000Y+044000               S0      
317GND              VIA        MD0100PA00X+050000Y+046000               S0      
317GND              VIA        MD0100PA00X+050000Y+048000               S0      
317GND              VIA        MD0100PA00X+050000Y+050000               S0      
317GND              VIA        MD0100PA00X+050000Y+054000               S0      
317GND              VIA        MD0100PA00X+050000Y+058000               S0      
317GND              VIA        MD0100PA00X+050000Y+006000               S0      
317GND              VIA        MD0100PA00X+050000Y+060000               S0      
317GND              VIA        MD0100PA00X+050000Y+064000               S0      
317GND              VIA        MD0100PA00X+050000Y+066000               S0      
317GND              VIA        MD0100PA00X+050000Y+068000               S0      
317GND              VIA        MD0100PA00X+050000Y+070000               S0      
317GND              VIA        MD0100PA00X+050000Y+072000               S0      
317GND              VIA        MD0100PA00X+050000Y+076000               S0      
317GND              VIA        MD0100PA00X+050000Y+078000               S0      
317GND              VIA        MD0100PA00X+050000Y+008000               S0      
317GND              VIA        MD0100PA00X+050000Y+080000               S0      
317GND              VIA        MD0100PA00X+050000Y+082000               S0      
317GND              VIA        MD0100PA00X+050000Y+084000               S0      
317GND              VIA        MD0100PA00X+050000Y+086000               S0      
317GND              VIA        MD0100PA00X+050000Y+088000               S0      
317GND              VIA        MD0100PA00X+050000Y+090000               S0      
317GND              VIA        MD0100PA00X+050000Y+092000               S0      
317GND              VIA        MD0100PA00X+050000Y+094000               S0      
317GND              VIA        MD0100PA00X+050000Y+096000               S0      
317GND              VIA        MD0100PA00X+050000Y+098000               S0      
317GND              VIA        MD0100PA00X+005100Y+091350               S0      
317GND              VIA        MD0100PA00X+051002Y+000550               S0      
317GND              VIA        MD0100PA00X+051256Y+198663               S0      
317GND              VIA        MD0100PA00X+005150Y+046900               S0      
317GND              VIA        MD0100PA00X+005150Y+073050               S0      
317GND              VIA        MD0100PA00X+005150Y+075750               S0      
317GND              VIA        MD0100PA00X+005200Y+188750               S0      
317GND              VIA        MD0100PA00X+052000Y+010000               S0      
317GND              VIA        MD0100PA00X+052000Y+104000               S0      
317GND              VIA        MD0100PA00X+052000Y+106000               S0      
317GND              VIA        MD0100PA00X+052000Y+108000               S0      
317GND              VIA        MD0100PA00X+052000Y+112000               S0      
317GND              VIA        MD0100PA00X+052000Y+116000               S0      
317GND              VIA        MD0100PA00X+052000Y+118000               S0      
317GND              VIA        MD0100PA00X+052000Y+012000               S0      
317GND              VIA        MD0100PA00X+052000Y+120000               S0      
317GND              VIA        MD0100PA00X+052000Y+126000               S0      
317GND              VIA        MD0100PA00X+052000Y+128000               S0      
317GND              VIA        MD0100PA00X+052000Y+130000               S0      
317GND              VIA        MD0100PA00X+052000Y+132000               S0      
317GND              VIA        MD0100PA00X+052000Y+134000               S0      
317GND              VIA        MD0100PA00X+052000Y+136000               S0      
317GND              VIA        MD0100PA00X+052000Y+138000               S0      
317GND              VIA        MD0100PA00X+052000Y+014000               S0      
317GND              VIA        MD0100PA00X+052000Y+140000               S0      
317GND              VIA        MD0100PA00X+052000Y+142000               S0      
317GND              VIA        MD0100PA00X+052000Y+144000               S0      
317GND              VIA        MD0100PA00X+052000Y+146000               S0      
317GND              VIA        MD0100PA00X+052000Y+148000               S0      
317GND              VIA        MD0100PA00X+052000Y+150000               S0      
317GND              VIA        MD0100PA00X+052000Y+152000               S0      
317GND              VIA        MD0100PA00X+052000Y+016000               S0      
317GND              VIA        MD0100PA00X+052000Y+166000               S0      
317GND              VIA        MD0100PA00X+052000Y+168000               S0      
317GND              VIA        MD0100PA00X+052000Y+170000               S0      
317GND              VIA        MD0100PA00X+052000Y+172000               S0      
317GND              VIA        MD0100PA00X+052000Y+174000               S0      
317GND              VIA        MD0100PA00X+052000Y+176000               S0      
317GND              VIA        MD0100PA00X+052000Y+178000               S0      
317GND              VIA        MD0100PA00X+052000Y+018000               S0      
317GND              VIA        MD0100PA00X+052000Y+182000               S0      
317GND              VIA        MD0100PA00X+052000Y+184000               S0      
317GND              VIA        MD0100PA00X+052000Y+186000               S0      
317GND              VIA        MD0100PA00X+052000Y+188000               S0      
317GND              VIA        MD0100PA00X+052000Y+190000               S0      
317GND              VIA        MD0100PA00X+052000Y+192000               S0      
317GND              VIA        MD0100PA00X+052000Y+194000               S0      
317GND              VIA        MD0100PA00X+052000Y+196000               S0      
317GND              VIA        MD0100PA00X+052000Y+198000               S0      
317GND              VIA        MD0100PA00X+052000Y+002000               S0      
317GND              VIA        MD0100PA00X+052000Y+020000               S0      
317GND              VIA        MD0100PA00X+052000Y+022000               S0      
317GND              VIA        MD0100PA00X+052000Y+024000               S0      
317GND              VIA        MD0100PA00X+052000Y+026000               S0      
317GND              VIA        MD0100PA00X+052000Y+028000               S0      
317GND              VIA        MD0100PA00X+052000Y+030000               S0      
317GND              VIA        MD0100PA00X+052000Y+032000               S0      
317GND              VIA        MD0100PA00X+052000Y+034000               S0      
317GND              VIA        MD0100PA00X+052000Y+036000               S0      
317GND              VIA        MD0100PA00X+052000Y+038000               S0      
317GND              VIA        MD0100PA00X+052000Y+004000               S0      
317GND              VIA        MD0100PA00X+052000Y+040000               S0      
317GND              VIA        MD0100PA00X+052000Y+042000               S0      
317GND              VIA        MD0100PA00X+052000Y+044000               S0      
317GND              VIA        MD0100PA00X+052000Y+046000               S0      
317GND              VIA        MD0100PA00X+052000Y+048000               S0      
317GND              VIA        MD0100PA00X+052000Y+052000               S0      
317GND              VIA        MD0100PA00X+052000Y+056000               S0      
317GND              VIA        MD0100PA00X+052000Y+058000               S0      
317GND              VIA        MD0100PA00X+052000Y+006000               S0      
317GND              VIA        MD0100PA00X+052000Y+060000               S0      
317GND              VIA        MD0100PA00X+052000Y+064000               S0      
317GND              VIA        MD0100PA00X+052000Y+066000               S0      
317GND              VIA        MD0100PA00X+052000Y+068000               S0      
317GND              VIA        MD0100PA00X+052000Y+070000               S0      
317GND              VIA        MD0100PA00X+052000Y+072000               S0      
317GND              VIA        MD0100PA00X+052000Y+076000               S0      
317GND              VIA        MD0100PA00X+052000Y+078000               S0      
317GND              VIA        MD0100PA00X+052000Y+008000               S0      
317GND              VIA        MD0100PA00X+052000Y+080000               S0      
317GND              VIA        MD0100PA00X+052000Y+082000               S0      
317GND              VIA        MD0100PA00X+052000Y+084000               S0      
317GND              VIA        MD0100PA00X+052000Y+086000               S0      
317GND              VIA        MD0100PA00X+052000Y+088000               S0      
317GND              VIA        MD0100PA00X+052000Y+090000               S0      
317GND              VIA        MD0100PA00X+052000Y+092000               S0      
317GND              VIA        MD0100PA00X+052000Y+094000               S0      
317GND              VIA        MD0100PA00X+052000Y+096000               S0      
317GND              VIA        MD0100PA00X+052000Y+098000               S0      
317GND              VIA        MD0100PA00X+005256Y+198663               S0      
317GND              VIA        MD0100PA00X+053002Y+000550               S0      
317GND              VIA        MD0100PA00X+053256Y+198663               S0      
317GND              VIA        MD0100PA00X+054000Y+010000               S0      
317GND              VIA        MD0100PA00X+054000Y+104000               S0      
317GND              VIA        MD0100PA00X+054000Y+106000               S0      
317GND              VIA        MD0100PA00X+054000Y+110000               S0      
317GND              VIA        MD0100PA00X+054000Y+112000               S0      
317GND              VIA        MD0100PA00X+054000Y+116000               S0      
317GND              VIA        MD0100PA00X+054000Y+118000               S0      
317GND              VIA        MD0100PA00X+054000Y+012000               S0      
317GND              VIA        MD0100PA00X+054000Y+120000               S0      
317GND              VIA        MD0100PA00X+054000Y+122000               S0      
317GND              VIA        MD0100PA00X+054000Y+128000               S0      
317GND              VIA        MD0100PA00X+054000Y+130000               S0      
317GND              VIA        MD0100PA00X+054000Y+132000               S0      
317GND              VIA        MD0100PA00X+054000Y+134000               S0      
317GND              VIA        MD0100PA00X+054000Y+136000               S0      
317GND              VIA        MD0100PA00X+054000Y+138000               S0      
317GND              VIA        MD0100PA00X+054000Y+014000               S0      
317GND              VIA        MD0100PA00X+054000Y+140000               S0      
317GND              VIA        MD0100PA00X+054000Y+142000               S0      
317GND              VIA        MD0100PA00X+054000Y+144000               S0      
317GND              VIA        MD0100PA00X+054000Y+146000               S0      
317GND              VIA        MD0100PA00X+054000Y+148000               S0      
317GND              VIA        MD0100PA00X+054000Y+150000               S0      
317GND              VIA        MD0100PA00X+054000Y+152000               S0      
317GND              VIA        MD0100PA00X+054000Y+016000               S0      
317GND              VIA        MD0100PA00X+054000Y+166000               S0      
317GND              VIA        MD0100PA00X+054000Y+168000               S0      
317GND              VIA        MD0100PA00X+054000Y+170000               S0      
317GND              VIA        MD0100PA00X+054000Y+172000               S0      
317GND              VIA        MD0100PA00X+054000Y+174000               S0      
317GND              VIA        MD0100PA00X+054000Y+176000               S0      
317GND              VIA        MD0100PA00X+054000Y+178000               S0      
317GND              VIA        MD0100PA00X+054000Y+018000               S0      
317GND              VIA        MD0100PA00X+054000Y+182000               S0      
317GND              VIA        MD0100PA00X+054000Y+184000               S0      
317GND              VIA        MD0100PA00X+054000Y+186000               S0      
317GND              VIA        MD0100PA00X+054000Y+188000               S0      
317GND              VIA        MD0100PA00X+054000Y+190000               S0      
317GND              VIA        MD0100PA00X+054000Y+192000               S0      
317GND              VIA        MD0100PA00X+054000Y+194000               S0      
317GND              VIA        MD0100PA00X+054000Y+196000               S0      
317GND              VIA        MD0100PA00X+054000Y+198000               S0      
317GND              VIA        MD0100PA00X+054000Y+002000               S0      
317GND              VIA        MD0100PA00X+054000Y+020000               S0      
317GND              VIA        MD0100PA00X+054000Y+022000               S0      
317GND              VIA        MD0100PA00X+054000Y+024000               S0      
317GND              VIA        MD0100PA00X+054000Y+026000               S0      
317GND              VIA        MD0100PA00X+054000Y+028000               S0      
317GND              VIA        MD0100PA00X+054000Y+030000               S0      
317GND              VIA        MD0100PA00X+054000Y+032000               S0      
317GND              VIA        MD0100PA00X+054000Y+034000               S0      
317GND              VIA        MD0100PA00X+054000Y+036000               S0      
317GND              VIA        MD0100PA00X+054000Y+038000               S0      
317GND              VIA        MD0100PA00X+054000Y+004000               S0      
317GND              VIA        MD0100PA00X+054000Y+040000               S0      
317GND              VIA        MD0100PA00X+054000Y+042000               S0      
317GND              VIA        MD0100PA00X+054000Y+044000               S0      
317GND              VIA        MD0100PA00X+054000Y+046000               S0      
317GND              VIA        MD0100PA00X+054000Y+054000               S0      
317GND              VIA        MD0100PA00X+054000Y+056000               S0      
317GND              VIA        MD0100PA00X+054000Y+058000               S0      
317GND              VIA        MD0100PA00X+054000Y+006000               S0      
317GND              VIA        MD0100PA00X+054000Y+060000               S0      
317GND              VIA        MD0100PA00X+054000Y+064000               S0      
317GND              VIA        MD0100PA00X+054000Y+066000               S0      
317GND              VIA        MD0100PA00X+054000Y+068000               S0      
317GND              VIA        MD0100PA00X+054000Y+070000               S0      
317GND              VIA        MD0100PA00X+054000Y+074000               S0      
317GND              VIA        MD0100PA00X+054000Y+076000               S0      
317GND              VIA        MD0100PA00X+054000Y+078000               S0      
317GND              VIA        MD0100PA00X+054000Y+008000               S0      
317GND              VIA        MD0100PA00X+054000Y+080000               S0      
317GND              VIA        MD0100PA00X+054000Y+082000               S0      
317GND              VIA        MD0100PA00X+054000Y+084000               S0      
317GND              VIA        MD0100PA00X+054000Y+086000               S0      
317GND              VIA        MD0100PA00X+054000Y+088000               S0      
317GND              VIA        MD0100PA00X+054000Y+090000               S0      
317GND              VIA        MD0100PA00X+054000Y+092000               S0      
317GND              VIA        MD0100PA00X+054000Y+094000               S0      
317GND              VIA        MD0100PA00X+054000Y+096000               S0      
317GND              VIA        MD0100PA00X+054000Y+098000               S0      
317GND              VIA        MD0100PA00X+000550Y+100030               S0      
317GND              VIA        MD0100PA00X+000550Y+010098               S0      
317GND              VIA        MD0100PA00X+000550Y+102030               S0      
317GND              VIA        MD0100PA00X+000550Y+104030               S0      
317GND              VIA        MD0100PA00X+000550Y+012098               S0      
317GND              VIA        MD0100PA00X+000550Y+014098               S0      
317GND              VIA        MD0100PA00X+000550Y+016098               S0      
317GND              VIA        MD0100PA00X+000550Y+018098               S0      
317GND              VIA        MD0100PA00X+000550Y+188069               S0      
317GND              VIA        MD0100PA00X+000550Y+188869               S0      
317GND              VIA        MD0100PA00X+000550Y+195369               S0      
317GND              VIA        MD0100PA00X+000550Y+197369               S0      
317GND              VIA        MD0100PA00X+000550Y+020098               S0      
317GND              VIA        MD0100PA00X+000550Y+002098               S0      
317GND              VIA        MD0100PA00X+000550Y+022098               S0      
317GND              VIA        MD0100PA00X+000550Y+024098               S0      
317GND              VIA        MD0100PA00X+000550Y+026098               S0      
317GND              VIA        MD0100PA00X+000550Y+028098               S0      
317GND              VIA        MD0100PA00X+000550Y+030098               S0      
317GND              VIA        MD0100PA00X+000550Y+032098               S0      
317GND              VIA        MD0100PA00X+000550Y+034098               S0      
317GND              VIA        MD0100PA00X+000550Y+036098               S0      
317GND              VIA        MD0100PA00X+000550Y+038098               S0      
317GND              VIA        MD0100PA00X+000550Y+040098               S0      
317GND              VIA        MD0100PA00X+000550Y+004098               S0      
317GND              VIA        MD0100PA00X+000550Y+042098               S0      
317GND              VIA        MD0100PA00X+000550Y+044098               S0      
317GND              VIA        MD0100PA00X+000550Y+046098               S0      
317GND              VIA        MD0100PA00X+000550Y+048098               S0      
317GND              VIA        MD0100PA00X+000550Y+050098               S0      
317GND              VIA        MD0100PA00X+000550Y+052098               S0      
317GND              VIA        MD0100PA00X+000550Y+054098               S0      
317GND              VIA        MD0100PA00X+000550Y+006098               S0      
317GND              VIA        MD0100PA00X+000550Y+008098               S0      
317GND              VIA        MD0100PA00X+000550Y+098030               S0      
317GND              VIA        MD0100PA00X+055002Y+000550               S0      
317GND              VIA        MD0100PA00X+055256Y+198663               S0      
317GND              VIA        MD0100PA00X+056000Y+010000               S0      
317GND              VIA        MD0100PA00X+056000Y+104000               S0      
317GND              VIA        MD0100PA00X+056000Y+106000               S0      
317GND              VIA        MD0100PA00X+056000Y+110000               S0      
317GND              VIA        MD0100PA00X+056000Y+112000               S0      
317GND              VIA        MD0100PA00X+056000Y+118000               S0      
317GND              VIA        MD0100PA00X+056000Y+012000               S0      
317GND              VIA        MD0100PA00X+056000Y+120000               S0      
317GND              VIA        MD0100PA00X+056000Y+122000               S0      
317GND              VIA        MD0100PA00X+056000Y+124000               S0      
317GND              VIA        MD0100PA00X+056000Y+130000               S0      
317GND              VIA        MD0100PA00X+056000Y+132000               S0      
317GND              VIA        MD0100PA00X+056000Y+134000               S0      
317GND              VIA        MD0100PA00X+056000Y+138000               S0      
317GND              VIA        MD0100PA00X+056000Y+014000               S0      
317GND              VIA        MD0100PA00X+056000Y+140000               S0      
317GND              VIA        MD0100PA00X+056000Y+142000               S0      
317GND              VIA        MD0100PA00X+056000Y+144000               S0      
317GND              VIA        MD0100PA00X+056000Y+146000               S0      
317GND              VIA        MD0100PA00X+056000Y+148000               S0      
317GND              VIA        MD0100PA00X+056000Y+150000               S0      
317GND              VIA        MD0100PA00X+056000Y+152000               S0      
317GND              VIA        MD0100PA00X+056000Y+016000               S0      
317GND              VIA        MD0100PA00X+056000Y+166000               S0      
317GND              VIA        MD0100PA00X+056000Y+168000               S0      
317GND              VIA        MD0100PA00X+056000Y+170000               S0      
317GND              VIA        MD0100PA00X+056000Y+172000               S0      
317GND              VIA        MD0100PA00X+056000Y+174000               S0      
317GND              VIA        MD0100PA00X+056000Y+176000               S0      
317GND              VIA        MD0100PA00X+056000Y+178000               S0      
317GND              VIA        MD0100PA00X+056000Y+018000               S0      
317GND              VIA        MD0100PA00X+056000Y+180000               S0      
317GND              VIA        MD0100PA00X+056000Y+184000               S0      
317GND              VIA        MD0100PA00X+056000Y+186000               S0      
317GND              VIA        MD0100PA00X+056000Y+188000               S0      
317GND              VIA        MD0100PA00X+056000Y+190000               S0      
317GND              VIA        MD0100PA00X+056000Y+192000               S0      
317GND              VIA        MD0100PA00X+056000Y+194000               S0      
317GND              VIA        MD0100PA00X+056000Y+196000               S0      
317GND              VIA        MD0100PA00X+056000Y+198000               S0      
317GND              VIA        MD0100PA00X+056000Y+002000               S0      
317GND              VIA        MD0100PA00X+056000Y+020000               S0      
317GND              VIA        MD0100PA00X+056000Y+022000               S0      
317GND              VIA        MD0100PA00X+056000Y+024000               S0      
317GND              VIA        MD0100PA00X+056000Y+026000               S0      
317GND              VIA        MD0100PA00X+056000Y+028000               S0      
317GND              VIA        MD0100PA00X+056000Y+030000               S0      
317GND              VIA        MD0100PA00X+056000Y+032000               S0      
317GND              VIA        MD0100PA00X+056000Y+034000               S0      
317GND              VIA        MD0100PA00X+056000Y+036000               S0      
317GND              VIA        MD0100PA00X+056000Y+038000               S0      
317GND              VIA        MD0100PA00X+056000Y+004000               S0      
317GND              VIA        MD0100PA00X+056000Y+040000               S0      
317GND              VIA        MD0100PA00X+056000Y+042000               S0      
317GND              VIA        MD0100PA00X+056000Y+044000               S0      
317GND              VIA        MD0100PA00X+056000Y+046000               S0      
317GND              VIA        MD0100PA00X+056000Y+054000               S0      
317GND              VIA        MD0100PA00X+056000Y+056000               S0      
317GND              VIA        MD0100PA00X+056000Y+058000               S0      
317GND              VIA        MD0100PA00X+056000Y+006000               S0      
317GND              VIA        MD0100PA00X+056000Y+064000               S0      
317GND              VIA        MD0100PA00X+056000Y+066000               S0      
317GND              VIA        MD0100PA00X+056000Y+068000               S0      
317GND              VIA        MD0100PA00X+056000Y+070000               S0      
317GND              VIA        MD0100PA00X+056000Y+074000               S0      
317GND              VIA        MD0100PA00X+056000Y+076000               S0      
317GND              VIA        MD0100PA00X+056000Y+078000               S0      
317GND              VIA        MD0100PA00X+056000Y+008000               S0      
317GND              VIA        MD0100PA00X+056000Y+080000               S0      
317GND              VIA        MD0100PA00X+056000Y+084000               S0      
317GND              VIA        MD0100PA00X+056000Y+086000               S0      
317GND              VIA        MD0100PA00X+056000Y+088000               S0      
317GND              VIA        MD0100PA00X+056000Y+090000               S0      
317GND              VIA        MD0100PA00X+056000Y+092000               S0      
317GND              VIA        MD0100PA00X+056000Y+094000               S0      
317GND              VIA        MD0100PA00X+056000Y+096000               S0      
317GND              VIA        MD0100PA00X+056000Y+098000               S0      
317GND              VIA        MD0100PA00X+005688Y+195425               S0      
317GND              VIA        MD0100PA00X+057002Y+000550               S0      
317GND              VIA        MD0100PA00X+057256Y+198663               S0      
317GND              VIA        MD0100PA00X+058000Y+010000               S0      
317GND              VIA        MD0100PA00X+058000Y+104000               S0      
317GND              VIA        MD0100PA00X+058000Y+106000               S0      
317GND              VIA        MD0100PA00X+058000Y+110000               S0      
317GND              VIA        MD0100PA00X+058000Y+112000               S0      
317GND              VIA        MD0100PA00X+058000Y+116000               S0      
317GND              VIA        MD0100PA00X+058000Y+118000               S0      
317GND              VIA        MD0100PA00X+058000Y+012000               S0      
317GND              VIA        MD0100PA00X+058000Y+120000               S0      
317GND              VIA        MD0100PA00X+058000Y+122000               S0      
317GND              VIA        MD0100PA00X+058000Y+124000               S0      
317GND              VIA        MD0100PA00X+058000Y+126000               S0      
317GND              VIA        MD0100PA00X+058000Y+132000               S0      
317GND              VIA        MD0100PA00X+058000Y+134000               S0      
317GND              VIA        MD0100PA00X+058000Y+136000               S0      
317GND              VIA        MD0100PA00X+058000Y+138000               S0      
317GND              VIA        MD0100PA00X+058000Y+014000               S0      
317GND              VIA        MD0100PA00X+058000Y+140000               S0      
317GND              VIA        MD0100PA00X+058000Y+142000               S0      
317GND              VIA        MD0100PA00X+058000Y+144000               S0      
317GND              VIA        MD0100PA00X+058000Y+146000               S0      
317GND              VIA        MD0100PA00X+058000Y+148000               S0      
317GND              VIA        MD0100PA00X+058000Y+150000               S0      
317GND              VIA        MD0100PA00X+058000Y+152000               S0      
317GND              VIA        MD0100PA00X+058000Y+016000               S0      
317GND              VIA        MD0100PA00X+058000Y+166000               S0      
317GND              VIA        MD0100PA00X+058000Y+168000               S0      
317GND              VIA        MD0100PA00X+058000Y+170000               S0      
317GND              VIA        MD0100PA00X+058000Y+172000               S0      
317GND              VIA        MD0100PA00X+058000Y+174000               S0      
317GND              VIA        MD0100PA00X+058000Y+176000               S0      
317GND              VIA        MD0100PA00X+058000Y+178000               S0      
317GND              VIA        MD0100PA00X+058000Y+018000               S0      
317GND              VIA        MD0100PA00X+058000Y+180000               S0      
317GND              VIA        MD0100PA00X+058000Y+184000               S0      
317GND              VIA        MD0100PA00X+058000Y+186000               S0      
317GND              VIA        MD0100PA00X+058000Y+188000               S0      
317GND              VIA        MD0100PA00X+058000Y+190000               S0      
317GND              VIA        MD0100PA00X+058000Y+192000               S0      
317GND              VIA        MD0100PA00X+058000Y+194000               S0      
317GND              VIA        MD0100PA00X+058000Y+196000               S0      
317GND              VIA        MD0100PA00X+058000Y+198000               S0      
317GND              VIA        MD0100PA00X+058000Y+002000               S0      
317GND              VIA        MD0100PA00X+058000Y+020000               S0      
317GND              VIA        MD0100PA00X+058000Y+022000               S0      
317GND              VIA        MD0100PA00X+058000Y+024000               S0      
317GND              VIA        MD0100PA00X+058000Y+026000               S0      
317GND              VIA        MD0100PA00X+058000Y+028000               S0      
317GND              VIA        MD0100PA00X+058000Y+030000               S0      
317GND              VIA        MD0100PA00X+058000Y+032000               S0      
317GND              VIA        MD0100PA00X+058000Y+034000               S0      
317GND              VIA        MD0100PA00X+058000Y+036000               S0      
317GND              VIA        MD0100PA00X+058000Y+038000               S0      
317GND              VIA        MD0100PA00X+058000Y+004000               S0      
317GND              VIA        MD0100PA00X+058000Y+040000               S0      
317GND              VIA        MD0100PA00X+058000Y+042000               S0      
317GND              VIA        MD0100PA00X+058000Y+044000               S0      
317GND              VIA        MD0100PA00X+058000Y+050000               S0      
317GND              VIA        MD0100PA00X+058000Y+052000               S0      
317GND              VIA        MD0100PA00X+058000Y+054000               S0      
317GND              VIA        MD0100PA00X+058000Y+056000               S0      
317GND              VIA        MD0100PA00X+058000Y+058000               S0      
317GND              VIA        MD0100PA00X+058000Y+006000               S0      
317GND              VIA        MD0100PA00X+058000Y+060000               S0      
317GND              VIA        MD0100PA00X+058000Y+064000               S0      
317GND              VIA        MD0100PA00X+058000Y+066000               S0      
317GND              VIA        MD0100PA00X+058000Y+068000               S0      
317GND              VIA        MD0100PA00X+058000Y+070000               S0      
317GND              VIA        MD0100PA00X+058000Y+074000               S0      
317GND              VIA        MD0100PA00X+058000Y+076000               S0      
317GND              VIA        MD0100PA00X+058000Y+078000               S0      
317GND              VIA        MD0100PA00X+058000Y+008000               S0      
317GND              VIA        MD0100PA00X+058000Y+080000               S0      
317GND              VIA        MD0100PA00X+058000Y+082000               S0      
317GND              VIA        MD0100PA00X+058000Y+084000               S0      
317GND              VIA        MD0100PA00X+058000Y+086000               S0      
317GND              VIA        MD0100PA00X+058000Y+088000               S0      
317GND              VIA        MD0100PA00X+058000Y+090000               S0      
317GND              VIA        MD0100PA00X+058000Y+092000               S0      
317GND              VIA        MD0100PA00X+058000Y+094000               S0      
317GND              VIA        MD0100PA00X+058000Y+096000               S0      
317GND              VIA        MD0100PA00X+058000Y+098000               S0      
317GND              VIA        MD0100PA00X+005850Y+132050               S0      
317GND              VIA        MD0100PA00X+005900Y+065950               S0      
317GND              VIA        MD0100PA00X+059002Y+000550               S0      
317GND              VIA        MD0100PA00X+059256Y+198663               S0      
317GND              VIA        MD0100PA00X+006000Y+190000               S0      
317GND              VIA        MD0100PA00X+006000Y+192000               S0      
317GND              VIA        MD0100PA00X+006000Y+192800               S0      
317GND              VIA        MD0100PA00X+006000Y+008000               S0      
317GND              VIA        MD0100PA00X+060000Y+010000               S0      
317GND              VIA        MD0100PA00X+060000Y+104000               S0      
317GND              VIA        MD0100PA00X+060000Y+106000               S0      
317GND              VIA        MD0100PA00X+060000Y+110000               S0      
317GND              VIA        MD0100PA00X+060000Y+112000               S0      
317GND              VIA        MD0100PA00X+060000Y+116000               S0      
317GND              VIA        MD0100PA00X+060000Y+118000               S0      
317GND              VIA        MD0100PA00X+060000Y+012000               S0      
317GND              VIA        MD0100PA00X+060000Y+120000               S0      
317GND              VIA        MD0100PA00X+060000Y+122000               S0      
317GND              VIA        MD0100PA00X+060000Y+124000               S0      
317GND              VIA        MD0100PA00X+060000Y+126000               S0      
317GND              VIA        MD0100PA00X+060000Y+134000               S0      
317GND              VIA        MD0100PA00X+060000Y+136000               S0      
317GND              VIA        MD0100PA00X+060000Y+014000               S0      
317GND              VIA        MD0100PA00X+060000Y+140000               S0      
317GND              VIA        MD0100PA00X+060000Y+142000               S0      
317GND              VIA        MD0100PA00X+060000Y+144000               S0      
317GND              VIA        MD0100PA00X+060000Y+146000               S0      
317GND              VIA        MD0100PA00X+060000Y+148000               S0      
317GND              VIA        MD0100PA00X+060000Y+150000               S0      
317GND              VIA        MD0100PA00X+060000Y+016000               S0      
317GND              VIA        MD0100PA00X+060000Y+166000               S0      
317GND              VIA        MD0100PA00X+060000Y+168000               S0      
317GND              VIA        MD0100PA00X+060000Y+170000               S0      
317GND              VIA        MD0100PA00X+060000Y+172000               S0      
317GND              VIA        MD0100PA00X+060000Y+174000               S0      
317GND              VIA        MD0100PA00X+060000Y+176000               S0      
317GND              VIA        MD0100PA00X+060000Y+178000               S0      
317GND              VIA        MD0100PA00X+060000Y+018000               S0      
317GND              VIA        MD0100PA00X+060000Y+180000               S0      
317GND              VIA        MD0100PA00X+060000Y+184000               S0      
317GND              VIA        MD0100PA00X+060000Y+186000               S0      
317GND              VIA        MD0100PA00X+060000Y+188000               S0      
317GND              VIA        MD0100PA00X+060000Y+190000               S0      
317GND              VIA        MD0100PA00X+060000Y+192000               S0      
317GND              VIA        MD0100PA00X+060000Y+194000               S0      
317GND              VIA        MD0100PA00X+060000Y+196000               S0      
317GND              VIA        MD0100PA00X+060000Y+198000               S0      
317GND              VIA        MD0100PA00X+060000Y+002000               S0      
317GND              VIA        MD0100PA00X+060000Y+020000               S0      
317GND              VIA        MD0100PA00X+060000Y+022000               S0      
317GND              VIA        MD0100PA00X+060000Y+024000               S0      
317GND              VIA        MD0100PA00X+060000Y+026000               S0      
317GND              VIA        MD0100PA00X+060000Y+028000               S0      
317GND              VIA        MD0100PA00X+060000Y+030000               S0      
317GND              VIA        MD0100PA00X+060000Y+032000               S0      
317GND              VIA        MD0100PA00X+060000Y+034000               S0      
317GND              VIA        MD0100PA00X+060000Y+036000               S0      
317GND              VIA        MD0100PA00X+060000Y+038000               S0      
317GND              VIA        MD0100PA00X+060000Y+004000               S0      
317GND              VIA        MD0100PA00X+060000Y+040000               S0      
317GND              VIA        MD0100PA00X+060000Y+042000               S0      
317GND              VIA        MD0100PA00X+060000Y+048000               S0      
317GND              VIA        MD0100PA00X+060000Y+050000               S0      
317GND              VIA        MD0100PA00X+060000Y+052000               S0      
317GND              VIA        MD0100PA00X+060000Y+054000               S0      
317GND              VIA        MD0100PA00X+060000Y+056000               S0      
317GND              VIA        MD0100PA00X+060000Y+058000               S0      
317GND              VIA        MD0100PA00X+060000Y+006000               S0      
317GND              VIA        MD0100PA00X+060000Y+060000               S0      
317GND              VIA        MD0100PA00X+060000Y+064000               S0      
317GND              VIA        MD0100PA00X+060000Y+066000               S0      
317GND              VIA        MD0100PA00X+060000Y+068000               S0      
317GND              VIA        MD0100PA00X+060000Y+070000               S0      
317GND              VIA        MD0100PA00X+060000Y+074000               S0      
317GND              VIA        MD0100PA00X+060000Y+076000               S0      
317GND              VIA        MD0100PA00X+060000Y+078000               S0      
317GND              VIA        MD0100PA00X+060000Y+008000               S0      
317GND              VIA        MD0100PA00X+060000Y+080000               S0      
317GND              VIA        MD0100PA00X+060000Y+082000               S0      
317GND              VIA        MD0100PA00X+060000Y+084000               S0      
317GND              VIA        MD0100PA00X+060000Y+086000               S0      
317GND              VIA        MD0100PA00X+060000Y+088000               S0      
317GND              VIA        MD0100PA00X+060000Y+090000               S0      
317GND              VIA        MD0100PA00X+060000Y+092000               S0      
317GND              VIA        MD0100PA00X+060000Y+094000               S0      
317GND              VIA        MD0100PA00X+060000Y+096000               S0      
317GND              VIA        MD0100PA00X+060000Y+098000               S0      
317GND              VIA        MD0100PA00X+061002Y+000550               S0      
317GND              VIA        MD0100PA00X+006110Y+060010               S0      
317GND              VIA        MD0100PA00X+061256Y+198663               S0      
317GND              VIA        MD0100PA00X+006150Y+068250               S0      
317GND              VIA        MD0100PA00X+006150Y+074800               S0      
317GND              VIA        MD0100PA00X+006190Y+058430               S0      
317GND              VIA        MD0100PA00X+006200Y+073650               S0      
317GND              VIA        MD0100PA00X+062000Y+010000               S0      
317GND              VIA        MD0100PA00X+062000Y+104000               S0      
317GND              VIA        MD0100PA00X+062000Y+106000               S0      
317GND              VIA        MD0100PA00X+062000Y+110000               S0      
317GND              VIA        MD0100PA00X+062000Y+112000               S0      
317GND              VIA        MD0100PA00X+062000Y+116000               S0      
317GND              VIA        MD0100PA00X+062000Y+118000               S0      
317GND              VIA        MD0100PA00X+062000Y+012000               S0      
317GND              VIA        MD0100PA00X+062000Y+120000               S0      
317GND              VIA        MD0100PA00X+062000Y+122000               S0      
317GND              VIA        MD0100PA00X+062000Y+124000               S0      
317GND              VIA        MD0100PA00X+062000Y+126000               S0      
317GND              VIA        MD0100PA00X+062000Y+128000               S0      
317GND              VIA        MD0100PA00X+062000Y+130000               S0      
317GND              VIA        MD0100PA00X+062000Y+136000               S0      
317GND              VIA        MD0100PA00X+062000Y+138000               S0      
317GND              VIA        MD0100PA00X+062000Y+014000               S0      
317GND              VIA        MD0100PA00X+062000Y+140000               S0      
317GND              VIA        MD0100PA00X+062000Y+142000               S0      
317GND              VIA        MD0100PA00X+062000Y+144000               S0      
317GND              VIA        MD0100PA00X+062000Y+146000               S0      
317GND              VIA        MD0100PA00X+062000Y+148000               S0      
317GND              VIA        MD0100PA00X+062000Y+150000               S0      
317GND              VIA        MD0100PA00X+062000Y+016000               S0      
317GND              VIA        MD0100PA00X+062000Y+166000               S0      
317GND              VIA        MD0100PA00X+062000Y+168000               S0      
317GND              VIA        MD0100PA00X+062000Y+170000               S0      
317GND              VIA        MD0100PA00X+062000Y+172000               S0      
317GND              VIA        MD0100PA00X+062000Y+174000               S0      
317GND              VIA        MD0100PA00X+062000Y+176000               S0      
317GND              VIA        MD0100PA00X+062000Y+178000               S0      
317GND              VIA        MD0100PA00X+062000Y+018000               S0      
317GND              VIA        MD0100PA00X+062000Y+180000               S0      
317GND              VIA        MD0100PA00X+062000Y+184000               S0      
317GND              VIA        MD0100PA00X+062000Y+186000               S0      
317GND              VIA        MD0100PA00X+062000Y+188000               S0      
317GND              VIA        MD0100PA00X+062000Y+190000               S0      
317GND              VIA        MD0100PA00X+062000Y+192000               S0      
317GND              VIA        MD0100PA00X+062000Y+194000               S0      
317GND              VIA        MD0100PA00X+062000Y+196000               S0      
317GND              VIA        MD0100PA00X+062000Y+198000               S0      
317GND              VIA        MD0100PA00X+062000Y+002000               S0      
317GND              VIA        MD0100PA00X+062000Y+020000               S0      
317GND              VIA        MD0100PA00X+062000Y+022000               S0      
317GND              VIA        MD0100PA00X+062000Y+024000               S0      
317GND              VIA        MD0100PA00X+062000Y+026000               S0      
317GND              VIA        MD0100PA00X+062000Y+028000               S0      
317GND              VIA        MD0100PA00X+062000Y+030000               S0      
317GND              VIA        MD0100PA00X+062000Y+032000               S0      
317GND              VIA        MD0100PA00X+062000Y+034000               S0      
317GND              VIA        MD0100PA00X+062000Y+036000               S0      
317GND              VIA        MD0100PA00X+062000Y+038000               S0      
317GND              VIA        MD0100PA00X+062000Y+004000               S0      
317GND              VIA        MD0100PA00X+062000Y+040000               S0      
317GND              VIA        MD0100PA00X+062000Y+042000               S0      
317GND              VIA        MD0100PA00X+062000Y+046000               S0      
317GND              VIA        MD0100PA00X+062000Y+048000               S0      
317GND              VIA        MD0100PA00X+062000Y+050000               S0      
317GND              VIA        MD0100PA00X+062000Y+052000               S0      
317GND              VIA        MD0100PA00X+062000Y+054000               S0      
317GND              VIA        MD0100PA00X+062000Y+056000               S0      
317GND              VIA        MD0100PA00X+062000Y+058000               S0      
317GND              VIA        MD0100PA00X+062000Y+006000               S0      
317GND              VIA        MD0100PA00X+062000Y+060000               S0      
317GND              VIA        MD0100PA00X+062000Y+064000               S0      
317GND              VIA        MD0100PA00X+062000Y+066000               S0      
317GND              VIA        MD0100PA00X+062000Y+068000               S0      
317GND              VIA        MD0100PA00X+062000Y+070000               S0      
317GND              VIA        MD0100PA00X+062000Y+074000               S0      
317GND              VIA        MD0100PA00X+062000Y+076000               S0      
317GND              VIA        MD0100PA00X+062000Y+078000               S0      
317GND              VIA        MD0100PA00X+062000Y+008000               S0      
317GND              VIA        MD0100PA00X+062000Y+080000               S0      
317GND              VIA        MD0100PA00X+062000Y+082000               S0      
317GND              VIA        MD0100PA00X+062000Y+084000               S0      
317GND              VIA        MD0100PA00X+062000Y+086000               S0      
317GND              VIA        MD0100PA00X+062000Y+088000               S0      
317GND              VIA        MD0100PA00X+062000Y+090000               S0      
317GND              VIA        MD0100PA00X+062000Y+092000               S0      
317GND              VIA        MD0100PA00X+062000Y+094000               S0      
317GND              VIA        MD0100PA00X+062000Y+096000               S0      
317GND              VIA        MD0100PA00X+062000Y+098000               S0      
317GND              VIA        MD0100PA00X+063002Y+000550               S0      
317GND              VIA        MD0100PA00X+006310Y+078880               S0      
317GND              VIA        MD0100PA00X+063256Y+198663               S0      
317GND              VIA        MD0100PA00X+006350Y+089900               S0      
317GND              VIA        MD0100PA00X+006400Y+132850               S0      
317GND              VIA        MD0100PA00X+064000Y+010000               S0      
317GND              VIA        MD0100PA00X+064000Y+104000               S0      
317GND              VIA        MD0100PA00X+064000Y+106000               S0      
317GND              VIA        MD0100PA00X+064000Y+110000               S0      
317GND              VIA        MD0100PA00X+064000Y+112000               S0      
317GND              VIA        MD0100PA00X+064000Y+116000               S0      
317GND              VIA        MD0100PA00X+064000Y+118000               S0      
317GND              VIA        MD0100PA00X+064000Y+012000               S0      
317GND              VIA        MD0100PA00X+064000Y+120000               S0      
317GND              VIA        MD0100PA00X+064000Y+122000               S0      
317GND              VIA        MD0100PA00X+064000Y+124000               S0      
317GND              VIA        MD0100PA00X+064000Y+126000               S0      
317GND              VIA        MD0100PA00X+064000Y+128000               S0      
317GND              VIA        MD0100PA00X+064000Y+130000               S0      
317GND              VIA        MD0100PA00X+064000Y+132000               S0      
317GND              VIA        MD0100PA00X+064000Y+138000               S0      
317GND              VIA        MD0100PA00X+064000Y+014000               S0      
317GND              VIA        MD0100PA00X+064000Y+140000               S0      
317GND              VIA        MD0100PA00X+064000Y+142000               S0      
317GND              VIA        MD0100PA00X+064000Y+144000               S0      
317GND              VIA        MD0100PA00X+064000Y+146000               S0      
317GND              VIA        MD0100PA00X+064000Y+148000               S0      
317GND              VIA        MD0100PA00X+064000Y+150000               S0      
317GND              VIA        MD0100PA00X+064000Y+016000               S0      
317GND              VIA        MD0100PA00X+064000Y+166000               S0      
317GND              VIA        MD0100PA00X+064000Y+168000               S0      
317GND              VIA        MD0100PA00X+064000Y+170000               S0      
317GND              VIA        MD0100PA00X+064000Y+172000               S0      
317GND              VIA        MD0100PA00X+064000Y+174000               S0      
317GND              VIA        MD0100PA00X+064000Y+176000               S0      
317GND              VIA        MD0100PA00X+064000Y+178000               S0      
317GND              VIA        MD0100PA00X+064000Y+018000               S0      
317GND              VIA        MD0100PA00X+064000Y+180000               S0      
317GND              VIA        MD0100PA00X+064000Y+184000               S0      
317GND              VIA        MD0100PA00X+064000Y+186000               S0      
317GND              VIA        MD0100PA00X+064000Y+188000               S0      
317GND              VIA        MD0100PA00X+064000Y+190000               S0      
317GND              VIA        MD0100PA00X+064000Y+192000               S0      
317GND              VIA        MD0100PA00X+064000Y+194000               S0      
317GND              VIA        MD0100PA00X+064000Y+196000               S0      
317GND              VIA        MD0100PA00X+064000Y+198000               S0      
317GND              VIA        MD0100PA00X+064000Y+002000               S0      
317GND              VIA        MD0100PA00X+064000Y+020000               S0      
317GND              VIA        MD0100PA00X+064000Y+022000               S0      
317GND              VIA        MD0100PA00X+064000Y+024000               S0      
317GND              VIA        MD0100PA00X+064000Y+026000               S0      
317GND              VIA        MD0100PA00X+064000Y+028000               S0      
317GND              VIA        MD0100PA00X+064000Y+030000               S0      
317GND              VIA        MD0100PA00X+064000Y+032000               S0      
317GND              VIA        MD0100PA00X+064000Y+034000               S0      
317GND              VIA        MD0100PA00X+064000Y+036000               S0      
317GND              VIA        MD0100PA00X+064000Y+038000               S0      
317GND              VIA        MD0100PA00X+064000Y+004000               S0      
317GND              VIA        MD0100PA00X+064000Y+040000               S0      
317GND              VIA        MD0100PA00X+064000Y+044000               S0      
317GND              VIA        MD0100PA00X+064000Y+046000               S0      
317GND              VIA        MD0100PA00X+064000Y+048000               S0      
317GND              VIA        MD0100PA00X+064000Y+050000               S0      
317GND              VIA        MD0100PA00X+064000Y+052000               S0      
317GND              VIA        MD0100PA00X+064000Y+054000               S0      
317GND              VIA        MD0100PA00X+064000Y+056000               S0      
317GND              VIA        MD0100PA00X+064000Y+058000               S0      
317GND              VIA        MD0100PA00X+064000Y+006000               S0      
317GND              VIA        MD0100PA00X+064000Y+060000               S0      
317GND              VIA        MD0100PA00X+064000Y+064000               S0      
317GND              VIA        MD0100PA00X+064000Y+066000               S0      
317GND              VIA        MD0100PA00X+064000Y+068000               S0      
317GND              VIA        MD0100PA00X+064000Y+070000               S0      
317GND              VIA        MD0100PA00X+064000Y+072000               S0      
317GND              VIA        MD0100PA00X+064000Y+074000               S0      
317GND              VIA        MD0100PA00X+064000Y+076000               S0      
317GND              VIA        MD0100PA00X+064000Y+078000               S0      
317GND              VIA        MD0100PA00X+064000Y+008000               S0      
317GND              VIA        MD0100PA00X+064000Y+080000               S0      
317GND              VIA        MD0100PA00X+064000Y+082000               S0      
317GND              VIA        MD0100PA00X+064000Y+084000               S0      
317GND              VIA        MD0100PA00X+064000Y+086000               S0      
317GND              VIA        MD0100PA00X+064000Y+088000               S0      
317GND              VIA        MD0100PA00X+064000Y+090000               S0      
317GND              VIA        MD0100PA00X+064000Y+092000               S0      
317GND              VIA        MD0100PA00X+064000Y+094000               S0      
317GND              VIA        MD0100PA00X+064000Y+096000               S0      
317GND              VIA        MD0100PA00X+064000Y+098000               S0      
317GND              VIA        MD0100PA00X+006450Y+158150               S0      
317GND              VIA        MD0100PA00X+065002Y+000550               S0      
317GND              VIA        MD0100PA00X+065256Y+198663               S0      
317GND              VIA        MD0100PA00X+006550Y+086750               S0      
317GND              VIA        MD0100PA00X+066000Y+010000               S0      
317GND              VIA        MD0100PA00X+066000Y+104000               S0      
317GND              VIA        MD0100PA00X+066000Y+110000               S0      
317GND              VIA        MD0100PA00X+066000Y+112000               S0      
317GND              VIA        MD0100PA00X+066000Y+116000               S0      
317GND              VIA        MD0100PA00X+066000Y+012000               S0      
317GND              VIA        MD0100PA00X+066000Y+120000               S0      
317GND              VIA        MD0100PA00X+066000Y+122000               S0      
317GND              VIA        MD0100PA00X+066000Y+124000               S0      
317GND              VIA        MD0100PA00X+066000Y+126000               S0      
317GND              VIA        MD0100PA00X+066000Y+128000               S0      
317GND              VIA        MD0100PA00X+066000Y+130000               S0      
317GND              VIA        MD0100PA00X+066000Y+132000               S0      
317GND              VIA        MD0100PA00X+066000Y+134000               S0      
317GND              VIA        MD0100PA00X+066000Y+014000               S0      
317GND              VIA        MD0100PA00X+066000Y+140000               S0      
317GND              VIA        MD0100PA00X+066000Y+142000               S0      
317GND              VIA        MD0100PA00X+066000Y+144000               S0      
317GND              VIA        MD0100PA00X+066000Y+148000               S0      
317GND              VIA        MD0100PA00X+066000Y+150000               S0      
317GND              VIA        MD0100PA00X+066000Y+016000               S0      
317GND              VIA        MD0100PA00X+066000Y+166000               S0      
317GND              VIA        MD0100PA00X+066000Y+168000               S0      
317GND              VIA        MD0100PA00X+066000Y+170000               S0      
317GND              VIA        MD0100PA00X+066000Y+172000               S0      
317GND              VIA        MD0100PA00X+066000Y+174000               S0      
317GND              VIA        MD0100PA00X+066000Y+176000               S0      
317GND              VIA        MD0100PA00X+066000Y+178000               S0      
317GND              VIA        MD0100PA00X+066000Y+018000               S0      
317GND              VIA        MD0100PA00X+066000Y+180000               S0      
317GND              VIA        MD0100PA00X+066000Y+182000               S0      
317GND              VIA        MD0100PA00X+066000Y+184000               S0      
317GND              VIA        MD0100PA00X+066000Y+186000               S0      
317GND              VIA        MD0100PA00X+066000Y+188000               S0      
317GND              VIA        MD0100PA00X+066000Y+190000               S0      
317GND              VIA        MD0100PA00X+066000Y+192000               S0      
317GND              VIA        MD0100PA00X+066000Y+194000               S0      
317GND              VIA        MD0100PA00X+066000Y+196000               S0      
317GND              VIA        MD0100PA00X+066000Y+198000               S0      
317GND              VIA        MD0100PA00X+066000Y+002000               S0      
317GND              VIA        MD0100PA00X+066000Y+020000               S0      
317GND              VIA        MD0100PA00X+066000Y+022000               S0      
317GND              VIA        MD0100PA00X+066000Y+024000               S0      
317GND              VIA        MD0100PA00X+066000Y+026000               S0      
317GND              VIA        MD0100PA00X+066000Y+028000               S0      
317GND              VIA        MD0100PA00X+066000Y+030000               S0      
317GND              VIA        MD0100PA00X+066000Y+032000               S0      
317GND              VIA        MD0100PA00X+066000Y+034000               S0      
317GND              VIA        MD0100PA00X+066000Y+036000               S0      
317GND              VIA        MD0100PA00X+066000Y+038000               S0      
317GND              VIA        MD0100PA00X+066000Y+004000               S0      
317GND              VIA        MD0100PA00X+066000Y+044000               S0      
317GND              VIA        MD0100PA00X+066000Y+046000               S0      
317GND              VIA        MD0100PA00X+066000Y+048000               S0      
317GND              VIA        MD0100PA00X+066000Y+050000               S0      
317GND              VIA        MD0100PA00X+066000Y+052000               S0      
317GND              VIA        MD0100PA00X+066000Y+054000               S0      
317GND              VIA        MD0100PA00X+066000Y+056000               S0      
317GND              VIA        MD0100PA00X+066000Y+058000               S0      
317GND              VIA        MD0100PA00X+066000Y+006000               S0      
317GND              VIA        MD0100PA00X+066000Y+060000               S0      
317GND              VIA        MD0100PA00X+066000Y+064000               S0      
317GND              VIA        MD0100PA00X+066000Y+066000               S0      
317GND              VIA        MD0100PA00X+066000Y+068000               S0      
317GND              VIA        MD0100PA00X+066000Y+072000               S0      
317GND              VIA        MD0100PA00X+066000Y+074000               S0      
317GND              VIA        MD0100PA00X+066000Y+076000               S0      
317GND              VIA        MD0100PA00X+066000Y+078000               S0      
317GND              VIA        MD0100PA00X+066000Y+008000               S0      
317GND              VIA        MD0100PA00X+066000Y+080000               S0      
317GND              VIA        MD0100PA00X+066000Y+082000               S0      
317GND              VIA        MD0100PA00X+066000Y+084000               S0      
317GND              VIA        MD0100PA00X+066000Y+086000               S0      
317GND              VIA        MD0100PA00X+066000Y+088000               S0      
317GND              VIA        MD0100PA00X+066000Y+090000               S0      
317GND              VIA        MD0100PA00X+066000Y+092000               S0      
317GND              VIA        MD0100PA00X+066000Y+096000               S0      
317GND              VIA        MD0100PA00X+066000Y+098000               S0      
317GND              VIA        MD0100PA00X+006650Y+169400               S0      
317GND              VIA        MD0100PA00X+006651Y+028790               S0      
317GND              VIA        MD0100PA00X+006700Y+026900               S0      
317GND              VIA        MD0100PA00X+006700Y+095350               S0      
317GND              VIA        MD0100PA00X+067002Y+000550               S0      
317GND              VIA        MD0100PA00X+067256Y+198663               S0      
317GND              VIA        MD0100PA00X+006750Y+119150               S0      
317GND              VIA        MD0100PA00X+006750Y+012409               S0      
317GND              VIA        MD0100PA00X+006750Y+134062               S0      
317GND              VIA        MD0100PA00X+006750Y+135237               S0      
317GND              VIA        MD0100PA00X+006750Y+013583               S0      
317GND              VIA        MD0100PA00X+006750Y+174613               S0      
317GND              VIA        MD0100PA00X+006750Y+175789               S0      
317GND              VIA        MD0100PA00X+006750Y+052960               S0      
317GND              VIA        MD0100PA00X+006750Y+054134               S0      
317GND              VIA        MD0100PA00X+006750Y+082250               S0      
317GND              VIA        MD0100PA00X+006750Y+093511               S0      
317GND              VIA        MD0100PA00X+006750Y+094685               S0      
317GND              VIA        MD0100PA00X+006800Y+165150               S0      
317GND              VIA        MD0100PA00X+068000Y+010000               S0      
317GND              VIA        MD0100PA00X+068000Y+104000               S0      
317GND              VIA        MD0100PA00X+068000Y+108000               S0      
317GND              VIA        MD0100PA00X+068000Y+110000               S0      
317GND              VIA        MD0100PA00X+068000Y+112000               S0      
317GND              VIA        MD0100PA00X+068000Y+116000               S0      
317GND              VIA        MD0100PA00X+068000Y+012000               S0      
317GND              VIA        MD0100PA00X+068000Y+120000               S0      
317GND              VIA        MD0100PA00X+068000Y+122000               S0      
317GND              VIA        MD0100PA00X+068000Y+124000               S0      
317GND              VIA        MD0100PA00X+068000Y+126000               S0      
317GND              VIA        MD0100PA00X+068000Y+128000               S0      
317GND              VIA        MD0100PA00X+068000Y+130000               S0      
317GND              VIA        MD0100PA00X+068000Y+132000               S0      
317GND              VIA        MD0100PA00X+068000Y+134000               S0      
317GND              VIA        MD0100PA00X+068000Y+136000               S0      
317GND              VIA        MD0100PA00X+068000Y+014000               S0      
317GND              VIA        MD0100PA00X+068000Y+142000               S0      
317GND              VIA        MD0100PA00X+068000Y+144000               S0      
317GND              VIA        MD0100PA00X+068000Y+148000               S0      
317GND              VIA        MD0100PA00X+068000Y+150000               S0      
317GND              VIA        MD0100PA00X+068000Y+016000               S0      
317GND              VIA        MD0100PA00X+068000Y+168000               S0      
317GND              VIA        MD0100PA00X+068000Y+172000               S0      
317GND              VIA        MD0100PA00X+068000Y+174000               S0      
317GND              VIA        MD0100PA00X+068000Y+176000               S0      
317GND              VIA        MD0100PA00X+068000Y+178000               S0      
317GND              VIA        MD0100PA00X+068000Y+018000               S0      
317GND              VIA        MD0100PA00X+068000Y+180000               S0      
317GND              VIA        MD0100PA00X+068000Y+182000               S0      
317GND              VIA        MD0100PA00X+068000Y+186000               S0      
317GND              VIA        MD0100PA00X+068000Y+188000               S0      
317GND              VIA        MD0100PA00X+068000Y+190000               S0      
317GND              VIA        MD0100PA00X+068000Y+192000               S0      
317GND              VIA        MD0100PA00X+068000Y+196000               S0      
317GND              VIA        MD0100PA00X+068000Y+198000               S0      
317GND              VIA        MD0100PA00X+068000Y+002000               S0      
317GND              VIA        MD0100PA00X+068000Y+020000               S0      
317GND              VIA        MD0100PA00X+068000Y+022000               S0      
317GND              VIA        MD0100PA00X+068000Y+024000               S0      
317GND              VIA        MD0100PA00X+068000Y+026000               S0      
317GND              VIA        MD0100PA00X+068000Y+028000               S0      
317GND              VIA        MD0100PA00X+068000Y+030000               S0      
317GND              VIA        MD0100PA00X+068000Y+032000               S0      
317GND              VIA        MD0100PA00X+068000Y+034000               S0      
317GND              VIA        MD0100PA00X+068000Y+036000               S0      
317GND              VIA        MD0100PA00X+068000Y+004000               S0      
317GND              VIA        MD0100PA00X+068000Y+042000               S0      
317GND              VIA        MD0100PA00X+068000Y+044000               S0      
317GND              VIA        MD0100PA00X+068000Y+046000               S0      
317GND              VIA        MD0100PA00X+068000Y+048000               S0      
317GND              VIA        MD0100PA00X+068000Y+050000               S0      
317GND              VIA        MD0100PA00X+068000Y+052000               S0      
317GND              VIA        MD0100PA00X+068000Y+054000               S0      
317GND              VIA        MD0100PA00X+068000Y+056000               S0      
317GND              VIA        MD0100PA00X+068000Y+058000               S0      
317GND              VIA        MD0100PA00X+068000Y+006000               S0      
317GND              VIA        MD0100PA00X+068000Y+060000               S0      
317GND              VIA        MD0100PA00X+068000Y+064000               S0      
317GND              VIA        MD0100PA00X+068000Y+066000               S0      
317GND              VIA        MD0100PA00X+068000Y+068000               S0      
317GND              VIA        MD0100PA00X+068000Y+072000               S0      
317GND              VIA        MD0100PA00X+068000Y+074000               S0      
317GND              VIA        MD0100PA00X+068000Y+076000               S0      
317GND              VIA        MD0100PA00X+068000Y+078000               S0      
317GND              VIA        MD0100PA00X+068000Y+008000               S0      
317GND              VIA        MD0100PA00X+068000Y+080000               S0      
317GND              VIA        MD0100PA00X+068000Y+082000               S0      
317GND              VIA        MD0100PA00X+068000Y+084000               S0      
317GND              VIA        MD0100PA00X+068000Y+086000               S0      
317GND              VIA        MD0100PA00X+068000Y+088000               S0      
317GND              VIA        MD0100PA00X+068000Y+090000               S0      
317GND              VIA        MD0100PA00X+068000Y+092000               S0      
317GND              VIA        MD0100PA00X+068000Y+096000               S0      
317GND              VIA        MD0100PA00X+068000Y+098000               S0      
317GND              VIA        MD0100PA00X+069002Y+000550               S0      
317GND              VIA        MD0100PA00X+069256Y+198663               S0      
317GND              VIA        MD0100PA00X+007002Y+000550               S0      
317GND              VIA        MD0100PA00X+070000Y+010000               S0      
317GND              VIA        MD0100PA00X+070000Y+104000               S0      
317GND              VIA        MD0100PA00X+070000Y+108000               S0      
317GND              VIA        MD0100PA00X+070000Y+110000               S0      
317GND              VIA        MD0100PA00X+070000Y+112000               S0      
317GND              VIA        MD0100PA00X+070000Y+116000               S0      
317GND              VIA        MD0100PA00X+070000Y+012000               S0      
317GND              VIA        MD0100PA00X+070000Y+120000               S0      
317GND              VIA        MD0100PA00X+070000Y+122000               S0      
317GND              VIA        MD0100PA00X+070000Y+124000               S0      
317GND              VIA        MD0100PA00X+070000Y+126000               S0      
317GND              VIA        MD0100PA00X+070000Y+128000               S0      
317GND              VIA        MD0100PA00X+070000Y+130000               S0      
317GND              VIA        MD0100PA00X+070000Y+132000               S0      
317GND              VIA        MD0100PA00X+070000Y+134000               S0      
317GND              VIA        MD0100PA00X+070000Y+136000               S0      
317GND              VIA        MD0100PA00X+070000Y+138000               S0      
317GND              VIA        MD0100PA00X+070000Y+014000               S0      
317GND              VIA        MD0100PA00X+070000Y+144000               S0      
317GND              VIA        MD0100PA00X+070000Y+148000               S0      
317GND              VIA        MD0100PA00X+070000Y+150000               S0      
317GND              VIA        MD0100PA00X+070000Y+016000               S0      
317GND              VIA        MD0100PA00X+070000Y+168000               S0      
317GND              VIA        MD0100PA00X+070000Y+174000               S0      
317GND              VIA        MD0100PA00X+070000Y+176000               S0      
317GND              VIA        MD0100PA00X+070000Y+178000               S0      
317GND              VIA        MD0100PA00X+070000Y+018000               S0      
317GND              VIA        MD0100PA00X+070000Y+180000               S0      
317GND              VIA        MD0100PA00X+070000Y+182000               S0      
317GND              VIA        MD0100PA00X+070000Y+186000               S0      
317GND              VIA        MD0100PA00X+070000Y+188000               S0      
317GND              VIA        MD0100PA00X+070000Y+190000               S0      
317GND              VIA        MD0100PA00X+070000Y+192000               S0      
317GND              VIA        MD0100PA00X+070000Y+194000               S0      
317GND              VIA        MD0100PA00X+070000Y+196000               S0      
317GND              VIA        MD0100PA00X+070000Y+198000               S0      
317GND              VIA        MD0100PA00X+070000Y+002000               S0      
317GND              VIA        MD0100PA00X+070000Y+020000               S0      
317GND              VIA        MD0100PA00X+070000Y+022000               S0      
317GND              VIA        MD0100PA00X+070000Y+024000               S0      
317GND              VIA        MD0100PA00X+070000Y+026000               S0      
317GND              VIA        MD0100PA00X+070000Y+028000               S0      
317GND              VIA        MD0100PA00X+070000Y+030000               S0      
317GND              VIA        MD0100PA00X+070000Y+032000               S0      
317GND              VIA        MD0100PA00X+070000Y+040000               S0      
317GND              VIA        MD0100PA00X+070000Y+042000               S0      
317GND              VIA        MD0100PA00X+070000Y+044000               S0      
317GND              VIA        MD0100PA00X+070000Y+046000               S0      
317GND              VIA        MD0100PA00X+070000Y+048000               S0      
317GND              VIA        MD0100PA00X+070000Y+050000               S0      
317GND              VIA        MD0100PA00X+070000Y+052000               S0      
317GND              VIA        MD0100PA00X+070000Y+054000               S0      
317GND              VIA        MD0100PA00X+070000Y+056000               S0      
317GND              VIA        MD0100PA00X+070000Y+058000               S0      
317GND              VIA        MD0100PA00X+070000Y+006000               S0      
317GND              VIA        MD0100PA00X+070000Y+060000               S0      
317GND              VIA        MD0100PA00X+070000Y+064000               S0      
317GND              VIA        MD0100PA00X+070000Y+066000               S0      
317GND              VIA        MD0100PA00X+070000Y+068000               S0      
317GND              VIA        MD0100PA00X+070000Y+072000               S0      
317GND              VIA        MD0100PA00X+070000Y+074000               S0      
317GND              VIA        MD0100PA00X+070000Y+076000               S0      
317GND              VIA        MD0100PA00X+070000Y+078000               S0      
317GND              VIA        MD0100PA00X+070000Y+008000               S0      
317GND              VIA        MD0100PA00X+070000Y+080000               S0      
317GND              VIA        MD0100PA00X+070000Y+082000               S0      
317GND              VIA        MD0100PA00X+070000Y+084000               S0      
317GND              VIA        MD0100PA00X+070000Y+086000               S0      
317GND              VIA        MD0100PA00X+070000Y+088000               S0      
317GND              VIA        MD0100PA00X+070000Y+090000               S0      
317GND              VIA        MD0100PA00X+070000Y+092000               S0      
317GND              VIA        MD0100PA00X+070000Y+096000               S0      
317GND              VIA        MD0100PA00X+070000Y+098000               S0      
317GND              VIA        MD0100PA00X+007084Y+138417               S0      
317GND              VIA        MD0100PA00X+007100Y+110900               S0      
317GND              VIA        MD0100PA00X+007100Y+127450               S0      
317GND              VIA        MD0100PA00X+007100Y+168000               S0      
317GND              VIA        MD0100PA00X+007100Y+046350               S0      
317GND              VIA        MD0100PA00X+007100Y+005800               S0      
317GND              VIA        MD0100PA00X+007100Y+086900               S0      
317GND              VIA        MD0100PA00X+071002Y+000550               S0      
317GND              VIA        MD0100PA00X+071256Y+198663               S0      
317GND              VIA        MD0100PA00X+007167Y+196133               S0      
317GND              VIA        MD0100PA00X+007200Y+155150               S0      
317GND              VIA        MD0100PA00X+072000Y+010000               S0      
317GND              VIA        MD0100PA00X+072000Y+104000               S0      
317GND              VIA        MD0100PA00X+072000Y+112000               S0      
317GND              VIA        MD0100PA00X+072000Y+116000               S0      
317GND              VIA        MD0100PA00X+072000Y+012000               S0      
317GND              VIA        MD0100PA00X+072000Y+120000               S0      
317GND              VIA        MD0100PA00X+072000Y+122000               S0      
317GND              VIA        MD0100PA00X+072000Y+124000               S0      
317GND              VIA        MD0100PA00X+072000Y+126000               S0      
317GND              VIA        MD0100PA00X+072000Y+128000               S0      
317GND              VIA        MD0100PA00X+072000Y+130000               S0      
317GND              VIA        MD0100PA00X+072000Y+132000               S0      
317GND              VIA        MD0100PA00X+072000Y+134000               S0      
317GND              VIA        MD0100PA00X+072000Y+136000               S0      
317GND              VIA        MD0100PA00X+072000Y+138000               S0      
317GND              VIA        MD0100PA00X+072000Y+014000               S0      
317GND              VIA        MD0100PA00X+072000Y+142000               S0      
317GND              VIA        MD0100PA00X+072000Y+144000               S0      
317GND              VIA        MD0100PA00X+072000Y+148000               S0      
317GND              VIA        MD0100PA00X+072000Y+152000               S0      
317GND              VIA        MD0100PA00X+072000Y+016000               S0      
317GND              VIA        MD0100PA00X+072000Y+168000               S0      
317GND              VIA        MD0100PA00X+072000Y+170000               S0      
317GND              VIA        MD0100PA00X+072000Y+172000               S0      
317GND              VIA        MD0100PA00X+072000Y+178000               S0      
317GND              VIA        MD0100PA00X+072000Y+018000               S0      
317GND              VIA        MD0100PA00X+072000Y+180000               S0      
317GND              VIA        MD0100PA00X+072000Y+182000               S0      
317GND              VIA        MD0100PA00X+072000Y+186000               S0      
317GND              VIA        MD0100PA00X+072000Y+188000               S0      
317GND              VIA        MD0100PA00X+072000Y+190000               S0      
317GND              VIA        MD0100PA00X+072000Y+192000               S0      
317GND              VIA        MD0100PA00X+072000Y+194000               S0      
317GND              VIA        MD0100PA00X+072000Y+196000               S0      
317GND              VIA        MD0100PA00X+072000Y+198000               S0      
317GND              VIA        MD0100PA00X+072000Y+002000               S0      
317GND              VIA        MD0100PA00X+072000Y+020000               S0      
317GND              VIA        MD0100PA00X+072000Y+022000               S0      
317GND              VIA        MD0100PA00X+072000Y+024000               S0      
317GND              VIA        MD0100PA00X+072000Y+026000               S0      
317GND              VIA        MD0100PA00X+072000Y+028000               S0      
317GND              VIA        MD0100PA00X+072000Y+030000               S0      
317GND              VIA        MD0100PA00X+072000Y+032000               S0      
317GND              VIA        MD0100PA00X+072000Y+038000               S0      
317GND              VIA        MD0100PA00X+072000Y+040000               S0      
317GND              VIA        MD0100PA00X+072000Y+042000               S0      
317GND              VIA        MD0100PA00X+072000Y+044000               S0      
317GND              VIA        MD0100PA00X+072000Y+046000               S0      
317GND              VIA        MD0100PA00X+072000Y+048000               S0      
317GND              VIA        MD0100PA00X+072000Y+050000               S0      
317GND              VIA        MD0100PA00X+072000Y+052000               S0      
317GND              VIA        MD0100PA00X+072000Y+054000               S0      
317GND              VIA        MD0100PA00X+072000Y+056000               S0      
317GND              VIA        MD0100PA00X+072000Y+058000               S0      
317GND              VIA        MD0100PA00X+072000Y+006000               S0      
317GND              VIA        MD0100PA00X+072000Y+060000               S0      
317GND              VIA        MD0100PA00X+072000Y+062000               S0      
317GND              VIA        MD0100PA00X+072000Y+064000               S0      
317GND              VIA        MD0100PA00X+072000Y+066000               S0      
317GND              VIA        MD0100PA00X+072000Y+068000               S0      
317GND              VIA        MD0100PA00X+072000Y+072000               S0      
317GND              VIA        MD0100PA00X+072000Y+074000               S0      
317GND              VIA        MD0100PA00X+072000Y+076000               S0      
317GND              VIA        MD0100PA00X+072000Y+078000               S0      
317GND              VIA        MD0100PA00X+072000Y+008000               S0      
317GND              VIA        MD0100PA00X+072000Y+080000               S0      
317GND              VIA        MD0100PA00X+072000Y+082000               S0      
317GND              VIA        MD0100PA00X+072000Y+084000               S0      
317GND              VIA        MD0100PA00X+072000Y+086000               S0      
317GND              VIA        MD0100PA00X+072000Y+088000               S0      
317GND              VIA        MD0100PA00X+072000Y+090000               S0      
317GND              VIA        MD0100PA00X+072000Y+092000               S0      
317GND              VIA        MD0100PA00X+072000Y+096000               S0      
317GND              VIA        MD0100PA00X+072000Y+098000               S0      
317GND              VIA        MD0100PA00X+007210Y+150990               S0      
317GND              VIA        MD0100PA00X+007210Y+153640               S0      
317GND              VIA        MD0100PA00X+007229Y+136563               S0      
317GND              VIA        MD0100PA00X+007250Y+130270               S0      
317GND              VIA        MD0100PA00X+007250Y+130770               S0      
317GND              VIA        MD0100PA00X+007250Y+135270               S0      
317GND              VIA        MD0100PA00X+007250Y+013616               S0      
317GND              VIA        MD0100PA00X+007250Y+015116               S0      
317GND              VIA        MD0100PA00X+007250Y+016616               S0      
317GND              VIA        MD0100PA00X+007250Y+170821               S0      
317GND              VIA        MD0100PA00X+007250Y+171321               S0      
317GND              VIA        MD0100PA00X+007250Y+175821               S0      
317GND              VIA        MD0100PA00X+007250Y+177321               S0      
317GND              VIA        MD0100PA00X+007250Y+178821               S0      
317GND              VIA        MD0100PA00X+007250Y+049167               S0      
317GND              VIA        MD0100PA00X+007250Y+049667               S0      
317GND              VIA        MD0100PA00X+007250Y+054167               S0      
317GND              VIA        MD0100PA00X+007250Y+055667               S0      
317GND              VIA        MD0100PA00X+007250Y+057167               S0      
317GND              VIA        MD0100PA00X+007250Y+008616               S0      
317GND              VIA        MD0100PA00X+007250Y+089719               S0      
317GND              VIA        MD0100PA00X+007250Y+090219               S0      
317GND              VIA        MD0100PA00X+007250Y+009116               S0      
317GND              VIA        MD0100PA00X+007250Y+094719               S0      
317GND              VIA        MD0100PA00X+007250Y+096219               S0      
317GND              VIA        MD0100PA00X+007250Y+097719               S0      
317GND              VIA        MD0100PA00X+007256Y+198663               S0      
317GND              VIA        MD0100PA00X+007290Y+060540               S0      
317GND              VIA        MD0100PA00X+073002Y+000550               S0      
317GND              VIA        MD0100PA00X+073256Y+198663               S0      
317GND              VIA        MD0100PA00X+007350Y+077950               S0      
317GND              VIA        MD0100PA00X+074000Y+010000               S0      
317GND              VIA        MD0100PA00X+074000Y+104000               S0      
317GND              VIA        MD0100PA00X+074000Y+108000               S0      
317GND              VIA        MD0100PA00X+074000Y+112000               S0      
317GND              VIA        MD0100PA00X+074000Y+116000               S0      
317GND              VIA        MD0100PA00X+074000Y+012000               S0      
317GND              VIA        MD0100PA00X+074000Y+120000               S0      
317GND              VIA        MD0100PA00X+074000Y+122000               S0      
317GND              VIA        MD0100PA00X+074000Y+124000               S0      
317GND              VIA        MD0100PA00X+074000Y+126000               S0      
317GND              VIA        MD0100PA00X+074000Y+128000               S0      
317GND              VIA        MD0100PA00X+074000Y+130000               S0      
317GND              VIA        MD0100PA00X+074000Y+132000               S0      
317GND              VIA        MD0100PA00X+074000Y+134000               S0      
317GND              VIA        MD0100PA00X+074000Y+136000               S0      
317GND              VIA        MD0100PA00X+074000Y+138000               S0      
317GND              VIA        MD0100PA00X+074000Y+014000               S0      
317GND              VIA        MD0100PA00X+074000Y+142000               S0      
317GND              VIA        MD0100PA00X+074000Y+144000               S0      
317GND              VIA        MD0100PA00X+074000Y+148000               S0      
317GND              VIA        MD0100PA00X+074000Y+152000               S0      
317GND              VIA        MD0100PA00X+074000Y+016000               S0      
317GND              VIA        MD0100PA00X+074000Y+168000               S0      
317GND              VIA        MD0100PA00X+074000Y+170000               S0      
317GND              VIA        MD0100PA00X+074000Y+172000               S0      
317GND              VIA        MD0100PA00X+074000Y+174000               S0      
317GND              VIA        MD0100PA00X+074000Y+018000               S0      
317GND              VIA        MD0100PA00X+074000Y+180000               S0      
317GND              VIA        MD0100PA00X+074000Y+182000               S0      
317GND              VIA        MD0100PA00X+074000Y+186000               S0      
317GND              VIA        MD0100PA00X+074000Y+188000               S0      
317GND              VIA        MD0100PA00X+074000Y+190000               S0      
317GND              VIA        MD0100PA00X+074000Y+196000               S0      
317GND              VIA        MD0100PA00X+074000Y+198000               S0      
317GND              VIA        MD0100PA00X+074000Y+002000               S0      
317GND              VIA        MD0100PA00X+074000Y+020000               S0      
317GND              VIA        MD0100PA00X+074000Y+022000               S0      
317GND              VIA        MD0100PA00X+074000Y+024000               S0      
317GND              VIA        MD0100PA00X+074000Y+026000               S0      
317GND              VIA        MD0100PA00X+074000Y+028000               S0      
317GND              VIA        MD0100PA00X+074000Y+030000               S0      
317GND              VIA        MD0100PA00X+074000Y+038000               S0      
317GND              VIA        MD0100PA00X+074000Y+004000               S0      
317GND              VIA        MD0100PA00X+074000Y+040000               S0      
317GND              VIA        MD0100PA00X+074000Y+042000               S0      
317GND              VIA        MD0100PA00X+074000Y+044000               S0      
317GND              VIA        MD0100PA00X+074000Y+046000               S0      
317GND              VIA        MD0100PA00X+074000Y+048000               S0      
317GND              VIA        MD0100PA00X+074000Y+050000               S0      
317GND              VIA        MD0100PA00X+074000Y+052000               S0      
317GND              VIA        MD0100PA00X+074000Y+054000               S0      
317GND              VIA        MD0100PA00X+074000Y+056000               S0      
317GND              VIA        MD0100PA00X+074000Y+058000               S0      
317GND              VIA        MD0100PA00X+074000Y+006000               S0      
317GND              VIA        MD0100PA00X+074000Y+060000               S0      
317GND              VIA        MD0100PA00X+074000Y+062000               S0      
317GND              VIA        MD0100PA00X+074000Y+064000               S0      
317GND              VIA        MD0100PA00X+074000Y+066000               S0      
317GND              VIA        MD0100PA00X+074000Y+068000               S0      
317GND              VIA        MD0100PA00X+074000Y+072000               S0      
317GND              VIA        MD0100PA00X+074000Y+074000               S0      
317GND              VIA        MD0100PA00X+074000Y+076000               S0      
317GND              VIA        MD0100PA00X+074000Y+078000               S0      
317GND              VIA        MD0100PA00X+074000Y+008000               S0      
317GND              VIA        MD0100PA00X+074000Y+080000               S0      
317GND              VIA        MD0100PA00X+074000Y+082000               S0      
317GND              VIA        MD0100PA00X+074000Y+084000               S0      
317GND              VIA        MD0100PA00X+074000Y+086000               S0      
317GND              VIA        MD0100PA00X+074000Y+088000               S0      
317GND              VIA        MD0100PA00X+074000Y+090000               S0      
317GND              VIA        MD0100PA00X+074000Y+092000               S0      
317GND              VIA        MD0100PA00X+074000Y+096000               S0      
317GND              VIA        MD0100PA00X+074000Y+098000               S0      
317GND              VIA        MD0100PA00X+007430Y+190000               S0      
317GND              VIA        MD0100PA00X+007500Y+118250               S0      
317GND              VIA        MD0100PA00X+075002Y+000550               S0      
317GND              VIA        MD0100PA00X+075256Y+198663               S0      
317GND              VIA        MD0100PA00X+075800Y+175600               S0      
317GND              VIA        MD0100PA00X+075970Y+181750               S0      
317GND              VIA        MD0100PA00X+075970Y+183750               S0      
317GND              VIA        MD0100PA00X+075990Y+195920               S0      
317GND              VIA        MD0100PA00X+007600Y+070650               S0      
317GND              VIA        MD0100PA00X+076000Y+010000               S0      
317GND              VIA        MD0100PA00X+076000Y+104000               S0      
317GND              VIA        MD0100PA00X+076000Y+112000               S0      
317GND              VIA        MD0100PA00X+076000Y+116000               S0      
317GND              VIA        MD0100PA00X+076000Y+012000               S0      
317GND              VIA        MD0100PA00X+076000Y+120000               S0      
317GND              VIA        MD0100PA00X+076000Y+122000               S0      
317GND              VIA        MD0100PA00X+076000Y+124000               S0      
317GND              VIA        MD0100PA00X+076000Y+126000               S0      
317GND              VIA        MD0100PA00X+076000Y+128000               S0      
317GND              VIA        MD0100PA00X+076000Y+130000               S0      
317GND              VIA        MD0100PA00X+076000Y+132000               S0      
317GND              VIA        MD0100PA00X+076000Y+134000               S0      
317GND              VIA        MD0100PA00X+076000Y+136000               S0      
317GND              VIA        MD0100PA00X+076000Y+138000               S0      
317GND              VIA        MD0100PA00X+076000Y+014000               S0      
317GND              VIA        MD0100PA00X+076000Y+142000               S0      
317GND              VIA        MD0100PA00X+076000Y+144000               S0      
317GND              VIA        MD0100PA00X+076000Y+148000               S0      
317GND              VIA        MD0100PA00X+076000Y+152000               S0      
317GND              VIA        MD0100PA00X+076000Y+016000               S0      
317GND              VIA        MD0100PA00X+076000Y+172000               S0      
317GND              VIA        MD0100PA00X+076000Y+174000               S0      
317GND              VIA        MD0100PA00X+076000Y+178000               S0      
317GND              VIA        MD0100PA00X+076000Y+018000               S0      
317GND              VIA        MD0100PA00X+076000Y+188000               S0      
317GND              VIA        MD0100PA00X+076000Y+194000               S0      
317GND              VIA        MD0100PA00X+076000Y+198000               S0      
317GND              VIA        MD0100PA00X+076000Y+002000               S0      
317GND              VIA        MD0100PA00X+076000Y+020000               S0      
317GND              VIA        MD0100PA00X+076000Y+022000               S0      
317GND              VIA        MD0100PA00X+076000Y+024000               S0      
317GND              VIA        MD0100PA00X+076000Y+026000               S0      
317GND              VIA        MD0100PA00X+076000Y+028000               S0      
317GND              VIA        MD0100PA00X+076000Y+032000               S0      
317GND              VIA        MD0100PA00X+076000Y+036000               S0      
317GND              VIA        MD0100PA00X+076000Y+038000               S0      
317GND              VIA        MD0100PA00X+076000Y+004000               S0      
317GND              VIA        MD0100PA00X+076000Y+040000               S0      
317GND              VIA        MD0100PA00X+076000Y+042000               S0      
317GND              VIA        MD0100PA00X+076000Y+044000               S0      
317GND              VIA        MD0100PA00X+076000Y+046000               S0      
317GND              VIA        MD0100PA00X+076000Y+048000               S0      
317GND              VIA        MD0100PA00X+076000Y+050000               S0      
317GND              VIA        MD0100PA00X+076000Y+052000               S0      
317GND              VIA        MD0100PA00X+076000Y+054000               S0      
317GND              VIA        MD0100PA00X+076000Y+056000               S0      
317GND              VIA        MD0100PA00X+076000Y+058000               S0      
317GND              VIA        MD0100PA00X+076000Y+006000               S0      
317GND              VIA        MD0100PA00X+076000Y+060000               S0      
317GND              VIA        MD0100PA00X+076000Y+062000               S0      
317GND              VIA        MD0100PA00X+076000Y+064000               S0      
317GND              VIA        MD0100PA00X+076000Y+068000               S0      
317GND              VIA        MD0100PA00X+076000Y+072000               S0      
317GND              VIA        MD0100PA00X+076000Y+074000               S0      
317GND              VIA        MD0100PA00X+076000Y+076000               S0      
317GND              VIA        MD0100PA00X+076000Y+078000               S0      
317GND              VIA        MD0100PA00X+076000Y+008000               S0      
317GND              VIA        MD0100PA00X+076000Y+080000               S0      
317GND              VIA        MD0100PA00X+076000Y+082000               S0      
317GND              VIA        MD0100PA00X+076000Y+084000               S0      
317GND              VIA        MD0100PA00X+076000Y+086000               S0      
317GND              VIA        MD0100PA00X+076000Y+088000               S0      
317GND              VIA        MD0100PA00X+076000Y+090000               S0      
317GND              VIA        MD0100PA00X+076000Y+092000               S0      
317GND              VIA        MD0100PA00X+076000Y+096000               S0      
317GND              VIA        MD0100PA00X+076000Y+098000               S0      
317GND              VIA        MD0100PA00X+007650Y+066500               S0      
317GND              VIA        MD0100PA00X+007697Y+186400               S0      
317GND              VIA        MD0100PA00X+076924Y+195578               S0      
317GND              VIA        MD0100PA00X+077002Y+000550               S0      
317GND              VIA        MD0100PA00X+077256Y+198663               S0      
317GND              VIA        MD0100PA00X+007731Y+025938               S0      
317GND              VIA        MD0100PA00X+077499Y+195571               S0      
317GND              VIA        MD0100PA00X+077840Y+065980               S0      
317GND              VIA        MD0100PA00X+078000Y+010000               S0      
317GND              VIA        MD0100PA00X+078000Y+106000               S0      
317GND              VIA        MD0100PA00X+078000Y+112000               S0      
317GND              VIA        MD0100PA00X+078000Y+116000               S0      
317GND              VIA        MD0100PA00X+078000Y+012000               S0      
317GND              VIA        MD0100PA00X+078000Y+120000               S0      
317GND              VIA        MD0100PA00X+078000Y+122000               S0      
317GND              VIA        MD0100PA00X+078000Y+124000               S0      
317GND              VIA        MD0100PA00X+078000Y+126000               S0      
317GND              VIA        MD0100PA00X+078000Y+128000               S0      
317GND              VIA        MD0100PA00X+078000Y+130000               S0      
317GND              VIA        MD0100PA00X+078000Y+132000               S0      
317GND              VIA        MD0100PA00X+078000Y+134000               S0      
317GND              VIA        MD0100PA00X+078000Y+136000               S0      
317GND              VIA        MD0100PA00X+078000Y+138000               S0      
317GND              VIA        MD0100PA00X+078000Y+014000               S0      
317GND              VIA        MD0100PA00X+078000Y+142000               S0      
317GND              VIA        MD0100PA00X+078000Y+144000               S0      
317GND              VIA        MD0100PA00X+078000Y+148000               S0      
317GND              VIA        MD0100PA00X+078000Y+152000               S0      
317GND              VIA        MD0100PA00X+078000Y+016000               S0      
317GND              VIA        MD0100PA00X+078000Y+174000               S0      
317GND              VIA        MD0100PA00X+078000Y+178000               S0      
317GND              VIA        MD0100PA00X+078000Y+018000               S0      
317GND              VIA        MD0100PA00X+078000Y+180000               S0      
317GND              VIA        MD0100PA00X+078000Y+184000               S0      
317GND              VIA        MD0100PA00X+078000Y+192000               S0      
317GND              VIA        MD0100PA00X+078000Y+198000               S0      
317GND              VIA        MD0100PA00X+078000Y+002000               S0      
317GND              VIA        MD0100PA00X+078000Y+020000               S0      
317GND              VIA        MD0100PA00X+078000Y+022000               S0      
317GND              VIA        MD0100PA00X+078000Y+024000               S0      
317GND              VIA        MD0100PA00X+078000Y+030000               S0      
317GND              VIA        MD0100PA00X+078000Y+034000               S0      
317GND              VIA        MD0100PA00X+078000Y+036000               S0      
317GND              VIA        MD0100PA00X+078000Y+038000               S0      
317GND              VIA        MD0100PA00X+078000Y+004000               S0      
317GND              VIA        MD0100PA00X+078000Y+040000               S0      
317GND              VIA        MD0100PA00X+078000Y+042000               S0      
317GND              VIA        MD0100PA00X+078000Y+044000               S0      
317GND              VIA        MD0100PA00X+078000Y+046000               S0      
317GND              VIA        MD0100PA00X+078000Y+048000               S0      
317GND              VIA        MD0100PA00X+078000Y+050000               S0      
317GND              VIA        MD0100PA00X+078000Y+052000               S0      
317GND              VIA        MD0100PA00X+078000Y+054000               S0      
317GND              VIA        MD0100PA00X+078000Y+056000               S0      
317GND              VIA        MD0100PA00X+078000Y+058000               S0      
317GND              VIA        MD0100PA00X+078000Y+006000               S0      
317GND              VIA        MD0100PA00X+078000Y+060000               S0      
317GND              VIA        MD0100PA00X+078000Y+062000               S0      
317GND              VIA        MD0100PA00X+078000Y+064000               S0      
317GND              VIA        MD0100PA00X+078000Y+070000               S0      
317GND              VIA        MD0100PA00X+078000Y+072000               S0      
317GND              VIA        MD0100PA00X+078000Y+074000               S0      
317GND              VIA        MD0100PA00X+078000Y+076000               S0      
317GND              VIA        MD0100PA00X+078000Y+078000               S0      
317GND              VIA        MD0100PA00X+078000Y+008000               S0      
317GND              VIA        MD0100PA00X+078000Y+080000               S0      
317GND              VIA        MD0100PA00X+078000Y+084000               S0      
317GND              VIA        MD0100PA00X+078000Y+086000               S0      
317GND              VIA        MD0100PA00X+078000Y+088000               S0      
317GND              VIA        MD0100PA00X+078000Y+090000               S0      
317GND              VIA        MD0100PA00X+078000Y+092000               S0      
317GND              VIA        MD0100PA00X+078000Y+096000               S0      
317GND              VIA        MD0100PA00X+078000Y+098000               S0      
317GND              VIA        MD0100PA00X+078021Y+195326               S0      
317GND              VIA        MD0100PA00X+079002Y+000550               S0      
317GND              VIA        MD0100PA00X+079256Y+198663               S0      
317GND              VIA        MD0100PA00X+079550Y+175500               S0      
317GND              VIA        MD0100PA00X+079840Y+065980               S0      
317GND              VIA        MD0100PA00X+079921Y+196053               S0      
317GND              VIA        MD0100PA00X+008000Y+148000               S0      
317GND              VIA        MD0100PA00X+008000Y+192000               S0      
317GND              VIA        MD0100PA00X+008000Y+192800               S0      
317GND              VIA        MD0100PA00X+008000Y+198000               S0      
317GND              VIA        MD0100PA00X+008000Y+020000               S0      
317GND              VIA        MD0100PA00X+008000Y+060000               S0      
317GND              VIA        MD0100PA00X+080000Y+010000               S0      
317GND              VIA        MD0100PA00X+080000Y+106000               S0      
317GND              VIA        MD0100PA00X+080000Y+108000               S0      
317GND              VIA        MD0100PA00X+080000Y+110000               S0      
317GND              VIA        MD0100PA00X+080000Y+112000               S0      
317GND              VIA        MD0100PA00X+080000Y+116000               S0      
317GND              VIA        MD0100PA00X+080000Y+012000               S0      
317GND              VIA        MD0100PA00X+080000Y+120000               S0      
317GND              VIA        MD0100PA00X+080000Y+122000               S0      
317GND              VIA        MD0100PA00X+080000Y+124000               S0      
317GND              VIA        MD0100PA00X+080000Y+126000               S0      
317GND              VIA        MD0100PA00X+080000Y+128000               S0      
317GND              VIA        MD0100PA00X+080000Y+130000               S0      
317GND              VIA        MD0100PA00X+080000Y+132000               S0      
317GND              VIA        MD0100PA00X+080000Y+134000               S0      
317GND              VIA        MD0100PA00X+080000Y+136000               S0      
317GND              VIA        MD0100PA00X+080000Y+138000               S0      
317GND              VIA        MD0100PA00X+080000Y+014000               S0      
317GND              VIA        MD0100PA00X+080000Y+142000               S0      
317GND              VIA        MD0100PA00X+080000Y+144000               S0      
317GND              VIA        MD0100PA00X+080000Y+148000               S0      
317GND              VIA        MD0100PA00X+080000Y+156000               S0      
317GND              VIA        MD0100PA00X+080000Y+174000               S0      
317GND              VIA        MD0100PA00X+080000Y+178000               S0      
317GND              VIA        MD0100PA00X+080000Y+180000               S0      
317GND              VIA        MD0100PA00X+080000Y+182000               S0      
317GND              VIA        MD0100PA00X+080000Y+192000               S0      
317GND              VIA        MD0100PA00X+080000Y+198000               S0      
317GND              VIA        MD0100PA00X+080000Y+002000               S0      
317GND              VIA        MD0100PA00X+080000Y+022000               S0      
317GND              VIA        MD0100PA00X+080000Y+024000               S0      
317GND              VIA        MD0100PA00X+080000Y+028000               S0      
317GND              VIA        MD0100PA00X+080000Y+034000               S0      
317GND              VIA        MD0100PA00X+080000Y+036000               S0      
317GND              VIA        MD0100PA00X+080000Y+038000               S0      
317GND              VIA        MD0100PA00X+080000Y+004000               S0      
317GND              VIA        MD0100PA00X+080000Y+040000               S0      
317GND              VIA        MD0100PA00X+080000Y+042000               S0      
317GND              VIA        MD0100PA00X+080000Y+044000               S0      
317GND              VIA        MD0100PA00X+080000Y+046000               S0      
317GND              VIA        MD0100PA00X+080000Y+048000               S0      
317GND              VIA        MD0100PA00X+080000Y+050000               S0      
317GND              VIA        MD0100PA00X+080000Y+052000               S0      
317GND              VIA        MD0100PA00X+080000Y+054000               S0      
317GND              VIA        MD0100PA00X+080000Y+056000               S0      
317GND              VIA        MD0100PA00X+080000Y+058000               S0      
317GND              VIA        MD0100PA00X+080000Y+006000               S0      
317GND              VIA        MD0100PA00X+080000Y+060000               S0      
317GND              VIA        MD0100PA00X+080000Y+062000               S0      
317GND              VIA        MD0100PA00X+080000Y+064000               S0      
317GND              VIA        MD0100PA00X+080000Y+072000               S0      
317GND              VIA        MD0100PA00X+080000Y+074000               S0      
317GND              VIA        MD0100PA00X+080000Y+076000               S0      
317GND              VIA        MD0100PA00X+080000Y+078000               S0      
317GND              VIA        MD0100PA00X+080000Y+008000               S0      
317GND              VIA        MD0100PA00X+080000Y+084000               S0      
317GND              VIA        MD0100PA00X+080000Y+086000               S0      
317GND              VIA        MD0100PA00X+080000Y+088000               S0      
317GND              VIA        MD0100PA00X+080000Y+090000               S0      
317GND              VIA        MD0100PA00X+080000Y+092000               S0      
317GND              VIA        MD0100PA00X+080000Y+096000               S0      
317GND              VIA        MD0100PA00X+080000Y+098000               S0      
317GND              VIA        MD0100PA00X+081002Y+000550               S0      
317GND              VIA        MD0100PA00X+081256Y+198663               S0      
317GND              VIA        MD0100PA00X+008150Y+121300               S0      
317GND              VIA        MD0100PA00X+081538Y+117375               S0      
317GND              VIA        MD0100PA00X+081538Y+036275               S0      
317GND              VIA        MD0100PA00X+081538Y+076825               S0      
317GND              VIA        MD0100PA00X+081600Y+180100               S0      
317GND              VIA        MD0100PA00X+081600Y+018700               S0      
317GND              VIA        MD0100PA00X+081663Y+157925               S0      
317GND              VIA        MD0100PA00X+081900Y+178500               S0      
317GND              VIA        MD0100PA00X+082000Y+010000               S0      
317GND              VIA        MD0100PA00X+082000Y+104000               S0      
317GND              VIA        MD0100PA00X+082000Y+106000               S0      
317GND              VIA        MD0100PA00X+082000Y+112000               S0      
317GND              VIA        MD0100PA00X+082000Y+012000               S0      
317GND              VIA        MD0100PA00X+082000Y+120000               S0      
317GND              VIA        MD0100PA00X+082000Y+122000               S0      
317GND              VIA        MD0100PA00X+082000Y+124000               S0      
317GND              VIA        MD0100PA00X+082000Y+126000               S0      
317GND              VIA        MD0100PA00X+082000Y+128000               S0      
317GND              VIA        MD0100PA00X+082000Y+130000               S0      
317GND              VIA        MD0100PA00X+082000Y+132000               S0      
317GND              VIA        MD0100PA00X+082000Y+134000               S0      
317GND              VIA        MD0100PA00X+082000Y+136000               S0      
317GND              VIA        MD0100PA00X+082000Y+138000               S0      
317GND              VIA        MD0100PA00X+082000Y+014000               S0      
317GND              VIA        MD0100PA00X+082000Y+142000               S0      
317GND              VIA        MD0100PA00X+082000Y+144000               S0      
317GND              VIA        MD0100PA00X+082000Y+148000               S0      
317GND              VIA        MD0100PA00X+082000Y+168000               S0      
317GND              VIA        MD0100PA00X+082000Y+182000               S0      
317GND              VIA        MD0100PA00X+082000Y+192000               S0      
317GND              VIA        MD0100PA00X+082000Y+198000               S0      
317GND              VIA        MD0100PA00X+082000Y+002000               S0      
317GND              VIA        MD0100PA00X+082000Y+022000               S0      
317GND              VIA        MD0100PA00X+082000Y+026000               S0      
317GND              VIA        MD0100PA00X+082000Y+004000               S0      
317GND              VIA        MD0100PA00X+082000Y+040000               S0      
317GND              VIA        MD0100PA00X+082000Y+042000               S0      
317GND              VIA        MD0100PA00X+082000Y+044000               S0      
317GND              VIA        MD0100PA00X+082000Y+046000               S0      
317GND              VIA        MD0100PA00X+082000Y+048000               S0      
317GND              VIA        MD0100PA00X+082000Y+050000               S0      
317GND              VIA        MD0100PA00X+082000Y+052000               S0      
317GND              VIA        MD0100PA00X+082000Y+054000               S0      
317GND              VIA        MD0100PA00X+082000Y+056000               S0      
317GND              VIA        MD0100PA00X+082000Y+058000               S0      
317GND              VIA        MD0100PA00X+082000Y+006000               S0      
317GND              VIA        MD0100PA00X+082000Y+060000               S0      
317GND              VIA        MD0100PA00X+082000Y+062000               S0      
317GND              VIA        MD0100PA00X+082000Y+066000               S0      
317GND              VIA        MD0100PA00X+082000Y+070000               S0      
317GND              VIA        MD0100PA00X+082000Y+072000               S0      
317GND              VIA        MD0100PA00X+082000Y+008000               S0      
317GND              VIA        MD0100PA00X+082000Y+082000               S0      
317GND              VIA        MD0100PA00X+082000Y+084000               S0      
317GND              VIA        MD0100PA00X+082000Y+086000               S0      
317GND              VIA        MD0100PA00X+082000Y+088000               S0      
317GND              VIA        MD0100PA00X+082000Y+090000               S0      
317GND              VIA        MD0100PA00X+082000Y+092000               S0      
317GND              VIA        MD0100PA00X+082000Y+096000               S0      
317GND              VIA        MD0100PA00X+082000Y+098000               S0      
317GND              VIA        MD0100PA00X+082050Y+017100               S0      
317GND              VIA        MD0100PA00X+082340Y+197340               S0      
317GND              VIA        MD0100PA00X+082434Y+117692               S0      
317GND              VIA        MD0100PA00X+082434Y+158242               S0      
317GND              VIA        MD0100PA00X+082434Y+036592               S0      
317GND              VIA        MD0100PA00X+082434Y+077141               S0      
317GND              VIA        MD0100PA00X+082539Y+169550               S0      
317GND              VIA        MD0100PA00X+082539Y+173950               S0      
317GND              VIA        MD0100PA00X+008275Y+146556               S0      
317GND              VIA        MD0100PA00X+082750Y+181700               S0      
317GND              VIA        MD0100PA00X+082790Y+197340               S0      
317GND              VIA        MD0100PA00X+082800Y+186200               S0      
317GND              VIA        MD0100PA00X+082800Y+020300               S0      
317GND              VIA        MD0100PA00X+082850Y+017100               S0      
317GND              VIA        MD0100PA00X+082939Y+169550               S0      
317GND              VIA        MD0100PA00X+082939Y+173950               S0      
317GND              VIA        MD0100PA00X+082950Y+178500               S0      
317GND              VIA        MD0100PA00X+083002Y+000550               S0      
317GND              VIA        MD0100PA00X+008320Y+076830               S0      
317GND              VIA        MD0100PA00X+008325Y+105964               S0      
317GND              VIA        MD0100PA00X+083256Y+198663               S0      
317GND              VIA        MD0100PA00X+083339Y+169550               S0      
317GND              VIA        MD0100PA00X+083339Y+173950               S0      
317GND              VIA        MD0100PA00X+083590Y+197350               S0      
317GND              VIA        MD0100PA00X+083739Y+169550               S0      
317GND              VIA        MD0100PA00X+083739Y+173950               S0      
317GND              VIA        MD0100PA00X+083750Y+178500               S0      
317GND              VIA        MD0100PA00X+083940Y+197350               S0      
317GND              VIA        MD0100PA00X+084000Y+010000               S0      
317GND              VIA        MD0100PA00X+084000Y+104000               S0      
317GND              VIA        MD0100PA00X+084000Y+106000               S0      
317GND              VIA        MD0100PA00X+084000Y+012000               S0      
317GND              VIA        MD0100PA00X+084000Y+120000               S0      
317GND              VIA        MD0100PA00X+084000Y+122000               S0      
317GND              VIA        MD0100PA00X+084000Y+124000               S0      
317GND              VIA        MD0100PA00X+084000Y+126000               S0      
317GND              VIA        MD0100PA00X+084000Y+128000               S0      
317GND              VIA        MD0100PA00X+084000Y+130000               S0      
317GND              VIA        MD0100PA00X+084000Y+132000               S0      
317GND              VIA        MD0100PA00X+084000Y+134000               S0      
317GND              VIA        MD0100PA00X+084000Y+136000               S0      
317GND              VIA        MD0100PA00X+084000Y+138000               S0      
317GND              VIA        MD0100PA00X+084000Y+014000               S0      
317GND              VIA        MD0100PA00X+084000Y+142000               S0      
317GND              VIA        MD0100PA00X+084000Y+144000               S0      
317GND              VIA        MD0100PA00X+084000Y+148000               S0      
317GND              VIA        MD0100PA00X+084000Y+160000               S0      
317GND              VIA        MD0100PA00X+084000Y+164000               S0      
317GND              VIA        MD0100PA00X+084000Y+166000               S0      
317GND              VIA        MD0100PA00X+084000Y+168000               S0      
317GND              VIA        MD0100PA00X+084000Y+017425               S0      
317GND              VIA        MD0100PA00X+084000Y+198000               S0      
317GND              VIA        MD0100PA00X+084000Y+002000               S0      
317GND              VIA        MD0100PA00X+084000Y+024000               S0      
317GND              VIA        MD0100PA00X+084000Y+004000               S0      
317GND              VIA        MD0100PA00X+084000Y+040000               S0      
317GND              VIA        MD0100PA00X+084000Y+042000               S0      
317GND              VIA        MD0100PA00X+084000Y+044000               S0      
317GND              VIA        MD0100PA00X+084000Y+046000               S0      
317GND              VIA        MD0100PA00X+084000Y+048000               S0      
317GND              VIA        MD0100PA00X+084000Y+050000               S0      
317GND              VIA        MD0100PA00X+084000Y+052000               S0      
317GND              VIA        MD0100PA00X+084000Y+054000               S0      
317GND              VIA        MD0100PA00X+084000Y+056000               S0      
317GND              VIA        MD0100PA00X+084000Y+058000               S0      
317GND              VIA        MD0100PA00X+084000Y+006000               S0      
317GND              VIA        MD0100PA00X+084000Y+060000               S0      
317GND              VIA        MD0100PA00X+084000Y+062000               S0      
317GND              VIA        MD0100PA00X+084000Y+064000               S0      
317GND              VIA        MD0100PA00X+084000Y+066000               S0      
317GND              VIA        MD0100PA00X+084000Y+068000               S0      
317GND              VIA        MD0100PA00X+084000Y+070000               S0      
317GND              VIA        MD0100PA00X+084000Y+072000               S0      
317GND              VIA        MD0100PA00X+084000Y+008000               S0      
317GND              VIA        MD0100PA00X+084000Y+080000               S0      
317GND              VIA        MD0100PA00X+084000Y+082000               S0      
317GND              VIA        MD0100PA00X+084000Y+084000               S0      
317GND              VIA        MD0100PA00X+084000Y+086000               S0      
317GND              VIA        MD0100PA00X+084000Y+088000               S0      
317GND              VIA        MD0100PA00X+084000Y+090000               S0      
317GND              VIA        MD0100PA00X+084000Y+092000               S0      
317GND              VIA        MD0100PA00X+084000Y+096000               S0      
317GND              VIA        MD0100PA00X+084000Y+098000               S0      
317GND              VIA        MD0100PA00X+084139Y+169550               S0      
317GND              VIA        MD0100PA00X+084350Y+197350               S0      
317GND              VIA        MD0100PA00X+084480Y+194970               S0      
317GND              VIA        MD0100PA00X+008450Y+031500               S0      
317GND              VIA        MD0100PA00X+084700Y+197350               S0      
317GND              VIA        MD0100PA00X+085002Y+000550               S0      
317GND              VIA        MD0100PA00X+085060Y+118103               S0      
317GND              VIA        MD0100PA00X+085097Y+158653               S0      
317GND              VIA        MD0100PA00X+085097Y+037003               S0      
317GND              VIA        MD0100PA00X+085097Y+077553               S0      
317GND              VIA        MD0100PA00X+008525Y+024724               S0      
317GND              VIA        MD0100PA00X+008525Y+065275               S0      
317GND              VIA        MD0100PA00X+085256Y+198663               S0      
317GND              VIA        MD0100PA00X+085450Y+114870               S0      
317GND              VIA        MD0100PA00X+085550Y+155430               S0      
317GND              VIA        MD0100PA00X+085610Y+074330               S0      
317GND              VIA        MD0100PA00X+085620Y+033730               S0      
317GND              VIA        MD0100PA00X+085880Y+195130               S0      
317GND              VIA        MD0100PA00X+085950Y+114410               S0      
317GND              VIA        MD0100PA00X+085950Y+114760               S0      
317GND              VIA        MD0100PA00X+085950Y+154970               S0      
317GND              VIA        MD0100PA00X+085950Y+155320               S0      
317GND              VIA        MD0100PA00X+085950Y+073830               S0      
317GND              VIA        MD0100PA00X+085950Y+074180               S0      
317GND              VIA        MD0100PA00X+086000Y+010000               S0      
317GND              VIA        MD0100PA00X+086000Y+104000               S0      
317GND              VIA        MD0100PA00X+086000Y+012000               S0      
317GND              VIA        MD0100PA00X+086000Y+120000               S0      
317GND              VIA        MD0100PA00X+086000Y+122000               S0      
317GND              VIA        MD0100PA00X+086000Y+124000               S0      
317GND              VIA        MD0100PA00X+086000Y+126000               S0      
317GND              VIA        MD0100PA00X+086000Y+128000               S0      
317GND              VIA        MD0100PA00X+086000Y+130000               S0      
317GND              VIA        MD0100PA00X+086000Y+132000               S0      
317GND              VIA        MD0100PA00X+086000Y+134000               S0      
317GND              VIA        MD0100PA00X+086000Y+138000               S0      
317GND              VIA        MD0100PA00X+086000Y+014000               S0      
317GND              VIA        MD0100PA00X+086000Y+142000               S0      
317GND              VIA        MD0100PA00X+086000Y+144000               S0      
317GND              VIA        MD0100PA00X+086000Y+158000               S0      
317GND              VIA        MD0100PA00X+086000Y+164000               S0      
317GND              VIA        MD0100PA00X+086000Y+166000               S0      
317GND              VIA        MD0100PA00X+086000Y+186000               S0      
317GND              VIA        MD0100PA00X+086000Y+188000               S0      
317GND              VIA        MD0100PA00X+086000Y+198000               S0      
317GND              VIA        MD0100PA00X+086000Y+002000               S0      
317GND              VIA        MD0100PA00X+086000Y+024000               S0      
317GND              VIA        MD0100PA00X+086000Y+026000               S0      
317GND              VIA        MD0100PA00X+086000Y+004000               S0      
317GND              VIA        MD0100PA00X+086000Y+040000               S0      
317GND              VIA        MD0100PA00X+086000Y+042000               S0      
317GND              VIA        MD0100PA00X+086000Y+044000               S0      
317GND              VIA        MD0100PA00X+086000Y+046000               S0      
317GND              VIA        MD0100PA00X+086000Y+048000               S0      
317GND              VIA        MD0100PA00X+086000Y+050000               S0      
317GND              VIA        MD0100PA00X+086000Y+052000               S0      
317GND              VIA        MD0100PA00X+086000Y+056000               S0      
317GND              VIA        MD0100PA00X+086000Y+058000               S0      
317GND              VIA        MD0100PA00X+086000Y+006000               S0      
317GND              VIA        MD0100PA00X+086000Y+060000               S0      
317GND              VIA        MD0100PA00X+086000Y+008000               S0      
317GND              VIA        MD0100PA00X+086000Y+080000               S0      
317GND              VIA        MD0100PA00X+086000Y+082000               S0      
317GND              VIA        MD0100PA00X+086000Y+084000               S0      
317GND              VIA        MD0100PA00X+086000Y+086000               S0      
317GND              VIA        MD0100PA00X+086000Y+088000               S0      
317GND              VIA        MD0100PA00X+086000Y+090000               S0      
317GND              VIA        MD0100PA00X+086000Y+092000               S0      
317GND              VIA        MD0100PA00X+086000Y+098000               S0      
317GND              VIA        MD0100PA00X+086010Y+033300               S0      
317GND              VIA        MD0100PA00X+086010Y+033650               S0      
317GND              VIA        MD0100PA00X+086329Y+148071               S0      
317GND              VIA        MD0100PA00X+086329Y+148614               S0      
317GND              VIA        MD0100PA00X+086329Y+188623               S0      
317GND              VIA        MD0100PA00X+086329Y+189165               S0      
317GND              VIA        MD0100PA00X+086329Y+066969               S0      
317GND              VIA        MD0100PA00X+086329Y+067511               S0      
317GND              VIA        MD0100PA00X+086331Y+026410               S0      
317GND              VIA        MD0100PA00X+086331Y+026968               S0      
317GND              VIA        MD0100PA00X+086331Y+107513               S0      
317GND              VIA        MD0100PA00X+086331Y+108070               S0      
317GND              VIA        MD0100PA00X+086335Y+111279               S0      
317GND              VIA        MD0100PA00X+086335Y+111863               S0      
317GND              VIA        MD0100PA00X+086335Y+192382               S0      
317GND              VIA        MD0100PA00X+086335Y+192965               S0      
317GND              VIA        MD0100PA00X+086335Y+030177               S0      
317GND              VIA        MD0100PA00X+086335Y+030760               S0      
317GND              VIA        MD0100PA00X+086335Y+151830               S0      
317GND              VIA        MD0100PA00X+086335Y+152414               S0      
317GND              VIA        MD0100PA00X+086340Y+070711               S0      
317GND              VIA        MD0100PA00X+086340Y+071328               S0      
317GND              VIA        MD0100PA00X+086344Y+102413               S0      
317GND              VIA        MD0100PA00X+086344Y+103091               S0      
317GND              VIA        MD0100PA00X+086344Y+109363               S0      
317GND              VIA        MD0100PA00X+086344Y+110000               S0      
317GND              VIA        MD0100PA00X+086344Y+142964               S0      
317GND              VIA        MD0100PA00X+086344Y+143643               S0      
317GND              VIA        MD0100PA00X+086344Y+149914               S0      
317GND              VIA        MD0100PA00X+086344Y+150551               S0      
317GND              VIA        MD0100PA00X+086344Y+183515               S0      
317GND              VIA        MD0100PA00X+086344Y+184194               S0      
317GND              VIA        MD0100PA00X+086344Y+190465               S0      
317GND              VIA        MD0100PA00X+086344Y+191102               S0      
317GND              VIA        MD0100PA00X+086344Y+021310               S0      
317GND              VIA        MD0100PA00X+086344Y+021989               S0      
317GND              VIA        MD0100PA00X+086344Y+028260               S0      
317GND              VIA        MD0100PA00X+086344Y+028897               S0      
317GND              VIA        MD0100PA00X+086344Y+061861               S0      
317GND              VIA        MD0100PA00X+086344Y+062540               S0      
317GND              VIA        MD0100PA00X+086344Y+068811               S0      
317GND              VIA        MD0100PA00X+086344Y+069448               S0      
317GND              VIA        MD0100PA00X+086400Y+118190               S0      
317GND              VIA        MD0100PA00X+086450Y+077650               S0      
317GND              VIA        MD0100PA00X+086500Y+037100               S0      
317GND              VIA        MD0100PA00X+086550Y+158900               S0      
317GND              VIA        MD0100PA00X+086750Y+118190               S0      
317GND              VIA        MD0100PA00X+086750Y+187000               S0      
317GND              VIA        MD0100PA00X+086800Y+077650               S0      
317GND              VIA        MD0100PA00X+086850Y+105950               S0      
317GND              VIA        MD0100PA00X+086850Y+146500               S0      
317GND              VIA        MD0100PA00X+086850Y+037100               S0      
317GND              VIA        MD0100PA00X+086850Y+065400               S0      
317GND              VIA        MD0100PA00X+086900Y+158900               S0      
317GND              VIA        MD0100PA00X+086925Y+014475               S0      
317GND              VIA        MD0100PA00X+008708Y+076825               S0      
317GND              VIA        MD0100PA00X+087002Y+000550               S0      
317GND              VIA        MD0100PA00X+087200Y+077650               S0      
317GND              VIA        MD0100PA00X+087220Y+118190               S0      
317GND              VIA        MD0100PA00X+087250Y+024150               S0      
317GND              VIA        MD0100PA00X+087250Y+037100               S0      
317GND              VIA        MD0100PA00X+087256Y+198663               S0      
317GND              VIA        MD0100PA00X+087288Y+134649               S0      
317GND              VIA        MD0100PA00X+087288Y+175160               S0      
317GND              VIA        MD0100PA00X+087288Y+053528               S0      
317GND              VIA        MD0100PA00X+087288Y+094093               S0      
317GND              VIA        MD0100PA00X+087300Y+158900               S0      
317GND              VIA        MD0100PA00X+087330Y+154910               S0      
317GND              VIA        MD0100PA00X+087340Y+073840               S0      
317GND              VIA        MD0100PA00X+087360Y+033220               S0      
317GND              VIA        MD0100PA00X+087396Y+167200               S0      
317GND              VIA        MD0100PA00X+087396Y+167650               S0      
317GND              VIA        MD0100PA00X+087396Y+168150               S0      
317GND              VIA        MD0100PA00X+087396Y+168550               S0      
317GND              VIA        MD0100PA00X+087420Y+114400               S0      
317GND              VIA        MD0100PA00X+087550Y+077650               S0      
317GND              VIA        MD0100PA00X+087570Y+118190               S0      
317GND              VIA        MD0100PA00X+087600Y+037100               S0      
317GND              VIA        MD0100PA00X+087644Y+102280               S0      
317GND              VIA        MD0100PA00X+087644Y+103224               S0      
317GND              VIA        MD0100PA00X+087644Y+104169               S0      
317GND              VIA        MD0100PA00X+087644Y+104799               S0      
317GND              VIA        MD0100PA00X+087644Y+105744               S0      
317GND              VIA        MD0100PA00X+087644Y+106689               S0      
317GND              VIA        MD0100PA00X+087644Y+107319               S0      
317GND              VIA        MD0100PA00X+087644Y+108264               S0      
317GND              VIA        MD0100PA00X+087644Y+109209               S0      
317GND              VIA        MD0100PA00X+087644Y+110154               S0      
317GND              VIA        MD0100PA00X+087644Y+111098               S0      
317GND              VIA        MD0100PA00X+087644Y+112043               S0      
317GND              VIA        MD0100PA00X+087644Y+112988               S0      
317GND              VIA        MD0100PA00X+087644Y+142831               S0      
317GND              VIA        MD0100PA00X+087644Y+143776               S0      
317GND              VIA        MD0100PA00X+087644Y+144721               S0      
317GND              VIA        MD0100PA00X+087644Y+145350               S0      
317GND              VIA        MD0100PA00X+087644Y+146295               S0      
317GND              VIA        MD0100PA00X+087644Y+147240               S0      
317GND              VIA        MD0100PA00X+087644Y+147870               S0      
317GND              VIA        MD0100PA00X+087644Y+148815               S0      
317GND              VIA        MD0100PA00X+087644Y+149760               S0      
317GND              VIA        MD0100PA00X+087644Y+150705               S0      
317GND              VIA        MD0100PA00X+087644Y+151650               S0      
317GND              VIA        MD0100PA00X+087644Y+152595               S0      
317GND              VIA        MD0100PA00X+087644Y+153539               S0      
317GND              VIA        MD0100PA00X+087644Y+183382               S0      
317GND              VIA        MD0100PA00X+087644Y+184327               S0      
317GND              VIA        MD0100PA00X+087644Y+185272               S0      
317GND              VIA        MD0100PA00X+087644Y+185902               S0      
317GND              VIA        MD0100PA00X+087644Y+186846               S0      
317GND              VIA        MD0100PA00X+087644Y+187791               S0      
317GND              VIA        MD0100PA00X+087644Y+188421               S0      
317GND              VIA        MD0100PA00X+087644Y+189366               S0      
317GND              VIA        MD0100PA00X+087644Y+190311               S0      
317GND              VIA        MD0100PA00X+087644Y+191256               S0      
317GND              VIA        MD0100PA00X+087644Y+192201               S0      
317GND              VIA        MD0100PA00X+087644Y+193146               S0      
317GND              VIA        MD0100PA00X+087644Y+194091               S0      
317GND              VIA        MD0100PA00X+087644Y+021177               S0      
317GND              VIA        MD0100PA00X+087644Y+022122               S0      
317GND              VIA        MD0100PA00X+087644Y+023067               S0      
317GND              VIA        MD0100PA00X+087644Y+023697               S0      
317GND              VIA        MD0100PA00X+087644Y+024642               S0      
317GND              VIA        MD0100PA00X+087644Y+025587               S0      
317GND              VIA        MD0100PA00X+087644Y+026216               S0      
317GND              VIA        MD0100PA00X+087644Y+027161               S0      
317GND              VIA        MD0100PA00X+087644Y+028106               S0      
317GND              VIA        MD0100PA00X+087644Y+029051               S0      
317GND              VIA        MD0100PA00X+087644Y+029996               S0      
317GND              VIA        MD0100PA00X+087644Y+030941               S0      
317GND              VIA        MD0100PA00X+087644Y+031886               S0      
317GND              VIA        MD0100PA00X+087644Y+061728               S0      
317GND              VIA        MD0100PA00X+087644Y+062673               S0      
317GND              VIA        MD0100PA00X+087644Y+063618               S0      
317GND              VIA        MD0100PA00X+087644Y+064248               S0      
317GND              VIA        MD0100PA00X+087644Y+065193               S0      
317GND              VIA        MD0100PA00X+087644Y+066138               S0      
317GND              VIA        MD0100PA00X+087644Y+066768               S0      
317GND              VIA        MD0100PA00X+087644Y+067713               S0      
317GND              VIA        MD0100PA00X+087644Y+068658               S0      
317GND              VIA        MD0100PA00X+087644Y+069602               S0      
317GND              VIA        MD0100PA00X+087644Y+070547               S0      
317GND              VIA        MD0100PA00X+087644Y+071492               S0      
317GND              VIA        MD0100PA00X+087644Y+072437               S0      
317GND              VIA        MD0100PA00X+087650Y+158900               S0      
317GND              VIA        MD0100PA00X+008790Y+117330               S0      
317GND              VIA        MD0100PA00X+087960Y+038520               S0      
317GND              VIA        MD0100PA00X+008808Y+157592               S0      
317GND              VIA        MD0100PA00X+088000Y+010000               S0      
317GND              VIA        MD0100PA00X+088000Y+100000               S0      
317GND              VIA        MD0100PA00X+088000Y+012000               S0      
317GND              VIA        MD0100PA00X+088000Y+120000               S0      
317GND              VIA        MD0100PA00X+088000Y+122000               S0      
317GND              VIA        MD0100PA00X+088000Y+124000               S0      
317GND              VIA        MD0100PA00X+088000Y+126000               S0      
317GND              VIA        MD0100PA00X+088000Y+128000               S0      
317GND              VIA        MD0100PA00X+088000Y+130000               S0      
317GND              VIA        MD0100PA00X+088000Y+132000               S0      
317GND              VIA        MD0100PA00X+088000Y+134000               S0      
317GND              VIA        MD0100PA00X+088000Y+159900               S0      
317GND              VIA        MD0100PA00X+088000Y+018000               S0      
317GND              VIA        MD0100PA00X+088000Y+002000               S0      
317GND              VIA        MD0100PA00X+088000Y+004000               S0      
317GND              VIA        MD0100PA00X+088000Y+040000               S0      
317GND              VIA        MD0100PA00X+088000Y+042000               S0      
317GND              VIA        MD0100PA00X+088000Y+044000               S0      
317GND              VIA        MD0100PA00X+088000Y+046000               S0      
317GND              VIA        MD0100PA00X+088000Y+048000               S0      
317GND              VIA        MD0100PA00X+088000Y+050000               S0      
317GND              VIA        MD0100PA00X+088000Y+052000               S0      
317GND              VIA        MD0100PA00X+088000Y+058000               S0      
317GND              VIA        MD0100PA00X+088000Y+006000               S0      
317GND              VIA        MD0100PA00X+088000Y+060000               S0      
317GND              VIA        MD0100PA00X+088000Y+008000               S0      
317GND              VIA        MD0100PA00X+088000Y+080000               S0      
317GND              VIA        MD0100PA00X+088000Y+082000               S0      
317GND              VIA        MD0100PA00X+088000Y+084000               S0      
317GND              VIA        MD0100PA00X+088000Y+086000               S0      
317GND              VIA        MD0100PA00X+088000Y+088000               S0      
317GND              VIA        MD0100PA00X+088000Y+090000               S0      
317GND              VIA        MD0100PA00X+088000Y+092000               S0      
317GND              VIA        MD0100PA00X+088575Y+170150               S0      
317GND              VIA        MD0100PA00X+088599Y+013489               S0      
317GND              VIA        MD0100PA00X+088652Y+094592               S0      
317GND              VIA        MD0100PA00X+088660Y+175610               S0      
317GND              VIA        MD0100PA00X+089002Y+000550               S0      
317GND              VIA        MD0100PA00X+089100Y+172000               S0      
317GND              VIA        MD0100PA00X+089125Y+134850               S0      
317GND              VIA        MD0100PA00X+089125Y+053750               S0      
317GND              VIA        MD0100PA00X+089655Y+198657               S0      
317GND              VIA        MD0100PA00X+089990Y+038230               S0      
317GND              VIA        MD0100PA00X+089994Y+101494               S0      
317GND              VIA        MD0100PA00X+089994Y+102994               S0      
317GND              VIA        MD0100PA00X+089994Y+104494               S0      
317GND              VIA        MD0100PA00X+089994Y+108994               S0      
317GND              VIA        MD0100PA00X+089994Y+109494               S0      
317GND              VIA        MD0100PA00X+089994Y+142045               S0      
317GND              VIA        MD0100PA00X+089994Y+143545               S0      
317GND              VIA        MD0100PA00X+089994Y+145045               S0      
317GND              VIA        MD0100PA00X+089994Y+149545               S0      
317GND              VIA        MD0100PA00X+089994Y+150045               S0      
317GND              VIA        MD0100PA00X+089994Y+182597               S0      
317GND              VIA        MD0100PA00X+089994Y+184097               S0      
317GND              VIA        MD0100PA00X+089994Y+185596               S0      
317GND              VIA        MD0100PA00X+089994Y+190097               S0      
317GND              VIA        MD0100PA00X+089994Y+190596               S0      
317GND              VIA        MD0100PA00X+089994Y+020392               S0      
317GND              VIA        MD0100PA00X+089994Y+021892               S0      
317GND              VIA        MD0100PA00X+089994Y+023392               S0      
317GND              VIA        MD0100PA00X+089994Y+027892               S0      
317GND              VIA        MD0100PA00X+089994Y+028392               S0      
317GND              VIA        MD0100PA00X+089994Y+060943               S0      
317GND              VIA        MD0100PA00X+089994Y+062443               S0      
317GND              VIA        MD0100PA00X+089994Y+063943               S0      
317GND              VIA        MD0100PA00X+089994Y+068443               S0      
317GND              VIA        MD0100PA00X+089994Y+068943               S0      
317GND              VIA        MD0100PA00X+009002Y+000550               S0      
317GND              VIA        MD0100PA00X+090000Y+010000               S0      
317GND              VIA        MD0100PA00X+090000Y+100000               S0      
317GND              VIA        MD0100PA00X+090000Y+102000               S0      
317GND              VIA        MD0100PA00X+090000Y+104000               S0      
317GND              VIA        MD0100PA00X+090000Y+108000               S0      
317GND              VIA        MD0100PA00X+090000Y+012000               S0      
317GND              VIA        MD0100PA00X+090000Y+120000               S0      
317GND              VIA        MD0100PA00X+090000Y+122000               S0      
317GND              VIA        MD0100PA00X+090000Y+124000               S0      
317GND              VIA        MD0100PA00X+090000Y+126000               S0      
317GND              VIA        MD0100PA00X+090000Y+128000               S0      
317GND              VIA        MD0100PA00X+090000Y+130000               S0      
317GND              VIA        MD0100PA00X+090000Y+132000               S0      
317GND              VIA        MD0100PA00X+090000Y+160000               S0      
317GND              VIA        MD0100PA00X+090000Y+002000               S0      
317GND              VIA        MD0100PA00X+090000Y+004000               S0      
317GND              VIA        MD0100PA00X+090000Y+040000               S0      
317GND              VIA        MD0100PA00X+090000Y+042000               S0      
317GND              VIA        MD0100PA00X+090000Y+044000               S0      
317GND              VIA        MD0100PA00X+090000Y+046000               S0      
317GND              VIA        MD0100PA00X+090000Y+048000               S0      
317GND              VIA        MD0100PA00X+090000Y+050000               S0      
317GND              VIA        MD0100PA00X+090000Y+052000               S0      
317GND              VIA        MD0100PA00X+090000Y+006000               S0      
317GND              VIA        MD0100PA00X+090000Y+060000               S0      
317GND              VIA        MD0100PA00X+090000Y+008000               S0      
317GND              VIA        MD0100PA00X+090000Y+080000               S0      
317GND              VIA        MD0100PA00X+090000Y+082000               S0      
317GND              VIA        MD0100PA00X+090000Y+084000               S0      
317GND              VIA        MD0100PA00X+090000Y+086000               S0      
317GND              VIA        MD0100PA00X+090000Y+088000               S0      
317GND              VIA        MD0100PA00X+090000Y+090000               S0      
317GND              VIA        MD0100PA00X+090000Y+092000               S0      
317GND              VIA        MD0100PA00X+090150Y+112350               S0      
317GND              VIA        MD0100PA00X+090150Y+152900               S0      
317GND              VIA        MD0100PA00X+090150Y+193450               S0      
317GND              VIA        MD0100PA00X+090150Y+031250               S0      
317GND              VIA        MD0100PA00X+090150Y+071800               S0      
317GND              VIA        MD0100PA00X+090484Y+104213               S0      
317GND              VIA        MD0100PA00X+090484Y+144764               S0      
317GND              VIA        MD0100PA00X+090484Y+185315               S0      
317GND              VIA        MD0100PA00X+090484Y+023111               S0      
317GND              VIA        MD0100PA00X+090484Y+063661               S0      
317GND              VIA        MD0100PA00X+009050Y+152150               S0      
317GND              VIA        MD0100PA00X+090600Y+171350               S0      
317GND              VIA        MD0100PA00X+090650Y+173410               S0      
317GND              VIA        MD0100PA00X+090749Y+135305               S0      
317GND              VIA        MD0100PA00X+090749Y+175856               S0      
317GND              VIA        MD0100PA00X+090749Y+054203               S0      
317GND              VIA        MD0100PA00X+090749Y+094754               S0      
317GND              VIA        MD0100PA00X+090849Y+013651               S0      
317GND              VIA        MD0100PA00X+090865Y+104213               S0      
317GND              VIA        MD0100PA00X+090865Y+144764               S0      
317GND              VIA        MD0100PA00X+090865Y+185315               S0      
317GND              VIA        MD0100PA00X+090865Y+023111               S0      
317GND              VIA        MD0100PA00X+090865Y+063661               S0      
317GND              VIA        MD0100PA00X+091002Y+000550               S0      
317GND              VIA        MD0100PA00X+009112Y+156590               S0      
317GND              VIA        MD0100PA00X+091256Y+198663               S0      
317GND              VIA        MD0100PA00X+091650Y+172950               S0      
317GND              VIA        MD0100PA00X+091900Y+145073               S0      
317GND              VIA        MD0100PA00X+091900Y+146254               S0      
317GND              VIA        MD0100PA00X+091900Y+185625               S0      
317GND              VIA        MD0100PA00X+091900Y+186805               S0      
317GND              VIA        MD0100PA00X+091900Y+063972               S0      
317GND              VIA        MD0100PA00X+091900Y+065151               S0      
317GND              VIA        MD0100PA00X+092000Y+010000               S0      
317GND              VIA        MD0100PA00X+092000Y+100000               S0      
317GND              VIA        MD0100PA00X+092000Y+102000               S0      
317GND              VIA        MD0100PA00X+092000Y+104000               S0      
317GND              VIA        MD0100PA00X+092000Y+106000               S0      
317GND              VIA        MD0100PA00X+092000Y+108000               S0      
317GND              VIA        MD0100PA00X+092000Y+112000               S0      
317GND              VIA        MD0100PA00X+092000Y+114000               S0      
317GND              VIA        MD0100PA00X+092000Y+012000               S0      
317GND              VIA        MD0100PA00X+092000Y+120000               S0      
317GND              VIA        MD0100PA00X+092000Y+122000               S0      
317GND              VIA        MD0100PA00X+092000Y+124000               S0      
317GND              VIA        MD0100PA00X+092000Y+126000               S0      
317GND              VIA        MD0100PA00X+092000Y+128000               S0      
317GND              VIA        MD0100PA00X+092000Y+130000               S0      
317GND              VIA        MD0100PA00X+092000Y+132000               S0      
317GND              VIA        MD0100PA00X+092000Y+134000               S0      
317GND              VIA        MD0100PA00X+092000Y+140000               S0      
317GND              VIA        MD0100PA00X+092000Y+144000               S0      
317GND              VIA        MD0100PA00X+092000Y+148000               S0      
317GND              VIA        MD0100PA00X+092000Y+152000               S0      
317GND              VIA        MD0100PA00X+092000Y+154000               S0      
317GND              VIA        MD0100PA00X+092000Y+160000               S0      
317GND              VIA        MD0100PA00X+092000Y+180000               S0      
317GND              VIA        MD0100PA00X+092000Y+184000               S0      
317GND              VIA        MD0100PA00X+092000Y+188000               S0      
317GND              VIA        MD0100PA00X+092000Y+190000               S0      
317GND              VIA        MD0100PA00X+092000Y+192000               S0      
317GND              VIA        MD0100PA00X+092000Y+194000               S0      
317GND              VIA        MD0100PA00X+092000Y+196000               S0      
317GND              VIA        MD0100PA00X+092000Y+198000               S0      
317GND              VIA        MD0100PA00X+092000Y+002000               S0      
317GND              VIA        MD0100PA00X+092000Y+028000               S0      
317GND              VIA        MD0100PA00X+092000Y+030000               S0      
317GND              VIA        MD0100PA00X+092000Y+032000               S0      
317GND              VIA        MD0100PA00X+092000Y+034000               S0      
317GND              VIA        MD0100PA00X+092000Y+036000               S0      
317GND              VIA        MD0100PA00X+092000Y+038000               S0      
317GND              VIA        MD0100PA00X+092000Y+004000               S0      
317GND              VIA        MD0100PA00X+092000Y+040000               S0      
317GND              VIA        MD0100PA00X+092000Y+042000               S0      
317GND              VIA        MD0100PA00X+092000Y+044000               S0      
317GND              VIA        MD0100PA00X+092000Y+046000               S0      
317GND              VIA        MD0100PA00X+092000Y+048000               S0      
317GND              VIA        MD0100PA00X+092000Y+050000               S0      
317GND              VIA        MD0100PA00X+092000Y+052000               S0      
317GND              VIA        MD0100PA00X+092000Y+058000               S0      
317GND              VIA        MD0100PA00X+092000Y+006000               S0      
317GND              VIA        MD0100PA00X+092000Y+060000               S0      
317GND              VIA        MD0100PA00X+092000Y+066000               S0      
317GND              VIA        MD0100PA00X+092000Y+068000               S0      
317GND              VIA        MD0100PA00X+092000Y+070000               S0      
317GND              VIA        MD0100PA00X+092000Y+072000               S0      
317GND              VIA        MD0100PA00X+092000Y+074000               S0      
317GND              VIA        MD0100PA00X+092000Y+076000               S0      
317GND              VIA        MD0100PA00X+092000Y+078000               S0      
317GND              VIA        MD0100PA00X+092000Y+008000               S0      
317GND              VIA        MD0100PA00X+092000Y+080000               S0      
317GND              VIA        MD0100PA00X+092000Y+082000               S0      
317GND              VIA        MD0100PA00X+092000Y+084000               S0      
317GND              VIA        MD0100PA00X+092000Y+086000               S0      
317GND              VIA        MD0100PA00X+092000Y+088000               S0      
317GND              VIA        MD0100PA00X+092000Y+090000               S0      
317GND              VIA        MD0100PA00X+092000Y+092000               S0      
317GND              VIA        MD0100PA00X+092140Y+023500               S0      
317GND              VIA        MD0100PA00X+092140Y+024520               S0      
317GND              VIA        MD0100PA00X+092290Y+104805               S0      
317GND              VIA        MD0100PA00X+092290Y+105420               S0      
317GND              VIA        MD0100PA00X+092300Y+116020               S0      
317GND              VIA        MD0100PA00X+092300Y+118020               S0      
317GND              VIA        MD0100PA00X+092350Y+157980               S0      
317GND              VIA        MD0100PA00X+092380Y+155930               S0      
317GND              VIA        MD0100PA00X+009256Y+198663               S0      
317GND              VIA        MD0100PA00X+092550Y+173800               S0      
317GND              VIA        MD0100PA00X+093002Y+000550               S0      
317GND              VIA        MD0100PA00X+093256Y+198663               S0      
317GND              VIA        MD0100PA00X+093300Y+170400               S0      
317GND              VIA        MD0100PA00X+093300Y+173650               S0      
317GND              VIA        MD0100PA00X+009360Y+184820               S0      
317GND              VIA        MD0100PA00X+094000Y+010000               S0      
317GND              VIA        MD0100PA00X+094000Y+100000               S0      
317GND              VIA        MD0100PA00X+094000Y+102000               S0      
317GND              VIA        MD0100PA00X+094000Y+104000               S0      
317GND              VIA        MD0100PA00X+094000Y+106000               S0      
317GND              VIA        MD0100PA00X+094000Y+108000               S0      
317GND              VIA        MD0100PA00X+094000Y+110000               S0      
317GND              VIA        MD0100PA00X+094000Y+112000               S0      
317GND              VIA        MD0100PA00X+094000Y+114000               S0      
317GND              VIA        MD0100PA00X+094000Y+116000               S0      
317GND              VIA        MD0100PA00X+094000Y+118000               S0      
317GND              VIA        MD0100PA00X+094000Y+012000               S0      
317GND              VIA        MD0100PA00X+094000Y+120000               S0      
317GND              VIA        MD0100PA00X+094000Y+122000               S0      
317GND              VIA        MD0100PA00X+094000Y+124000               S0      
317GND              VIA        MD0100PA00X+094000Y+126000               S0      
317GND              VIA        MD0100PA00X+094000Y+128000               S0      
317GND              VIA        MD0100PA00X+094000Y+130000               S0      
317GND              VIA        MD0100PA00X+094000Y+132000               S0      
317GND              VIA        MD0100PA00X+094000Y+134000               S0      
317GND              VIA        MD0100PA00X+094000Y+014000               S0      
317GND              VIA        MD0100PA00X+094000Y+140000               S0      
317GND              VIA        MD0100PA00X+094000Y+016000               S0      
317GND              VIA        MD0100PA00X+094000Y+176000               S0      
317GND              VIA        MD0100PA00X+094000Y+018000               S0      
317GND              VIA        MD0100PA00X+094000Y+180000               S0      
317GND              VIA        MD0100PA00X+094000Y+182000               S0      
317GND              VIA        MD0100PA00X+094000Y+184000               S0      
317GND              VIA        MD0100PA00X+094000Y+186000               S0      
317GND              VIA        MD0100PA00X+094000Y+188000               S0      
317GND              VIA        MD0100PA00X+094000Y+190000               S0      
317GND              VIA        MD0100PA00X+094000Y+192000               S0      
317GND              VIA        MD0100PA00X+094000Y+194000               S0      
317GND              VIA        MD0100PA00X+094000Y+196000               S0      
317GND              VIA        MD0100PA00X+094000Y+198000               S0      
317GND              VIA        MD0100PA00X+094000Y+002000               S0      
317GND              VIA        MD0100PA00X+094000Y+020000               S0      
317GND              VIA        MD0100PA00X+094000Y+022000               S0      
317GND              VIA        MD0100PA00X+094000Y+024000               S0      
317GND              VIA        MD0100PA00X+094000Y+026000               S0      
317GND              VIA        MD0100PA00X+094000Y+028000               S0      
317GND              VIA        MD0100PA00X+094000Y+030000               S0      
317GND              VIA        MD0100PA00X+094000Y+032000               S0      
317GND              VIA        MD0100PA00X+094000Y+034000               S0      
317GND              VIA        MD0100PA00X+094000Y+036000               S0      
317GND              VIA        MD0100PA00X+094000Y+038000               S0      
317GND              VIA        MD0100PA00X+094000Y+004000               S0      
317GND              VIA        MD0100PA00X+094000Y+040000               S0      
317GND              VIA        MD0100PA00X+094000Y+042000               S0      
317GND              VIA        MD0100PA00X+094000Y+044000               S0      
317GND              VIA        MD0100PA00X+094000Y+046000               S0      
317GND              VIA        MD0100PA00X+094000Y+048000               S0      
317GND              VIA        MD0100PA00X+094000Y+050000               S0      
317GND              VIA        MD0100PA00X+094000Y+052000               S0      
317GND              VIA        MD0100PA00X+094000Y+058000               S0      
317GND              VIA        MD0100PA00X+094000Y+006000               S0      
317GND              VIA        MD0100PA00X+094000Y+060000               S0      
317GND              VIA        MD0100PA00X+094000Y+062000               S0      
317GND              VIA        MD0100PA00X+094000Y+064000               S0      
317GND              VIA        MD0100PA00X+094000Y+066000               S0      
317GND              VIA        MD0100PA00X+094000Y+068000               S0      
317GND              VIA        MD0100PA00X+094000Y+070000               S0      
317GND              VIA        MD0100PA00X+094000Y+072000               S0      
317GND              VIA        MD0100PA00X+094000Y+074000               S0      
317GND              VIA        MD0100PA00X+094000Y+076000               S0      
317GND              VIA        MD0100PA00X+094000Y+078000               S0      
317GND              VIA        MD0100PA00X+094000Y+008000               S0      
317GND              VIA        MD0100PA00X+094000Y+080000               S0      
317GND              VIA        MD0100PA00X+094000Y+082000               S0      
317GND              VIA        MD0100PA00X+094000Y+084000               S0      
317GND              VIA        MD0100PA00X+094000Y+086000               S0      
317GND              VIA        MD0100PA00X+094000Y+088000               S0      
317GND              VIA        MD0100PA00X+094000Y+090000               S0      
317GND              VIA        MD0100PA00X+094000Y+092000               S0      
317GND              VIA        MD0100PA00X+094000Y+094000               S0      
317GND              VIA        MD0100PA00X+009470Y+197410               S0      
317GND              VIA        MD0100PA00X+009470Y+059980               S0      
317GND              VIA        MD0100PA00X+095002Y+000550               S0      
317GND              VIA        MD0100PA00X+095150Y+165800               S0      
317GND              VIA        MD0100PA00X+095200Y+167800               S0      
317GND              VIA        MD0100PA00X+095256Y+198663               S0      
317GND              VIA        MD0100PA00X+095430Y+141260               S0      
317GND              VIA        MD0100PA00X+009570Y+121970               S0      
317GND              VIA        MD0100PA00X+009585Y+036156               S0      
317GND              VIA        MD0100PA00X+009600Y+010791               S0      
317GND              VIA        MD0100PA00X+009600Y+011421               S0      
317GND              VIA        MD0100PA00X+009600Y+012366               S0      
317GND              VIA        MD0100PA00X+009600Y+126776               S0      
317GND              VIA        MD0100PA00X+009600Y+127721               S0      
317GND              VIA        MD0100PA00X+009600Y+128665               S0      
317GND              VIA        MD0100PA00X+009600Y+129610               S0      
317GND              VIA        MD0100PA00X+009600Y+130555               S0      
317GND              VIA        MD0100PA00X+009600Y+131500               S0      
317GND              VIA        MD0100PA00X+009600Y+132445               S0      
317GND              VIA        MD0100PA00X+009600Y+133075               S0      
317GND              VIA        MD0100PA00X+009600Y+013400               S0      
317GND              VIA        MD0100PA00X+009600Y+134020               S0      
317GND              VIA        MD0100PA00X+009600Y+135050               S0      
317GND              VIA        MD0100PA00X+009600Y+135594               S0      
317GND              VIA        MD0100PA00X+009600Y+136539               S0      
317GND              VIA        MD0100PA00X+009600Y+137484               S0      
317GND              VIA        MD0100PA00X+009600Y+013941               S0      
317GND              VIA        MD0100PA00X+009600Y+014886               S0      
317GND              VIA        MD0100PA00X+009600Y+154110               S0      
317GND              VIA        MD0100PA00X+009600Y+015831               S0      
317GND              VIA        MD0100PA00X+009600Y+167327               S0      
317GND              VIA        MD0100PA00X+009600Y+168272               S0      
317GND              VIA        MD0100PA00X+009600Y+169217               S0      
317GND              VIA        MD0100PA00X+009600Y+170162               S0      
317GND              VIA        MD0100PA00X+009600Y+171106               S0      
317GND              VIA        MD0100PA00X+009600Y+172051               S0      
317GND              VIA        MD0100PA00X+009600Y+172996               S0      
317GND              VIA        MD0100PA00X+009600Y+173626               S0      
317GND              VIA        MD0100PA00X+009600Y+174511               S0      
317GND              VIA        MD0100PA00X+009600Y+175516               S0      
317GND              VIA        MD0100PA00X+009600Y+176146               S0      
317GND              VIA        MD0100PA00X+009600Y+177091               S0      
317GND              VIA        MD0100PA00X+009600Y+178036               S0      
317GND              VIA        MD0100PA00X+009600Y+045673               S0      
317GND              VIA        MD0100PA00X+009600Y+046618               S0      
317GND              VIA        MD0100PA00X+009600Y+047563               S0      
317GND              VIA        MD0100PA00X+009600Y+048508               S0      
317GND              VIA        MD0100PA00X+009600Y+049453               S0      
317GND              VIA        MD0100PA00X+009600Y+050398               S0      
317GND              VIA        MD0100PA00X+009600Y+051343               S0      
317GND              VIA        MD0100PA00X+009600Y+051972               S0      
317GND              VIA        MD0100PA00X+009600Y+052917               S0      
317GND              VIA        MD0100PA00X+009600Y+053950               S0      
317GND              VIA        MD0100PA00X+009600Y+054492               S0      
317GND              VIA        MD0100PA00X+009600Y+055437               S0      
317GND              VIA        MD0100PA00X+009600Y+056382               S0      
317GND              VIA        MD0100PA00X+009600Y+006087               S0      
317GND              VIA        MD0100PA00X+009600Y+007012               S0      
317GND              VIA        MD0100PA00X+009600Y+007957               S0      
317GND              VIA        MD0100PA00X+009600Y+086224               S0      
317GND              VIA        MD0100PA00X+009600Y+087169               S0      
317GND              VIA        MD0100PA00X+009600Y+088114               S0      
317GND              VIA        MD0100PA00X+009600Y+008902               S0      
317GND              VIA        MD0100PA00X+009600Y+089059               S0      
317GND              VIA        MD0100PA00X+009600Y+090004               S0      
317GND              VIA        MD0100PA00X+009600Y+090949               S0      
317GND              VIA        MD0100PA00X+009600Y+091894               S0      
317GND              VIA        MD0100PA00X+009600Y+092524               S0      
317GND              VIA        MD0100PA00X+009600Y+093469               S0      
317GND              VIA        MD0100PA00X+009600Y+094500               S0      
317GND              VIA        MD0100PA00X+009600Y+095043               S0      
317GND              VIA        MD0100PA00X+009600Y+095988               S0      
317GND              VIA        MD0100PA00X+009600Y+096933               S0      
317GND              VIA        MD0100PA00X+009600Y+009846               S0      
317GND              VIA        MD0100PA00X+096000Y+010000               S0      
317GND              VIA        MD0100PA00X+096000Y+100000               S0      
317GND              VIA        MD0100PA00X+096000Y+102000               S0      
317GND              VIA        MD0100PA00X+096000Y+104000               S0      
317GND              VIA        MD0100PA00X+096000Y+106000               S0      
317GND              VIA        MD0100PA00X+096000Y+108000               S0      
317GND              VIA        MD0100PA00X+096000Y+110000               S0      
317GND              VIA        MD0100PA00X+096000Y+112000               S0      
317GND              VIA        MD0100PA00X+096000Y+114000               S0      
317GND              VIA        MD0100PA00X+096000Y+116000               S0      
317GND              VIA        MD0100PA00X+096000Y+118000               S0      
317GND              VIA        MD0100PA00X+096000Y+012000               S0      
317GND              VIA        MD0100PA00X+096000Y+120000               S0      
317GND              VIA        MD0100PA00X+096000Y+122000               S0      
317GND              VIA        MD0100PA00X+096000Y+124000               S0      
317GND              VIA        MD0100PA00X+096000Y+126000               S0      
317GND              VIA        MD0100PA00X+096000Y+128000               S0      
317GND              VIA        MD0100PA00X+096000Y+130000               S0      
317GND              VIA        MD0100PA00X+096000Y+132000               S0      
317GND              VIA        MD0100PA00X+096000Y+134000               S0      
317GND              VIA        MD0100PA00X+096000Y+136000               S0      
317GND              VIA        MD0100PA00X+096000Y+138000               S0      
317GND              VIA        MD0100PA00X+096000Y+014000               S0      
317GND              VIA        MD0100PA00X+096000Y+140000               S0      
317GND              VIA        MD0100PA00X+096000Y+016000               S0      
317GND              VIA        MD0100PA00X+096000Y+170000               S0      
317GND              VIA        MD0100PA00X+096000Y+172000               S0      
317GND              VIA        MD0100PA00X+096000Y+174000               S0      
317GND              VIA        MD0100PA00X+096000Y+176000               S0      
317GND              VIA        MD0100PA00X+096000Y+178000               S0      
317GND              VIA        MD0100PA00X+096000Y+018000               S0      
317GND              VIA        MD0100PA00X+096000Y+180000               S0      
317GND              VIA        MD0100PA00X+096000Y+182000               S0      
317GND              VIA        MD0100PA00X+096000Y+184000               S0      
317GND              VIA        MD0100PA00X+096000Y+186000               S0      
317GND              VIA        MD0100PA00X+096000Y+188000               S0      
317GND              VIA        MD0100PA00X+096000Y+190000               S0      
317GND              VIA        MD0100PA00X+096000Y+192000               S0      
317GND              VIA        MD0100PA00X+096000Y+194000               S0      
317GND              VIA        MD0100PA00X+096000Y+196000               S0      
317GND              VIA        MD0100PA00X+096000Y+198000               S0      
317GND              VIA        MD0100PA00X+096000Y+002000               S0      
317GND              VIA        MD0100PA00X+096000Y+020000               S0      
317GND              VIA        MD0100PA00X+096000Y+022000               S0      
317GND              VIA        MD0100PA00X+096000Y+024000               S0      
317GND              VIA        MD0100PA00X+096000Y+026000               S0      
317GND              VIA        MD0100PA00X+096000Y+028000               S0      
317GND              VIA        MD0100PA00X+096000Y+030000               S0      
317GND              VIA        MD0100PA00X+096000Y+032000               S0      
317GND              VIA        MD0100PA00X+096000Y+034000               S0      
317GND              VIA        MD0100PA00X+096000Y+036000               S0      
317GND              VIA        MD0100PA00X+096000Y+038000               S0      
317GND              VIA        MD0100PA00X+096000Y+004000               S0      
317GND              VIA        MD0100PA00X+096000Y+040000               S0      
317GND              VIA        MD0100PA00X+096000Y+042000               S0      
317GND              VIA        MD0100PA00X+096000Y+044000               S0      
317GND              VIA        MD0100PA00X+096000Y+046000               S0      
317GND              VIA        MD0100PA00X+096000Y+048000               S0      
317GND              VIA        MD0100PA00X+096000Y+050000               S0      
317GND              VIA        MD0100PA00X+096000Y+052000               S0      
317GND              VIA        MD0100PA00X+096000Y+054000               S0      
317GND              VIA        MD0100PA00X+096000Y+056000               S0      
317GND              VIA        MD0100PA00X+096000Y+058000               S0      
317GND              VIA        MD0100PA00X+096000Y+006000               S0      
317GND              VIA        MD0100PA00X+096000Y+060000               S0      
317GND              VIA        MD0100PA00X+096000Y+062000               S0      
317GND              VIA        MD0100PA00X+096000Y+064000               S0      
317GND              VIA        MD0100PA00X+096000Y+066000               S0      
317GND              VIA        MD0100PA00X+096000Y+068000               S0      
317GND              VIA        MD0100PA00X+096000Y+070000               S0      
317GND              VIA        MD0100PA00X+096000Y+072000               S0      
317GND              VIA        MD0100PA00X+096000Y+074000               S0      
317GND              VIA        MD0100PA00X+096000Y+076000               S0      
317GND              VIA        MD0100PA00X+096000Y+078000               S0      
317GND              VIA        MD0100PA00X+096000Y+008000               S0      
317GND              VIA        MD0100PA00X+096000Y+080000               S0      
317GND              VIA        MD0100PA00X+096000Y+082000               S0      
317GND              VIA        MD0100PA00X+096000Y+084000               S0      
317GND              VIA        MD0100PA00X+096000Y+086000               S0      
317GND              VIA        MD0100PA00X+096000Y+088000               S0      
317GND              VIA        MD0100PA00X+096000Y+090000               S0      
317GND              VIA        MD0100PA00X+096000Y+092000               S0      
317GND              VIA        MD0100PA00X+096000Y+094000               S0      
317GND              VIA        MD0100PA00X+096000Y+096000               S0      
317GND              VIA        MD0100PA00X+096000Y+098000               S0      
317GND              VIA        MD0100PA00X+009610Y+117670               S0      
317GND              VIA        MD0100PA00X+009610Y+005230               S0      
317GND              VIA        MD0100PA00X+096350Y+140900               S0      
317GND              VIA        MD0100PA00X+096350Y+165700               S0      
317GND              VIA        MD0100PA00X+096350Y+167500               S0      
317GND              VIA        MD0100PA00X+009653Y+097768               S0      
317GND              VIA        MD0100PA00X+096800Y+140900               S0      
317GND              VIA        MD0100PA00X+009690Y+040600               S0      
317GND              VIA        MD0100PA00X+009700Y+162250               S0      
317GND              VIA        MD0100PA00X+009700Y+029650               S0      
317GND              VIA        MD0100PA00X+009700Y+077210               S0      
317GND              VIA        MD0100PA00X+097002Y+000550               S0      
317GND              VIA        MD0100PA00X+009710Y+081130               S0      
317GND              VIA        MD0100PA00X+097256Y+198663               S0      
317GND              VIA        MD0100PA00X+097300Y+140900               S0      
317GND              VIA        MD0100PA00X+009740Y+036660               S0      
317GND              VIA        MD0100PA00X+097750Y+140900               S0      
317GND              VIA        MD0100PA00X+097996Y+107521               S0      
317GND              VIA        MD0100PA00X+098000Y+010000               S0      
317GND              VIA        MD0100PA00X+098000Y+100000               S0      
317GND              VIA        MD0100PA00X+098000Y+102000               S0      
317GND              VIA        MD0100PA00X+098000Y+104000               S0      
317GND              VIA        MD0100PA00X+098000Y+110000               S0      
317GND              VIA        MD0100PA00X+098000Y+112000               S0      
317GND              VIA        MD0100PA00X+098000Y+114000               S0      
317GND              VIA        MD0100PA00X+098000Y+116000               S0      
317GND              VIA        MD0100PA00X+098000Y+118000               S0      
317GND              VIA        MD0100PA00X+098000Y+012000               S0      
317GND              VIA        MD0100PA00X+098000Y+120000               S0      
317GND              VIA        MD0100PA00X+098000Y+122000               S0      
317GND              VIA        MD0100PA00X+098000Y+124000               S0      
317GND              VIA        MD0100PA00X+098000Y+126000               S0      
317GND              VIA        MD0100PA00X+098000Y+128000               S0      
317GND              VIA        MD0100PA00X+098000Y+130000               S0      
317GND              VIA        MD0100PA00X+098000Y+132000               S0      
317GND              VIA        MD0100PA00X+098000Y+134000               S0      
317GND              VIA        MD0100PA00X+098000Y+136000               S0      
317GND              VIA        MD0100PA00X+098000Y+138000               S0      
317GND              VIA        MD0100PA00X+098000Y+140000               S0      
317GND              VIA        MD0100PA00X+098000Y+170000               S0      
317GND              VIA        MD0100PA00X+098000Y+172000               S0      
317GND              VIA        MD0100PA00X+098000Y+174000               S0      
317GND              VIA        MD0100PA00X+098000Y+176000               S0      
317GND              VIA        MD0100PA00X+098000Y+178000               S0      
317GND              VIA        MD0100PA00X+098000Y+018000               S0      
317GND              VIA        MD0100PA00X+098000Y+180000               S0      
317GND              VIA        MD0100PA00X+098000Y+182000               S0      
317GND              VIA        MD0100PA00X+098000Y+184000               S0      
317GND              VIA        MD0100PA00X+098000Y+186000               S0      
317GND              VIA        MD0100PA00X+098000Y+192000               S0      
317GND              VIA        MD0100PA00X+098000Y+194000               S0      
317GND              VIA        MD0100PA00X+098000Y+196000               S0      
317GND              VIA        MD0100PA00X+098000Y+198000               S0      
317GND              VIA        MD0100PA00X+098000Y+002000               S0      
317GND              VIA        MD0100PA00X+098000Y+020000               S0      
317GND              VIA        MD0100PA00X+098000Y+022000               S0      
317GND              VIA        MD0100PA00X+098000Y+024000               S0      
317GND              VIA        MD0100PA00X+098000Y+026000               S0      
317GND              VIA        MD0100PA00X+098000Y+028000               S0      
317GND              VIA        MD0100PA00X+098000Y+030000               S0      
317GND              VIA        MD0100PA00X+098000Y+032000               S0      
317GND              VIA        MD0100PA00X+098000Y+034000               S0      
317GND              VIA        MD0100PA00X+098000Y+036000               S0      
317GND              VIA        MD0100PA00X+098000Y+038000               S0      
317GND              VIA        MD0100PA00X+098000Y+004000               S0      
317GND              VIA        MD0100PA00X+098000Y+040000               S0      
317GND              VIA        MD0100PA00X+098000Y+042000               S0      
317GND              VIA        MD0100PA00X+098000Y+044000               S0      
317GND              VIA        MD0100PA00X+098000Y+046000               S0      
317GND              VIA        MD0100PA00X+098000Y+048000               S0      
317GND              VIA        MD0100PA00X+098000Y+050000               S0      
317GND              VIA        MD0100PA00X+098000Y+052000               S0      
317GND              VIA        MD0100PA00X+098000Y+054000               S0      
317GND              VIA        MD0100PA00X+098000Y+056000               S0      
317GND              VIA        MD0100PA00X+098000Y+058000               S0      
317GND              VIA        MD0100PA00X+098000Y+006000               S0      
317GND              VIA        MD0100PA00X+098000Y+060000               S0      
317GND              VIA        MD0100PA00X+098000Y+062000               S0      
317GND              VIA        MD0100PA00X+098000Y+064000               S0      
317GND              VIA        MD0100PA00X+098000Y+066000               S0      
317GND              VIA        MD0100PA00X+098000Y+070000               S0      
317GND              VIA        MD0100PA00X+098000Y+072000               S0      
317GND              VIA        MD0100PA00X+098000Y+074000               S0      
317GND              VIA        MD0100PA00X+098000Y+076000               S0      
317GND              VIA        MD0100PA00X+098000Y+078000               S0      
317GND              VIA        MD0100PA00X+098000Y+008000               S0      
317GND              VIA        MD0100PA00X+098000Y+080000               S0      
317GND              VIA        MD0100PA00X+098000Y+082000               S0      
317GND              VIA        MD0100PA00X+098000Y+084000               S0      
317GND              VIA        MD0100PA00X+098000Y+086000               S0      
317GND              VIA        MD0100PA00X+098000Y+088000               S0      
317GND              VIA        MD0100PA00X+098000Y+090000               S0      
317GND              VIA        MD0100PA00X+098000Y+092000               S0      
317GND              VIA        MD0100PA00X+098000Y+094000               S0      
317GND              VIA        MD0100PA00X+098000Y+096000               S0      
317GND              VIA        MD0100PA00X+098000Y+098000               S0      
317GND              VIA        MD0100PA00X+098002Y+189786               S0      
317GND              VIA        MD0100PA00X+098170Y+140900               S0      
317GND              VIA        MD0100PA00X+009830Y+125590               S0      
317GND              VIA        MD0100PA00X+009830Y+044340               S0      
317GND              VIA        MD0100PA00X+009830Y+085040               S0      
317GND              VIA        MD0100PA00X+009860Y+165980               S0      
317GND              VIA        MD0100PA00X+098620Y+140900               S0      
317GND              VIA        MD0100PA00X+009880Y+197410               S0      
317GND              VIA        MD0100PA00X+099002Y+000550               S0      
317GND              VIA        MD0100PA00X+099030Y+141250               S0      
317GND              VIA        MD0100PA00X+009910Y+121980               S0      
317GND              VIA        MD0100PA00X+099160Y+162250               S0      
317GND              VIA        MD0100PA00X+099250Y+163600               S0      
317GND              VIA        MD0100PA00X+099256Y+198663               S0      
317GND              VIA        MD0100PA00X+099460Y+141410               S0      
317GND              VIA        MD0100PA00X+099490Y+164610               S0      
317GND              VIA        MD0100PA00X+099500Y+165610               S0      
317GND              VIA        MD0100PA00X+099500Y+166610               S0      
317GND              VIA        MD0100PA00X+099510Y+167610               S0      
317GND              VIA        MD0100PA00X+009960Y+100140               S0      
317GND              VIA        MD0100PA00X+009980Y+019420               S0      
317GND              VIA        MD0100PA00X+009990Y+058240               S0      
317GND              VIA        MD0100PA00X+099947Y+192346               S0      
317GND              VIA        MD0100PA00X+099992Y+110260               S0      
317GND              VIA        MD0100PA00X+029750Y+141900               S0      
317GND              VIA        MD0100PA00X+029750Y+142400               S0      
317GND              VIA        MD0100PA00X+029750Y+058300               S0      
317GND              VIA        MD0100PA00X+029750Y+058800               S0      
317GND              VIA        MD0100PA00X+030000Y+142150               S0      
317GND              VIA        MD0100PA00X+030000Y+058550               S0      
317GND              VIA        MD0100PA00X+030250Y+141900               S0      
317GND              VIA        MD0100PA00X+030250Y+142400               S0      
317GND              VIA        MD0100PA00X+030250Y+058300               S0      
317GND              VIA        MD0100PA00X+030250Y+058800               S0      
317GND              VIA        MD0100PA00X+035900Y+119050               S0      
317GND              VIA        MD0100PA00X+035900Y+119600               S0      
317GND              VIA        MD0100PA00X+035900Y+120150               S0      
317GND              VIA        MD0100PA00X+035900Y+120700               S0      
317GND              VIA        MD0100PA00X+035900Y+121250               S0      
317GND              VIA        MD0100PA00X+035900Y+168900               S0      
317GND              VIA        MD0100PA00X+035900Y+169450               S0      
317GND              VIA        MD0100PA00X+035900Y+170000               S0      
317GND              VIA        MD0100PA00X+035900Y+170550               S0      
317GND              VIA        MD0100PA00X+035900Y+171100               S0      
317GND              VIA        MD0100PA00X+035900Y+038900               S0      
317GND              VIA        MD0100PA00X+035900Y+039450               S0      
317GND              VIA        MD0100PA00X+035900Y+040000               S0      
317GND              VIA        MD0100PA00X+035900Y+040550               S0      
317GND              VIA        MD0100PA00X+035900Y+041100               S0      
317GND              VIA        MD0100PA00X+035900Y+081900               S0      
317GND              VIA        MD0100PA00X+035900Y+082450               S0      
317GND              VIA        MD0100PA00X+035900Y+083000               S0      
317GND              VIA        MD0100PA00X+035900Y+083550               S0      
317GND              VIA        MD0100PA00X+035900Y+084100               S0      
317GND              VIA        MD0100PA00X+036450Y+120150               S0      
317GND              VIA        MD0100PA00X+036450Y+120700               S0      
317GND              VIA        MD0100PA00X+036450Y+121250               S0      
317GND              VIA        MD0100PA00X+036450Y+170000               S0      
317GND              VIA        MD0100PA00X+036450Y+170550               S0      
317GND              VIA        MD0100PA00X+036450Y+171100               S0      
317GND              VIA        MD0100PA00X+036450Y+040000               S0      
317GND              VIA        MD0100PA00X+036450Y+040550               S0      
317GND              VIA        MD0100PA00X+036450Y+041100               S0      
317GND              VIA        MD0100PA00X+036450Y+083000               S0      
317GND              VIA        MD0100PA00X+036450Y+083550               S0      
317GND              VIA        MD0100PA00X+036450Y+084100               S0      
317GND              VIA        MD0100PA00X+036500Y+119050               S0      
317GND              VIA        MD0100PA00X+036500Y+119600               S0      
317GND              VIA        MD0100PA00X+036500Y+168900               S0      
317GND              VIA        MD0100PA00X+036500Y+169450               S0      
317GND              VIA        MD0100PA00X+036500Y+038900               S0      
317GND              VIA        MD0100PA00X+036500Y+039450               S0      
317GND              VIA        MD0100PA00X+036500Y+081900               S0      
317GND              VIA        MD0100PA00X+036500Y+082450               S0      
317GND              VIA        MD0100PA00X+037000Y+119050               S0      
317GND              VIA        MD0100PA00X+037000Y+119600               S0      
317GND              VIA        MD0100PA00X+037000Y+120150               S0      
317GND              VIA        MD0100PA00X+037000Y+120700               S0      
317GND              VIA        MD0100PA00X+037000Y+121250               S0      
317GND              VIA        MD0100PA00X+037000Y+168900               S0      
317GND              VIA        MD0100PA00X+037000Y+169450               S0      
317GND              VIA        MD0100PA00X+037000Y+170000               S0      
317GND              VIA        MD0100PA00X+037000Y+170550               S0      
317GND              VIA        MD0100PA00X+037000Y+171100               S0      
317GND              VIA        MD0100PA00X+037000Y+038900               S0      
317GND              VIA        MD0100PA00X+037000Y+039450               S0      
317GND              VIA        MD0100PA00X+037000Y+040000               S0      
317GND              VIA        MD0100PA00X+037000Y+040550               S0      
317GND              VIA        MD0100PA00X+037000Y+041100               S0      
317GND              VIA        MD0100PA00X+037000Y+081900               S0      
317GND              VIA        MD0100PA00X+037000Y+082450               S0      
317GND              VIA        MD0100PA00X+037000Y+083000               S0      
317GND              VIA        MD0100PA00X+037000Y+083550               S0      
317GND              VIA        MD0100PA00X+037000Y+084100               S0      
317GND              VIA        MD0100PA00X+037550Y+119050               S0      
317GND              VIA        MD0100PA00X+037550Y+119600               S0      
317GND              VIA        MD0100PA00X+037550Y+120150               S0      
317GND              VIA        MD0100PA00X+037550Y+120700               S0      
317GND              VIA        MD0100PA00X+037550Y+121250               S0      
317GND              VIA        MD0100PA00X+037550Y+168900               S0      
317GND              VIA        MD0100PA00X+037550Y+169450               S0      
317GND              VIA        MD0100PA00X+037550Y+170000               S0      
317GND              VIA        MD0100PA00X+037550Y+170550               S0      
317GND              VIA        MD0100PA00X+037550Y+171100               S0      
317GND              VIA        MD0100PA00X+037550Y+038900               S0      
317GND              VIA        MD0100PA00X+037550Y+039450               S0      
317GND              VIA        MD0100PA00X+037550Y+040000               S0      
317GND              VIA        MD0100PA00X+037550Y+040550               S0      
317GND              VIA        MD0100PA00X+037550Y+041100               S0      
317GND              VIA        MD0100PA00X+037550Y+081900               S0      
317GND              VIA        MD0100PA00X+037550Y+082450               S0      
317GND              VIA        MD0100PA00X+037550Y+083000               S0      
317GND              VIA        MD0100PA00X+037550Y+083550               S0      
317GND              VIA        MD0100PA00X+037550Y+084100               S0      
317GND              VIA        MD0100PA00X+038100Y+119050               S0      
317GND              VIA        MD0100PA00X+038100Y+119600               S0      
317GND              VIA        MD0100PA00X+038100Y+120150               S0      
317GND              VIA        MD0100PA00X+038100Y+120700               S0      
317GND              VIA        MD0100PA00X+038100Y+121250               S0      
317GND              VIA        MD0100PA00X+038100Y+168900               S0      
317GND              VIA        MD0100PA00X+038100Y+169450               S0      
317GND              VIA        MD0100PA00X+038100Y+170000               S0      
317GND              VIA        MD0100PA00X+038100Y+170550               S0      
317GND              VIA        MD0100PA00X+038100Y+171100               S0      
317GND              VIA        MD0100PA00X+038100Y+038900               S0      
317GND              VIA        MD0100PA00X+038100Y+039450               S0      
317GND              VIA        MD0100PA00X+038100Y+040000               S0      
317GND              VIA        MD0100PA00X+038100Y+040550               S0      
317GND              VIA        MD0100PA00X+038100Y+041100               S0      
317GND              VIA        MD0100PA00X+038100Y+081900               S0      
317GND              VIA        MD0100PA00X+038100Y+082450               S0      
317GND              VIA        MD0100PA00X+038100Y+083000               S0      
317GND              VIA        MD0100PA00X+038100Y+083550               S0      
317GND              VIA        MD0100PA00X+038100Y+084100               S0      
317GND              VIA        MD0100PA00X+089150Y+170800               S0      
317GND              VIA        MD0100PA00X+089150Y+171200               S0      
317GND              VIA        MD0100PA00X+089550Y+170800               S0      
317GND              VIA        MD0100PA00X+089550Y+171200               S0      
317GND              VIA        MD0160PA00X+001750Y+180190               S0      
317GND              VIA        MD0160PA00X+001750Y+180690               S0      
317GND              VIA        MD0160PA00X+001750Y+181190               S0      
317GND              VIA        MD0160PA00X+001750Y+181650               S0      
317GND              VIA        MD0160PA00X+002200Y+180910               S0      
317GND              VIA        MD0160PA00X+002200Y+181410               S0      
317GND              VIA        MD0160PA00X+002210Y+180280               S0      
317GND              VIA        MD0160PA00X+002630Y+181500               S0      
317GND              VIA        MD0160PA00X+002650Y+180520               S0      
317GND              VIA        MD0160PA00X+002660Y+181060               S0      
317GND              VIA        MD0160PA00X+003080Y+180530               S0      
317GND              VIA        MD0160PA00X+003080Y+181050               S0      
317GND              VIA        MD0160PA00X+003490Y+180720               S0      
317GND              VIA        MD0160PA00X+003510Y+181300               S0      
317GND              VIA        MD0160PA00X+003832Y+180449               S0      
317GND              VIA        MD0160PA00X+003880Y+181010               S0      
317GND              VIA        MD0160PA00X+093500Y+151600               S0      
317GND              VIA        MD0160PA00X+093500Y+152500               S0      
317GND              VIA        MD0160PA00X+093500Y+153500               S0      
317GND              VIA        MD0160PA00X+093500Y+154500               S0      
317GND              VIA        MD0160PA00X+093500Y+155500               S0      
317GND              VIA        MD0160PA00X+093500Y+156500               S0      
317GND              VIA        MD0160PA00X+093500Y+157500               S0      
317GND              VIA        MD0160PA00X+093500Y+158500               S0      
317GND              VIA        MD0160PA00X+093500Y+159500               S0      
317GND              VIA        MD0160PA00X+094500Y+151600               S0      
317GND              VIA        MD0160PA00X+094500Y+152500               S0      
317GND              VIA        MD0160PA00X+094500Y+153500               S0      
317GND              VIA        MD0160PA00X+094500Y+154500               S0      
317GND              VIA        MD0160PA00X+094500Y+155500               S0      
317GND              VIA        MD0160PA00X+094500Y+156500               S0      
317GND              VIA        MD0160PA00X+094500Y+157500               S0      
317GND              VIA        MD0160PA00X+094500Y+158500               S0      
317GND              VIA        MD0160PA00X+094500Y+159500               S0      
317GND              VIA        MD0160PA00X+095500Y+151600               S0      
317GND              VIA        MD0160PA00X+095500Y+152500               S0      
317GND              VIA        MD0160PA00X+095500Y+153500               S0      
317GND              VIA        MD0160PA00X+095500Y+154500               S0      
317GND              VIA        MD0160PA00X+095500Y+155500               S0      
317GND              VIA        MD0160PA00X+095500Y+156500               S0      
317GND              VIA        MD0160PA00X+095500Y+157500               S0      
317GND              VIA        MD0160PA00X+095500Y+158500               S0      
317GND              VIA        MD0160PA00X+095500Y+159500               S0      
317GND              VIA        MD0160PA00X+096500Y+151600               S0      
317GND              VIA        MD0160PA00X+096500Y+152500               S0      
317GND              VIA        MD0160PA00X+096500Y+153500               S0      
317GND              VIA        MD0160PA00X+096500Y+154500               S0      
317GND              VIA        MD0160PA00X+096500Y+155500               S0      
317GND              VIA        MD0160PA00X+096500Y+156500               S0      
317GND              VIA        MD0160PA00X+096500Y+157500               S0      
317GND              VIA        MD0160PA00X+096500Y+158500               S0      
317GND              VIA        MD0160PA00X+096500Y+159500               S0      
317GND              VIA        MD0160PA00X+096500Y+160500               S0      
317GND              VIA        MD0160PA00X+097500Y+152500               S0      
317GND              VIA        MD0160PA00X+097500Y+153500               S0      
317GND              VIA        MD0160PA00X+097500Y+154500               S0      
317GND              VIA        MD0160PA00X+097500Y+155500               S0      
317GND              VIA        MD0160PA00X+097500Y+156500               S0      
317GND              VIA        MD0160PA00X+097500Y+157500               S0      
317GND              VIA        MD0160PA00X+097500Y+158500               S0      
317GND              VIA        MD0160PA00X+097500Y+159500               S0      
317GND              VIA        MD0160PA00X+097500Y+160500               S0      
327NNAME00000                         A01X+000886Y+171316X0980Y0200     S0      
327NNAME00000                         A01X+038742Y+170886X0460Y0120     S0      
317NNAME00000                   D0220PA01X+042130Y+171850               S0      
317NNAME00000                   D0300PA01X+086512Y+175625               S0      
317NNAME00000                   D0240PA01X+041750Y+171820               S0      
317NNAME00000       VIA        MD0280PA08X+004515Y+172065               S0      
317NNAME00000       VIA        MD0100PA00X+014440Y+172040               S0      
317NNAME00000       VIA        MD0100PA00X+003800Y+171500               S0      
317NNAME00000       VIA        MD0100PA00X+042073Y+172176               S0      
317NNAME00000       VIA        MD0100PA00X+086512Y+175180               S0      
327SSD_PRSNT10                        A01X+035918Y+168259X0120Y0460     S0      
317SSD_PRSNT10                  D0220PA01X+034500Y+164870               S0      
317SSD_PRSNT10                  D0240PA01X+034470Y+165250               S0      
317SSD_PRSNT10      VIA        MD0280PA01X+034600Y+165750               S0      
327NNAME00001                         A08X+000886Y+158402X0980Y0200     S0      
327NNAME00001                         A01X+036114Y+168259X0120Y0460     S0      
317NNAME00001                   D0220PA01X+035300Y+164870               S0      
317NNAME00001                   D0300PA01X+006923Y+185965               S0      
317NNAME00001                   D0240PA01X+035270Y+165250               S0      
317NNAME00001       VIA        MD0280PA08X+004955Y+158374               S0      
317NNAME00001       VIA        MD0100PA00X+014030Y+172410               S0      
317NNAME00001       VIA        MD0100PA00X+035617Y+164929               S0      
317NNAME00001       VIA        MD0100PA00X+006780Y+185520               S0      
317NNAME00001       VIA        MD0100PA00X+009363Y+180220               S0      
327P3V3                               A01X+089775Y+135655X0480Y0160     S0      
327P3V3                               A01X+089775Y+095104X0480Y0160     S0      
327P3V3                               A01X+089775Y+054552X0480Y0160     S0      
327P3V3                               A01X+089875Y+014001X0480Y0160     S0      
327P3V3                               A01X+009123Y+024186X0480Y0160     S0      
327P3V3                               A01X+009123Y+064738X0480Y0160     S0      
327P3V3                               A01X+009123Y+105289X0480Y0160     S0      
327P3V3                               A01X+009123Y+145840X0480Y0160     S0      
327P3V3                               A01X+008564Y+185365X0160Y0480     S0      
327P3V3                               A01X+016940Y+014101X0480Y0160     S0      
327P3V3                               A01X+015094Y+056325X0160Y0480     S0      
327P3V3                               A01X+018744Y+095625X0160Y0480     S0      
327P3V3                               A01X+016940Y+135655X0480Y0160     S0      
327P3V3                               A01X+020110Y+176944X0480Y0160     S0      
327P3V3                               A01X+089775Y+176206X0480Y0160     S0      
327P3V3                               A01X+080900Y+171450X0500Y0650     S0      
327P3V3                               A01X+080900Y+172350X0500Y0650     S0      
327P3V3                               A01X+029902Y+141370X0120Y0420     S0      
327P3V3                               A01X+030780Y+058452X0420Y0120     S0      
327P3V3                               A01X+030790Y+085310X0450Y0550     S0      
327P3V3                               A01X+030760Y+042260X0450Y0550     S0      
327P3V3                               A01X+030720Y+122400X0450Y0550     S0      
327P3V3                               A01X+030770Y+172210X0450Y0550     S0      
317P3V3                         D0220PA01X+092320Y+137650               S0      
317P3V3                         D0220PA01X+092320Y+097100               S0      
317P3V3                         D0220PA01X+092320Y+056550               S0      
317P3V3                         D0220PA01X+092320Y+016000               S0      
317P3V3                         D0220PA01X+009620Y+101650               S0      
317P3V3                         D0220PA01X+019020Y+137750               S0      
317P3V3                         D0220PA01X+019570Y+097400               S0      
317P3V3                         D0220PA01X+009620Y+020550               S0      
317P3V3                         D0220PA01X+009620Y+142200               S0      
317P3V3                         D0220PA01X+019520Y+056900               S0      
317P3V3                         D0220PA01X+009620Y+061100               S0      
317P3V3                         D0220PA01X+019470Y+178600               S0      
317P3V3                         D0220PA01X+019570Y+016250               S0      
317P3V3                         D0220PA01X+092320Y+178200               S0      
317P3V3                         D0220PA01X+009719Y+182592               S0      
327P3V3                               A01X+035850Y+010465X0120Y0600     S0      
327P3V3                               A01X+028084Y+175240X0140Y0600     S0      
327P3V3                               A01X+018132Y+054715X0600Y0140     S0      
327P3V3                               A01X+013014Y+149597X0600Y0140     S0      
327P3V3                               A01X+083683Y+019675X0600Y0140     S0      
327P3V3                               A01X+083683Y+181093X0600Y0140     S0      
327P3V3                               A01X+040630Y+042050X0450Y0550     S0      
327P3V3                               A01X+040630Y+085050X0450Y0550     S0      
327P3V3                               A01X+040830Y+123250X0450Y0550     S0      
327P3V3                               A01X+038800Y+173630X0550Y0450     S0      
317P3V3                         D0220PA01X+016483Y+097973               S0      
317P3V3                         D0220PA01X+089889Y+179082               S0      
317P3V3                         D0220PA01X+089370Y+177690               S0      
317P3V3                         D0220PA01X+089021Y+137650               S0      
317P3V3                         D0220PA01X+089339Y+137135               S0      
317P3V3                         D0220PA01X+088991Y+097391               S0      
317P3V3                         D0220PA01X+089377Y+096591               S0      
317P3V3                         D0220PA01X+089938Y+057442               S0      
317P3V3                         D0220PA01X+089354Y+056041               S0      
317P3V3                         D0220PA01X+088712Y+016835               S0      
317P3V3                         D0220PA01X+089528Y+015472               S0      
317P3V3                         D0220PA01X+017089Y+179069               S0      
317P3V3                         D0220PA01X+017008Y+177693               S0      
317P3V3                         D0220PA01X+017107Y+138532               S0      
317P3V3                         D0220PA01X+016407Y+136813               S0      
317P3V3                         D0220PA01X+005986Y+020837               S0      
317P3V3                         D0220PA01X+016045Y+097700               S0      
317P3V3                         D0220PA01X+016214Y+057184               S0      
317P3V3                         D0220PA01X+016730Y+056042               S0      
317P3V3                         D0220PA01X+017106Y+016881               S0      
317P3V3                         D0220PA01X+016399Y+015134               S0      
317P3V3                         D0220PA01X+007351Y+183727               S0      
317P3V3                         D0220PA01X+007168Y+182333               S0      
317P3V3                         D0220PA01X+006380Y+142579               S0      
317P3V3                         D0220PA01X+006414Y+141791               S0      
317P3V3                         D0220PA01X+006404Y+102029               S0      
317P3V3                         D0220PA01X+006350Y+101244               S0      
317P3V3                         D0220PA01X+006741Y+063166               S0      
317P3V3                         D0220PA01X+006362Y+061117               S0      
317P3V3                         D0220PA01X+006390Y+020919               S0      
317P3V3                         D0220PA01X+088455Y+177725               S0      
317P3V3                         D0220PA01X+088399Y+136970               S0      
317P3V3                         D0220PA01X+088455Y+096623               S0      
317P3V3                         D0220PA01X+088455Y+056072               S0      
317P3V3                         D0220PA01X+088630Y+016100               S0      
317P3V3                         D0220PA01X+021940Y+177620               S0      
317P3V3                         D0220PA01X+015126Y+134780               S0      
317P3V3                         D0220PA01X+020730Y+096548               S0      
317P3V3                         D0220PA01X+015450Y+054130               S0      
317P3V3                         D0220PA01X+015056Y+013970               S0      
317P3V3                         D0220PA01X+008440Y+183630               S0      
317P3V3                         D0220PA01X+008359Y+144755               S0      
317P3V3                         D0220PA01X+008400Y+104280               S0      
317P3V3                         D0220PA01X+008359Y+063653               S0      
317P3V3                         D0220PA01X+008359Y+023102               S0      
317P3V3                         D0220PA01X+032920Y+060100               S0      
317P3V3                         D0220PA01X+031750Y+056230               S0      
317P3V3                         D0220PA01X+030750Y+139230               S0      
317P3V3                         D0220PA01X+027680Y+140350               S0      
317P3V3                         D0220PA01X+091050Y+173120               S0      
317P3V3                         D0220PA01X+076474Y+195981               S0      
317P3V3                         D0220PA01X+081500Y+178830               S0      
317P3V3                         D0220PA01X+081650Y+158580               S0      
317P3V3                         D0220PA01X+081650Y+118030               S0      
317P3V3                         D0220PA01X+081650Y+077480               S0      
317P3V3                         D0220PA01X+081650Y+036930               S0      
317P3V3                         D0220PA01X+081650Y+017430               S0      
317P3V3                         D0220PA01X+084460Y+114560               S0      
317P3V3                         D0220PA01X+084620Y+074020               S0      
317P3V3                         D0220PA01X+084405Y+033420               S0      
317P3V3                         D0220PA01X+082450Y+017430               S0      
317P3V3                         D0220PA01X+083250Y+017430               S0      
317P3V3                         D0220PA01X+084790Y+194520               S0      
317P3V3                         D0220PA01X+082550Y+178830               S0      
317P3V3                         D0220PA01X+084150Y+178830               S0      
317P3V3                         D0220PA01X+084560Y+155120               S0      
317P3V3                         D0220PA01X+089875Y+136379               S0      
317P3V3                         D0220PA01X+092320Y+138099               S0      
317P3V3                         D0220PA01X+086180Y+136449               S0      
317P3V3                         D0220PA01X+089865Y+095828               S0      
317P3V3                         D0220PA01X+092320Y+097548               S0      
317P3V3                         D0220PA01X+086180Y+095898               S0      
317P3V3                         D0220PA01X+089875Y+055276               S0      
317P3V3                         D0220PA01X+092320Y+056997               S0      
317P3V3                         D0220PA01X+086180Y+055347               S0      
317P3V3                         D0220PA01X+089965Y+014725               S0      
317P3V3                         D0220PA01X+092320Y+016445               S0      
317P3V3                         D0220PA01X+086696Y+015936               S0      
317P3V3                         D0220PA01X+095900Y+166030               S0      
317P3V3                         D0220PA01X+095900Y+167170               S0      
317P3V3                         D0220PA01X+019570Y+016700               S0      
317P3V3                         D0220PA01X+038200Y+010130               S0      
317P3V3                         D0220PA01X+008195Y+023972               S0      
317P3V3                         D0220PA01X+009620Y+021447               S0      
317P3V3                         D0220PA01X+012570Y+005130               S0      
317P3V3                         D0220PA01X+008195Y+064523               S0      
317P3V3                         D0220PA01X+009620Y+061998               S0      
317P3V3                         D0220PA01X+007775Y+105284               S0      
317P3V3                         D0220PA01X+009620Y+102549               S0      
317P3V3                         D0220PA01X+012530Y+044110               S0      
317P3V3                         D0220PA01X+012680Y+084560               S0      
317P3V3                         D0220PA01X+007675Y+145855               S0      
317P3V3                         D0220PA01X+009620Y+143100               S0      
317P3V3                         D0220PA01X+009440Y+183990               S0      
317P3V3                         D0220PA01X+007710Y+184960               S0      
317P3V3                         D0220PA01X+012600Y+125210               S0      
317P3V3                         D0220PA01X+012690Y+165780               S0      
317P3V3                         D0220PA01X+017040Y+014775               S0      
317P3V3                         D0220PA01X+013607Y+016248               S0      
317P3V3                         D0220PA01X+020030Y+056900               S0      
317P3V3                         D0220PA01X+012203Y+057307               S0      
317P3V3                         D0220PA01X+011430Y+033502               S0      
317P3V3                         D0220PA01X+011794Y+074062               S0      
317P3V3                         D0220PA01X+017800Y+095620               S0      
317P3V3                         D0220PA01X+022950Y+094978               S0      
317P3V3                         D0220PA01X+017040Y+136329               S0      
317P3V3                         D0220PA01X+014008Y+137801               S0      
317P3V3                         D0220PA01X+011790Y+114600               S0      
317P3V3                         D0220PA01X+010910Y+154370               S0      
317P3V3                         D0220PA01X+020020Y+176220               S0      
317P3V3                         D0220PA01X+024830Y+176990               S0      
317P3V3                         D0220PA01X+011900Y+194390               S0      
317P3V3                         D0220PA01X+089880Y+176930               S0      
317P3V3                         D0220PA01X+086180Y+177000               S0      
317P3V3                         D0220PA01X+003730Y+196060               S0      
317P3V3                         D0220PA01X+007938Y+158018               S0      
317P3V3                         D0220PA01X+009000Y+118030               S0      
317P3V3                         D0220PA01X+009000Y+077480               S0      
317P3V3                         D0220PA01X+009000Y+036930               S0      
317P3V3                         D0220PA01X+015400Y+162270               S0      
317P3V3                         D0220PA01X+015400Y+121720               S0      
317P3V3                         D0220PA01X+015400Y+081170               S0      
317P3V3                         D0220PA01X+015362Y+040583               S0      
317P3V3                         D0220PA01X+020450Y+003220               S0      
317P3V3                         D0220PA01X+039170Y+034100               S0      
317P3V3                         D0220PA01X+034380Y+045900               S0      
317P3V3                         D0220PA01X+034380Y+088900               S0      
317P3V3                         D0220PA01X+034380Y+126050               S0      
317P3V3                         D0220PA01X+035620Y+164100               S0      
317P3V3                         D0220PA01X+035620Y+034100               S0      
317P3V3                         D0220PA01X+037930Y+045900               S0      
317P3V3                         D0220PA01X+037930Y+088900               S0      
317P3V3                         D0220PA01X+037930Y+126050               S0      
317P3V3                         D0220PA01X+034380Y+175900               S0      
317P3V3                         D0220PA01X+038520Y+077100               S0      
317P3V3                         D0220PA01X+042900Y+082070               S0      
317P3V3                         D0220PA01X+039170Y+114250               S0      
317P3V3                         D0220PA01X+042900Y+122320               S0      
317P3V3                         D0220PA01X+042900Y+172170               S0      
317P3V3                         D0220PA01X+032320Y+141350               S0      
317P3V3                         D0220PA01X+032320Y+140540               S0      
317P3V3                         D0220PA01X+032320Y+142570               S0      
317P3V3                         D0220PA01X+032320Y+141750               S0      
317P3V3                         D0220PA01X+032320Y+143770               S0      
317P3V3                         D0220PA01X+030360Y+144470               S0      
317P3V3                         D0220PA01X+032320Y+142970               S0      
317P3V3                         D0220PA01X+031160Y+144470               S0      
317P3V3                         D0220PA01X+029160Y+144470               S0      
317P3V3                         D0220PA01X+029960Y+144470               S0      
317P3V3                         D0220PA01X+027965Y+144470               S0      
317P3V3                         D0220PA01X+028760Y+144470               S0      
317P3V3                         D0220PA01X+027680Y+142350               S0      
317P3V3                         D0220PA01X+027680Y+141150               S0      
317P3V3                         D0220PA01X+027680Y+143150               S0      
317P3V3                         D0220PA01X+027680Y+141950               S0      
317P3V3                         D0220PA01X+030800Y+060870               S0      
317P3V3                         D0220PA01X+031600Y+060870               S0      
317P3V3                         D0220PA01X+029600Y+060870               S0      
317P3V3                         D0220PA01X+030400Y+060870               S0      
317P3V3                         D0220PA01X+028400Y+060870               S0      
317P3V3                         D0220PA01X+027680Y+058900               S0      
317P3V3                         D0220PA01X+029200Y+060870               S0      
317P3V3                         D0220PA01X+027680Y+059700               S0      
317P3V3                         D0220PA01X+027680Y+057700               S0      
317P3V3                         D0220PA01X+027680Y+058500               S0      
317P3V3                         D0220PA01X+027680Y+056500               S0      
317P3V3                         D0220PA01X+027680Y+057300               S0      
317P3V3                         D0220PA01X+029845Y+056230               S0      
317P3V3                         D0220PA01X+029058Y+056230               S0      
317P3V3                         D0220PA01X+031550Y+139230               S0      
317P3V3                         D0220PA01X+032920Y+059300               S0      
317P3V3                         D0220PA01X+039800Y+041020               S0      
317P3V3                         D0220PA01X+040070Y+084050               S0      
317P3V3                         D0220PA01X+040220Y+119200               S0      
317P3V3                         D0220PA01X+037900Y+173270               S0      
317P3V3                         D0220PA01X+005600Y+188420               S0      
317P3V3                         D0220PA01X+028490Y+138680               S0      
317P3V3                         D0220PA01X+029310Y+138680               S0      
317P3V3                         D0220PA01X+033270Y+057860               S0      
317P3V3                         D0220PA01X+033270Y+057058               S0      
317P3V3                         D0220PA01X+026880Y+172200               S0      
317P3V3                         D0220PA01X+028020Y+172200               S0      
317P3V3                         D0220PA01X+034850Y+007180               S0      
317P3V3                         D0220PA01X+035800Y+006730               S0      
317P3V3                         D0220PA01X+020300Y+053120               S0      
317P3V3                         D0220PA01X+027550Y+179170               S0      
317P3V3                         D0220PA01X+028350Y+179170               S0      
317P3V3                         D0220PA01X+029150Y+179170               S0      
317P3V3                         D0220PA01X+011000Y+147330               S0      
317P3V3                         D0220PA01X+011800Y+147330               S0      
317P3V3                         D0220PA01X+012600Y+147330               S0      
317P3V3                         D0220PA01X+020300Y+054620               S0      
317P3V3                         D0220PA01X+020300Y+053870               S0      
317P3V3                         D0220PA01X+038370Y+034100               S0      
317P3V3                         D0220PA01X+009620Y+021000               S0      
317P3V3                         D0220PA01X+035180Y+088900               S0      
317P3V3                         D0220PA01X+009620Y+102100               S0      
317P3V3                         D0220PA01X+035180Y+045900               S0      
317P3V3                         D0220PA01X+009620Y+061550               S0      
317P3V3                         D0220PA01X+035180Y+126050               S0      
317P3V3                         D0220PA01X+009620Y+142650               S0      
317P3V3                         D0220PA01X+034820Y+164100               S0      
317P3V3                         D0220PA01X+009720Y+183000               S0      
317P3V3                         D0220PA01X+038730Y+045900               S0      
317P3V3                         D0220PA01X+019520Y+057350               S0      
317P3V3                         D0220PA01X+034820Y+034100               S0      
317P3V3                         D0220PA01X+038730Y+126050               S0      
317P3V3                         D0220PA01X+019020Y+138200               S0      
317P3V3                         D0220PA01X+038730Y+088900               S0      
317P3V3                         D0220PA01X+019570Y+097850               S0      
317P3V3                         D0220PA01X+035180Y+175900               S0      
317P3V3                         D0220PA01X+019470Y+179050               S0      
317P3V3                         D0220PA01X+037720Y+077100               S0      
317P3V3                         D0220PA01X+042900Y+081270               S0      
317P3V3                         D0220PA01X+038370Y+114250               S0      
317P3V3                         D0220PA01X+042900Y+121520               S0      
317P3V3                         D0220PA01X+042900Y+171370               S0      
317P3V3                         D0220PA01X+092320Y+178650               S0      
317P3V3                         D0340PA01X+095900Y+162720               S0      
317P3V3                         D0340PA01X+087250Y+145920               S0      
317P3V3                         D0340PA01X+087250Y+105370               S0      
317P3V3                         D0340PA01X+087250Y+064820               S0      
317P3V3                         D0340PA01X+087250Y+025080               S0      
317P3V3                         D0340PA01X+087150Y+186420               S0      
317P3V3                         D0340PA01X+032030Y+058340               S0      
317P3V3                         D0340PA01X+029760Y+140130               S0      
317P3V3                         D0340PA01X+029300Y+175180               S0      
317P3V3                         D0340PA01X+028800Y+175180               S0      
317P3V3                         D0340PA01X+010000Y+011920               S0      
317P3V3                         D0340PA01X+010000Y+093020               S0      
317P3V3                         D0340PA01X+010000Y+052520               S0      
317P3V3                         D0340PA01X+010000Y+133520               S0      
317P3V3                         D0340PA01X+010000Y+174970               S0      
317P3V3                         D0340PA01X+014400Y+064820               S0      
317P3V3                         D0340PA01X+014400Y+024170               S0      
317P3V3                         D0340PA01X+014400Y+105370               S0      
317P3V3                         D0340PA01X+014400Y+145820               S0      
317P3V3                         D0340PA01X+014400Y+186420               S0      
317P3V3                         D0240PA01X+008200Y+024369               S0      
317P3V3                         D0240PA01X+008200Y+064920               S0      
317P3V3                         D0240PA01X+008325Y+105284               S0      
317P3V3                         D0240PA01X+008275Y+145835               S0      
317P3V3                         D0240PA01X+008019Y+185427               S0      
317P3V3                         D0240PA01X+017589Y+014146               S0      
317P3V3                         D0240PA01X+015170Y+056950               S0      
317P3V3                         D0240PA01X+018200Y+095630               S0      
317P3V3                         D0240PA01X+017589Y+135660               S0      
317P3V3                         D0240PA01X+019461Y+176939               S0      
317P3V3                         D0240PA01X+090524Y+014006               S0      
317P3V3                         D0240PA01X+090424Y+054558               S0      
317P3V3                         D0240PA01X+090424Y+095109               S0      
317P3V3                         D0240PA01X+090424Y+135660               S0      
317P3V3                         D0240PA01X+090424Y+176211               S0      
317P3V3                         D0240PA01X+083480Y+020300               S0      
317P3V3                         D0240PA01X+083480Y+181700               S0      
317P3V3                         D0240PA01X+036080Y+011700               S0      
317P3V3                         D0240PA01X+036080Y+012050               S0      
317P3V3                         D0240PA01X+018080Y+055350               S0      
317P3V3                         D0240PA01X+012830Y+150200               S0      
327P3V3                               A08X+100974Y+162610X2300Y0320     S0      
327P3V3                               A08X+100974Y+163110X2300Y0320     S0      
327P3V3                               A01X+089524Y+186689X0790Y0200     S0      
327P3V3                               A01X+089524Y+146138X0790Y0200     S0      
327P3V3                               A01X+089524Y+105587X0790Y0200     S0      
327P3V3                               A01X+089524Y+065035X0790Y0200     S0      
327P3V3                               A01X+089524Y+024484X0790Y0200     S0      
327P3V3                               A01X+016689Y+186689X0790Y0200     S0      
327P3V3                               A01X+016689Y+146138X0790Y0200     S0      
327P3V3                               A01X+016689Y+105587X0790Y0200     S0      
327P3V3                               A01X+016689Y+065035X0790Y0200     S0      
327P3V3                               A01X+016689Y+024484X0790Y0200     S0      
327P3V3                               A01X+007721Y+174728X0790Y0200     S0      
327P3V3                               A01X+007721Y+134177X0790Y0200     S0      
327P3V3                               A01X+007721Y+093626X0790Y0200     S0      
327P3V3                               A01X+007721Y+053075X0790Y0200     S0      
327P3V3                               A01X+007721Y+012524X0790Y0200     S0      
317P3V3             VIA        MD0280PA08X+024359Y+177951               S0      
317P3V3             VIA        MD0280PA08X+083100Y+162500               S0      
317P3V3             VIA        MD0280PA08X+085100Y+162700               S0      
317P3V3             VIA        MD0280PA08X+087350Y+162550               S0      
317P3V3             VIA        MD0280PA08X+090350Y+162750               S0      
317P3V3             VIA        MD0280PA08X+093350Y+162500               S0      
317P3V3             VIA        MD0280PA08X+096150Y+162450               S0      
317P3V3             VIA        MD0280PA01X+076320Y+169860               S0      
317P3V3             VIA        MD0100PA00X+010000Y+142300               S0      
317P3V3             VIA        MD0100PA00X+010029Y+182592               S0      
317P3V3             VIA        MD0100PA00X+010030Y+183000               S0      
317P3V3             VIA        MD0100PA00X+010040Y+020830               S0      
317P3V3             VIA        MD0100PA00X+010400Y+174780               S0      
317P3V3             VIA        MD0100PA00X+010905Y+154060               S0      
317P3V3             VIA        MD0100PA00X+011000Y+147000               S0      
317P3V3             VIA        MD0100PA00X+011237Y+188398               S0      
317P3V3             VIA        MD0100PA00X+011430Y+033830               S0      
317P3V3             VIA        MD0100PA00X+011790Y+114920               S0      
317P3V3             VIA        MD0100PA00X+011794Y+074380               S0      
317P3V3             VIA        MD0100PA00X+011800Y+147000               S0      
317P3V3             VIA        MD0100PA00X+012530Y+043800               S0      
317P3V3             VIA        MD0100PA00X+012570Y+005440               S0      
317P3V3             VIA        MD0100PA00X+012600Y+146600               S0      
317P3V3             VIA        MD0100PA00X+012680Y+084250               S0      
317P3V3             VIA        MD0100PA00X+012690Y+165470               S0      
317P3V3             VIA        MD0100PA00X+012825Y+150650               S0      
317P3V3             VIA        MD0100PA00X+012915Y+125205               S0      
317P3V3             VIA        MD0100PA00X+014013Y+138130               S0      
317P3V3             VIA        MD0100PA00X+014796Y+134780               S0      
317P3V3             VIA        MD0100PA00X+014800Y+105350               S0      
317P3V3             VIA        MD0100PA00X+014800Y+145800               S0      
317P3V3             VIA        MD0100PA00X+014800Y+186400               S0      
317P3V3             VIA        MD0100PA00X+014800Y+024150               S0      
317P3V3             VIA        MD0100PA00X+014800Y+064800               S0      
317P3V3             VIA        MD0100PA00X+015020Y+162800               S0      
317P3V3             VIA        MD0100PA00X+015056Y+014285               S0      
317P3V3             VIA        MD0100PA00X+015550Y+057400               S0      
317P3V3             VIA        MD0100PA00X+015680Y+081600               S0      
317P3V3             VIA        MD0100PA00X+015720Y+041200               S0      
317P3V3             VIA        MD0100PA00X+015775Y+054125               S0      
317P3V3             VIA        MD0100PA00X+015805Y+121605               S0      
317P3V3             VIA        MD0100PA00X+015950Y+018100               S0      
317P3V3             VIA        MD0100PA00X+015960Y+058140               S0      
317P3V3             VIA        MD0100PA00X+016110Y+098062               S0      
317P3V3             VIA        MD0100PA00X+016220Y+098800               S0      
317P3V3             VIA        MD0100PA00X+016730Y+014770               S0      
317P3V3             VIA        MD0100PA00X+016730Y+136324               S0      
317P3V3             VIA        MD0100PA00X+017050Y+047850               S0      
317P3V3             VIA        MD0100PA00X+017310Y+105587               S0      
317P3V3             VIA        MD0100PA00X+017310Y+146138               S0      
317P3V3             VIA        MD0100PA00X+017310Y+186689               S0      
317P3V3             VIA        MD0100PA00X+017310Y+024484               S0      
317P3V3             VIA        MD0100PA00X+017310Y+065035               S0      
317P3V3             VIA        MD0100PA00X+017380Y+037980               S0      
317P3V3             VIA        MD0100PA00X+017772Y+177816               S0      
317P3V3             VIA        MD0100PA00X+017800Y+096000               S0      
317P3V3             VIA        MD0100PA00X+018008Y+179069               S0      
317P3V3             VIA        MD0100PA00X+018446Y+010337               S0      
317P3V3             VIA        MD0100PA00X+018450Y+055350               S0      
317P3V3             VIA        MD0100PA00X+019033Y+091353               S0      
317P3V3             VIA        MD0100PA00X+019340Y+137750               S0      
317P3V3             VIA        MD0100PA00X+019340Y+138200               S0      
317P3V3             VIA        MD0100PA00X+019525Y+057670               S0      
317P3V3             VIA        MD0100PA00X+019790Y+178600               S0      
317P3V3             VIA        MD0100PA00X+019790Y+179050               S0      
317P3V3             VIA        MD0100PA00X+019880Y+016250               S0      
317P3V3             VIA        MD0100PA00X+019880Y+016700               S0      
317P3V3             VIA        MD0100PA00X+019890Y+097400               S0      
317P3V3             VIA        MD0100PA00X+019890Y+097850               S0      
317P3V3             VIA        MD0100PA00X+020025Y+057210               S0      
317P3V3             VIA        MD0100PA00X+020330Y+176335               S0      
317P3V3             VIA        MD0100PA00X+020650Y+053125               S0      
317P3V3             VIA        MD0100PA00X+020650Y+053875               S0      
317P3V3             VIA        MD0100PA00X+020650Y+054625               S0      
317P3V3             VIA        MD0100PA00X+020735Y+096863               S0      
317P3V3             VIA        MD0100PA00X+020815Y+003225               S0      
317P3V3             VIA        MD0100PA00X+021450Y+145900               S0      
317P3V3             VIA        MD0100PA00X+021470Y+078420               S0      
317P3V3             VIA        MD0100PA00X+022050Y+006750               S0      
317P3V3             VIA        MD0100PA00X+022250Y+177620               S0      
317P3V3             VIA        MD0100PA00X+022950Y+094660               S0      
317P3V3             VIA        MD0100PA00X+025190Y+176990               S0      
317P3V3             VIA        MD0100PA00X+026550Y+172200               S0      
317P3V3             VIA        MD0100PA00X+027350Y+140350               S0      
317P3V3             VIA        MD0100PA00X+027350Y+141150               S0      
317P3V3             VIA        MD0100PA00X+027350Y+141950               S0      
317P3V3             VIA        MD0100PA00X+027350Y+142350               S0      
317P3V3             VIA        MD0100PA00X+027350Y+143150               S0      
317P3V3             VIA        MD0100PA00X+027350Y+056500               S0      
317P3V3             VIA        MD0100PA00X+027350Y+057300               S0      
317P3V3             VIA        MD0100PA00X+027350Y+057700               S0      
317P3V3             VIA        MD0100PA00X+027350Y+058500               S0      
317P3V3             VIA        MD0100PA00X+027350Y+058900               S0      
317P3V3             VIA        MD0100PA00X+027350Y+059700               S0      
317P3V3             VIA        MD0100PA00X+027965Y+144800               S0      
317P3V3             VIA        MD0100PA00X+028350Y+172200               S0      
317P3V3             VIA        MD0100PA00X+028400Y+061200               S0      
317P3V3             VIA        MD0100PA00X+028490Y+138350               S0      
317P3V3             VIA        MD0100PA00X+028760Y+144800               S0      
317P3V3             VIA        MD0100PA00X+029058Y+055900               S0      
317P3V3             VIA        MD0100PA00X+029160Y+144800               S0      
317P3V3             VIA        MD0100PA00X+029200Y+061200               S0      
317P3V3             VIA        MD0100PA00X+029200Y+083700               S0      
317P3V3             VIA        MD0100PA00X+029250Y+096550               S0      
317P3V3             VIA        MD0100PA00X+029300Y+038500               S0      
317P3V3             VIA        MD0100PA00X+029310Y+138350               S0      
317P3V3             VIA        MD0100PA00X+029350Y+073800               S0      
317P3V3             VIA        MD0100PA00X+029400Y+111150               S0      
317P3V3             VIA        MD0100PA00X+029450Y+125400               S0      
317P3V3             VIA        MD0100PA00X+029450Y+040800               S0      
317P3V3             VIA        MD0100PA00X+029500Y+124500               S0      
317P3V3             VIA        MD0100PA00X+029520Y+090300               S0      
317P3V3             VIA        MD0100PA00X+029520Y+091300               S0      
317P3V3             VIA        MD0100PA00X+029600Y+061200               S0      
317P3V3             VIA        MD0100PA00X+029700Y+175200               S0      
317P3V3             VIA        MD0100PA00X+029700Y+177700               S0      
317P3V3             VIA        MD0100PA00X+029845Y+055900               S0      
317P3V3             VIA        MD0100PA00X+029960Y+144800               S0      
317P3V3             VIA        MD0100PA00X+030140Y+140150               S0      
317P3V3             VIA        MD0100PA00X+030180Y+172210               S0      
317P3V3             VIA        MD0100PA00X+030200Y+175200               S0      
317P3V3             VIA        MD0100PA00X+030250Y+122400               S0      
317P3V3             VIA        MD0100PA00X+030320Y+042260               S0      
317P3V3             VIA        MD0100PA00X+030350Y+085310               S0      
317P3V3             VIA        MD0100PA00X+030360Y+144800               S0      
317P3V3             VIA        MD0100PA00X+030400Y+061200               S0      
317P3V3             VIA        MD0100PA00X+030520Y+090300               S0      
317P3V3             VIA        MD0100PA00X+030520Y+091300               S0      
317P3V3             VIA        MD0100PA00X+030750Y+138900               S0      
317P3V3             VIA        MD0100PA00X+030800Y+061200               S0      
317P3V3             VIA        MD0100PA00X+031160Y+144800               S0      
317P3V3             VIA        MD0100PA00X+031550Y+138900               S0      
317P3V3             VIA        MD0100PA00X+031600Y+061200               S0      
317P3V3             VIA        MD0100PA00X+031750Y+055900               S0      
317P3V3             VIA        MD0100PA00X+032010Y+058720               S0      
317P3V3             VIA        MD0100PA00X+032650Y+140540               S0      
317P3V3             VIA        MD0100PA00X+032650Y+141350               S0      
317P3V3             VIA        MD0100PA00X+032650Y+141750               S0      
317P3V3             VIA        MD0100PA00X+032650Y+142570               S0      
317P3V3             VIA        MD0100PA00X+032650Y+142970               S0      
317P3V3             VIA        MD0100PA00X+032650Y+143770               S0      
317P3V3             VIA        MD0100PA00X+032750Y+136850               S0      
317P3V3             VIA        MD0100PA00X+032800Y+137400               S0      
317P3V3             VIA        MD0100PA00X+032800Y+138150               S0      
317P3V3             VIA        MD0100PA00X+033250Y+059300               S0      
317P3V3             VIA        MD0100PA00X+033250Y+060100               S0      
317P3V3             VIA        MD0100PA00X+033600Y+057058               S0      
317P3V3             VIA        MD0100PA00X+033600Y+057860               S0      
317P3V3             VIA        MD0100PA00X+034373Y+045581               S0      
317P3V3             VIA        MD0100PA00X+034375Y+175550               S0      
317P3V3             VIA        MD0100PA00X+034376Y+125738               S0      
317P3V3             VIA        MD0100PA00X+034377Y+088590               S0      
317P3V3             VIA        MD0100PA00X+034450Y+007175               S0      
317P3V3             VIA        MD0100PA00X+034826Y+034411               S0      
317P3V3             VIA        MD0100PA00X+034826Y+164413               S0      
317P3V3             VIA        MD0100PA00X+035173Y+045581               S0      
317P3V3             VIA        MD0100PA00X+035175Y+125738               S0      
317P3V3             VIA        MD0100PA00X+035175Y+175550               S0      
317P3V3             VIA        MD0100PA00X+035179Y+088584               S0      
317P3V3             VIA        MD0100PA00X+035625Y+164412               S0      
317P3V3             VIA        MD0100PA00X+035626Y+034418               S0      
317P3V3             VIA        MD0100PA00X+035800Y+006400               S0      
317P3V3             VIA        MD0100PA00X+036075Y+012400               S0      
317P3V3             VIA        MD0100PA00X+036900Y+029400               S0      
317P3V3             VIA        MD0100PA00X+037725Y+077450               S0      
317P3V3             VIA        MD0100PA00X+037900Y+173600               S0      
317P3V3             VIA        MD0100PA00X+037926Y+045589               S0      
317P3V3             VIA        MD0100PA00X+037927Y+125738               S0      
317P3V3             VIA        MD0100PA00X+037927Y+088590               S0      
317P3V3             VIA        MD0100PA00X+038200Y+009800               S0      
317P3V3             VIA        MD0100PA00X+038300Y+173630               S0      
317P3V3             VIA        MD0100PA00X+038375Y+034450               S0      
317P3V3             VIA        MD0100PA00X+038376Y+114566               S0      
317P3V3             VIA        MD0100PA00X+038524Y+077412               S0      
317P3V3             VIA        MD0100PA00X+038725Y+045588               S0      
317P3V3             VIA        MD0100PA00X+038729Y+125736               S0      
317P3V3             VIA        MD0100PA00X+038729Y+088590               S0      
317P3V3             VIA        MD0100PA00X+039175Y+034450               S0      
317P3V3             VIA        MD0100PA00X+039176Y+114568               S0      
317P3V3             VIA        MD0100PA00X+040150Y+041025               S0      
317P3V3             VIA        MD0100PA00X+040400Y+084050               S0      
317P3V3             VIA        MD0100PA00X+040500Y+028900               S0      
317P3V3             VIA        MD0100PA00X+040550Y+119200               S0      
317P3V3             VIA        MD0100PA00X+040550Y+027750               S0      
317P3V3             VIA        MD0100PA00X+040830Y+123750               S0      
317P3V3             VIA        MD0100PA00X+041055Y+042050               S0      
317P3V3             VIA        MD0100PA00X+041055Y+085050               S0      
317P3V3             VIA        MD0100PA00X+042550Y+121525               S0      
317P3V3             VIA        MD0100PA00X+042550Y+122325               S0      
317P3V3             VIA        MD0100PA00X+042550Y+171375               S0      
317P3V3             VIA        MD0100PA00X+042588Y+172172               S0      
317P3V3             VIA        MD0100PA00X+042589Y+082073               S0      
317P3V3             VIA        MD0100PA00X+042589Y+081275               S0      
317P3V3             VIA        MD0100PA00X+054216Y+156054               S0      
317P3V3             VIA        MD0100PA00X+054216Y+156604               S0      
317P3V3             VIA        MD0100PA00X+054766Y+156054               S0      
317P3V3             VIA        MD0100PA00X+054766Y+156604               S0      
317P3V3             VIA        MD0100PA00X+006031Y+021234               S0      
317P3V3             VIA        MD0100PA00X+006243Y+060774               S0      
317P3V3             VIA        MD0100PA00X+006296Y+142260               S0      
317P3V3             VIA        MD0100PA00X+063420Y+156120               S0      
317P3V3             VIA        MD0100PA00X+063420Y+156570               S0      
317P3V3             VIA        MD0100PA00X+063970Y+156120               S0      
317P3V3             VIA        MD0100PA00X+063970Y+156570               S0      
317P3V3             VIA        MD0100PA00X+006404Y+101665               S0      
317P3V3             VIA        MD0100PA00X+064620Y+156120               S0      
317P3V3             VIA        MD0100PA00X+064620Y+156570               S0      
317P3V3             VIA        MD0100PA00X+065170Y+156120               S0      
317P3V3             VIA        MD0100PA00X+065170Y+156570               S0      
317P3V3             VIA        MD0100PA00X+065700Y+133150               S0      
317P3V3             VIA        MD0100PA00X+066000Y+105350               S0      
317P3V3             VIA        MD0100PA00X+066150Y+065050               S0      
317P3V3             VIA        MD0100PA00X+066200Y+118350               S0      
317P3V3             VIA        MD0100PA00X+066200Y+145900               S0      
317P3V3             VIA        MD0100PA00X+066200Y+082660               S0      
317P3V3             VIA        MD0100PA00X+066300Y+053550               S0      
317P3V3             VIA        MD0100PA00X+066500Y+093700               S0      
317P3V3             VIA        MD0100PA00X+007100Y+012524               S0      
317P3V3             VIA        MD0100PA00X+007100Y+134177               S0      
317P3V3             VIA        MD0100PA00X+007100Y+174728               S0      
317P3V3             VIA        MD0100PA00X+007100Y+053075               S0      
317P3V3             VIA        MD0100PA00X+007100Y+093626               S0      
317P3V3             VIA        MD0100PA00X+007212Y+184118               S0      
317P3V3             VIA        MD0100PA00X+072870Y+193310               S0      
317P3V3             VIA        MD0100PA00X+075350Y+166200               S0      
317P3V3             VIA        MD0100PA00X+075350Y+166650               S0      
317P3V3             VIA        MD0100PA00X+075900Y+166200               S0      
317P3V3             VIA        MD0100PA00X+075900Y+166650               S0      
317P3V3             VIA        MD0100PA00X+076550Y+166200               S0      
317P3V3             VIA        MD0100PA00X+076550Y+166650               S0      
317P3V3             VIA        MD0100PA00X+007675Y+146276               S0      
317P3V3             VIA        MD0100PA00X+007716Y+181828               S0      
317P3V3             VIA        MD0100PA00X+077100Y+166200               S0      
317P3V3             VIA        MD0100PA00X+077100Y+166650               S0      
317P3V3             VIA        MD0100PA00X+007775Y+105675               S0      
317P3V3             VIA        MD0100PA00X+078250Y+064800               S0      
317P3V3             VIA        MD0100PA00X+008015Y+144678               S0      
317P3V3             VIA        MD0100PA00X+008015Y+023025               S0      
317P3V3             VIA        MD0100PA00X+008015Y+063576               S0      
317P3V3             VIA        MD0100PA00X+008047Y+157012               S0      
317P3V3             VIA        MD0100PA00X+008060Y+184890               S0      
317P3V3             VIA        MD0100PA00X+080850Y+162150               S0      
317P3V3             VIA        MD0100PA00X+080850Y+162600               S0      
317P3V3             VIA        MD0100PA00X+080850Y+163050               S0      
317P3V3             VIA        MD0100PA00X+081300Y+158575               S0      
317P3V3             VIA        MD0100PA00X+081335Y+036925               S0      
317P3V3             VIA        MD0100PA00X+081400Y+162150               S0      
317P3V3             VIA        MD0100PA00X+081400Y+162600               S0      
317P3V3             VIA        MD0100PA00X+081400Y+163050               S0      
317P3V3             VIA        MD0100PA00X+081500Y+178500               S0      
317P3V3             VIA        MD0100PA00X+008169Y+103960               S0      
317P3V3             VIA        MD0100PA00X+081650Y+017100               S0      
317P3V3             VIA        MD0100PA00X+081900Y+183900               S0      
317P3V3             VIA        MD0100PA00X+082450Y+017100               S0      
317P3V3             VIA        MD0100PA00X+008275Y+145515               S0      
317P3V3             VIA        MD0100PA00X+083250Y+017100               S0      
317P3V3             VIA        MD0100PA00X+083475Y+182329               S0      
317P3V3             VIA        MD0100PA00X+084400Y+019000               S0      
317P3V3             VIA        MD0100PA00X+084405Y+033730               S0      
317P3V3             VIA        MD0100PA00X+084460Y+114870               S0      
317P3V3             VIA        MD0100PA00X+084470Y+194520               S0      
317P3V3             VIA        MD0100PA00X+084560Y+155430               S0      
317P3V3             VIA        MD0100PA00X+084620Y+074330               S0      
317P3V3             VIA        MD0100PA00X+008522Y+064523               S0      
317P3V3             VIA        MD0100PA00X+008543Y+023972               S0      
317P3V3             VIA        MD0100PA00X+085762Y+095898               S0      
317P3V3             VIA        MD0100PA00X+085769Y+136449               S0      
317P3V3             VIA        MD0100PA00X+085774Y+055347               S0      
317P3V3             VIA        MD0100PA00X+086696Y+016254               S0      
317P3V3             VIA        MD0100PA00X+008690Y+077475               S0      
317P3V3             VIA        MD0100PA00X+087600Y+186400               S0      
317P3V3             VIA        MD0100PA00X+087650Y+105350               S0      
317P3V3             VIA        MD0100PA00X+087650Y+145900               S0      
317P3V3             VIA        MD0100PA00X+087650Y+025100               S0      
317P3V3             VIA        MD0100PA00X+087650Y+064800               S0      
317P3V3             VIA        MD0100PA00X+088322Y+137350               S0      
317P3V3             VIA        MD0100PA00X+088378Y+178105               S0      
317P3V3             VIA        MD0100PA00X+088378Y+056452               S0      
317P3V3             VIA        MD0100PA00X+088378Y+097003               S0      
317P3V3             VIA        MD0100PA00X+008850Y+117730               S0      
317P3V3             VIA        MD0100PA00X+088553Y+016480               S0      
317P3V3             VIA        MD0100PA00X+089555Y+176925               S0      
317P3V3             VIA        MD0100PA00X+089555Y+055272               S0      
317P3V3             VIA        MD0100PA00X+089555Y+095823               S0      
317P3V3             VIA        MD0100PA00X+089565Y+136374               S0      
317P3V3             VIA        MD0100PA00X+089644Y+014720               S0      
317P3V3             VIA        MD0100PA00X+090144Y+105587               S0      
317P3V3             VIA        MD0100PA00X+090144Y+146138               S0      
317P3V3             VIA        MD0100PA00X+090144Y+186689               S0      
317P3V3             VIA        MD0100PA00X+090144Y+024484               S0      
317P3V3             VIA        MD0100PA00X+090144Y+065035               S0      
317P3V3             VIA        MD0100PA00X+009104Y+183528               S0      
317P3V3             VIA        MD0100PA00X+091050Y+173460               S0      
317P3V3             VIA        MD0100PA00X+092630Y+137650               S0      
317P3V3             VIA        MD0100PA00X+092630Y+138099               S0      
317P3V3             VIA        MD0100PA00X+092635Y+016000               S0      
317P3V3             VIA        MD0100PA00X+092635Y+016445               S0      
317P3V3             VIA        MD0100PA00X+092637Y+056550               S0      
317P3V3             VIA        MD0100PA00X+092637Y+056997               S0      
317P3V3             VIA        MD0100PA00X+092640Y+178200               S0      
317P3V3             VIA        MD0100PA00X+092640Y+178650               S0      
317P3V3             VIA        MD0100PA00X+092648Y+097100               S0      
317P3V3             VIA        MD0100PA00X+092648Y+097548               S0      
317P3V3             VIA        MD0100PA00X+009270Y+035840               S0      
317P3V3             VIA        MD0100PA00X+009590Y+060550               S0      
317P3V3             VIA        MD0100PA00X+095900Y+163100               S0      
317P3V3             VIA        MD0100PA00X+095900Y+165700               S0      
317P3V3             VIA        MD0100PA00X+095900Y+167500               S0      
317P3V3             VIA        MD0100PA00X+009600Y+011900               S0      
317P3V3             VIA        MD0100PA00X+009600Y+133500               S0      
317P3V3             VIA        MD0100PA00X+009600Y+052400               S0      
317P3V3             VIA        MD0100PA00X+009600Y+093000               S0      
317P3V3             VIA        MD0100PA00X+009650Y+101120               S0      
317P3V3             VIA        MD0100PA00X+009930Y+143120               S0      
317P3V3             VIA        MD0100PA00X+009990Y+141960               S0      
327P12V                               A01X+096070Y+142518X0830Y0570     S0      
327P12V                               A01X+097320Y+142518X0830Y0570     S0      
327P12V                               A01X+002922Y+184060X0570Y0830     S0      
327P12V                               A01X+002922Y+187750X0570Y0830     S0      
327P12V                               A01X+002922Y+185290X0570Y0830     S0      
327P12V                               A01X+002922Y+186520X0570Y0830     S0      
327P12V                               A01X+000886Y+182024X0980Y0200     S0      
327P12V                               A01X+000886Y+182339X0980Y0200     S0      
327P12V                               A01X+000886Y+182654X0980Y0200     S0      
327P12V                               A01X+000886Y+182969X0980Y0200     S0      
327P12V                               A01X+000886Y+183284X0980Y0200     S0      
327P12V                               A01X+000886Y+183599X0980Y0200     S0      
327P12V                               A08X+000886Y+182024X0980Y0200     S0      
327P12V                               A08X+000886Y+182339X0980Y0200     S0      
327P12V                               A08X+000886Y+182654X0980Y0200     S0      
327P12V                               A08X+000886Y+182969X0980Y0200     S0      
327P12V                               A08X+000886Y+183284X0980Y0200     S0      
327P12V                               A08X+000886Y+183599X0980Y0200     S0      
327P12V                               A01X+087885Y+166025X0500Y0650     S0      
327P12V                               A01X+080244Y+194911X0650Y0250     S0      
327P12V                               A01X+080244Y+194411X0650Y0250     S0      
327P12V                               A01X+080244Y+193911X0650Y0250     S0      
327P12V                               A01X+083550Y+116850X0650Y0250     S0      
327P12V                               A01X+083550Y+116350X0650Y0250     S0      
327P12V                               A01X+083550Y+115850X0650Y0250     S0      
327P12V                               A01X+083550Y+076300X0650Y0250     S0      
327P12V                               A01X+083550Y+075800X0650Y0250     S0      
327P12V                               A01X+083550Y+075300X0650Y0250     S0      
327P12V                               A01X+083550Y+035750X0650Y0250     S0      
327P12V                               A01X+083550Y+035250X0650Y0250     S0      
327P12V                               A01X+083550Y+034750X0650Y0250     S0      
327P12V                               A01X+083550Y+157400X0650Y0250     S0      
327P12V                               A01X+083550Y+156900X0650Y0250     S0      
327P12V                               A01X+083550Y+156400X0650Y0250     S0      
327P12V                               A01X+018550Y+004400X0650Y0250     S0      
327P12V                               A01X+018550Y+004900X0650Y0250     S0      
327P12V                               A01X+018550Y+005400X0650Y0250     S0      
327P12V                               A01X+013690Y+041810X0650Y0250     S0      
327P12V                               A01X+013690Y+042310X0650Y0250     S0      
327P12V                               A01X+013690Y+042810X0650Y0250     S0      
327P12V                               A01X+013690Y+082360X0650Y0250     S0      
327P12V                               A01X+013690Y+082860X0650Y0250     S0      
327P12V                               A01X+013690Y+083360X0650Y0250     S0      
327P12V                               A01X+013720Y+122910X0650Y0250     S0      
327P12V                               A01X+013720Y+123410X0650Y0250     S0      
327P12V                               A01X+013720Y+123910X0650Y0250     S0      
327P12V                               A01X+013840Y+163460X0650Y0250     S0      
327P12V                               A01X+013840Y+163960X0650Y0250     S0      
327P12V                               A01X+013840Y+164460X0650Y0250     S0      
327P12V                               A01X+010720Y+035750X0650Y0250     S0      
327P12V                               A01X+010720Y+035250X0650Y0250     S0      
327P12V                               A01X+010720Y+034750X0650Y0250     S0      
327P12V                               A01X+010720Y+076300X0650Y0250     S0      
327P12V                               A01X+010720Y+075800X0650Y0250     S0      
327P12V                               A01X+010720Y+075300X0650Y0250     S0      
327P12V                               A01X+010720Y+116890X0650Y0250     S0      
327P12V                               A01X+010720Y+116390X0650Y0250     S0      
327P12V                               A01X+010720Y+115890X0650Y0250     S0      
327P12V                               A01X+010670Y+156910X0650Y0250     S0      
327P12V                               A01X+010670Y+156410X0650Y0250     S0      
327P12V                               A01X+010670Y+155910X0650Y0250     S0      
327P12V                               A01X+007950Y+194900X0650Y0250     S0      
327P12V                               A01X+007950Y+194400X0650Y0250     S0      
327P12V                               A01X+007950Y+193900X0650Y0250     S0      
317P12V                         D0340PA01X+090150Y+168520               S0      
317P12V                         D0220PA01X+092320Y+177750               S0      
317P12V                         D0220PA01X+092320Y+137200               S0      
317P12V                         D0220PA01X+092320Y+096650               S0      
317P12V                         D0220PA01X+092320Y+056100               S0      
317P12V                         D0220PA01X+092320Y+015550               S0      
317P12V                         D0220PA01X+019470Y+178150               S0      
317P12V                         D0220PA01X+019020Y+137300               S0      
317P12V                         D0220PA01X+019570Y+096950               S0      
317P12V                         D0220PA01X+019520Y+056450               S0      
317P12V                         D0220PA01X+019570Y+015800               S0      
317P12V                         D0220PA01X+009720Y+182150               S0      
317P12V                         D0220PA01X+009620Y+141750               S0      
317P12V                         D0220PA01X+009300Y+100880               S0      
317P12V                         D0220PA01X+009250Y+060330               S0      
317P12V                         D0220PA01X+009620Y+020100               S0      
317P12V                         D0220PA01X+078884Y+193521               S0      
317P12V                         D0220PA01X+079254Y+193951               S0      
317P12V                         D0220PA01X+082400Y+115570               S0      
317P12V                         D0220PA01X+082770Y+116000               S0      
317P12V                         D0220PA01X+082400Y+075020               S0      
317P12V                         D0220PA01X+082770Y+075450               S0      
317P12V                         D0220PA01X+082400Y+034470               S0      
317P12V                         D0220PA01X+082770Y+034900               S0      
317P12V                         D0220PA01X+082400Y+156120               S0      
317P12V                         D0220PA01X+082770Y+156550               S0      
317P12V                         D0220PA01X+078839Y+196096               S0      
317P12V                         D0220PA01X+084015Y+158695               S0      
317P12V                         D0220PA01X+084015Y+118145               S0      
317P12V                         D0220PA01X+084015Y+077595               S0      
317P12V                         D0220PA01X+084015Y+037045               S0      
317P12V                         D0220PA01X+089850Y+173070               S0      
317P12V                         D0220PA01X+018085Y+003105               S0      
317P12V                         D0220PA01X+012998Y+040468               S0      
317P12V                         D0220PA01X+013035Y+081055               S0      
317P12V                         D0220PA01X+013035Y+121605               S0      
317P12V                         D0220PA01X+013035Y+162255               S0      
317P12V                         D0220PA01X+011365Y+037045               S0      
317P12V                         D0220PA01X+011365Y+077595               S0      
317P12V                         D0220PA01X+011365Y+118145               S0      
317P12V                         D0220PA01X+010303Y+158133               S0      
317P12V                         D0220PA01X+006105Y+196185               S0      
317P12V                         D0220PA01X+036380Y+005800               S0      
317P12V                         D0220PA01X+019700Y+005680               S0      
317P12V                         D0220PA01X+019330Y+005250               S0      
317P12V                         D0220PA01X+014840Y+043090               S0      
317P12V                         D0220PA01X+014840Y+083640               S0      
317P12V                         D0220PA01X+014470Y+042660               S0      
317P12V                         D0220PA01X+014470Y+083210               S0      
317P12V                         D0220PA01X+014870Y+124190               S0      
317P12V                         D0220PA01X+014990Y+164740               S0      
317P12V                         D0220PA01X+014500Y+123760               S0      
317P12V                         D0220PA01X+014620Y+164310               S0      
317P12V                         D0220PA01X+009570Y+034470               S0      
317P12V                         D0220PA01X+009570Y+075020               S0      
317P12V                         D0220PA01X+009940Y+034900               S0      
317P12V                         D0220PA01X+009940Y+075450               S0      
317P12V                         D0220PA01X+009570Y+115610               S0      
317P12V                         D0220PA01X+009500Y+155220               S0      
317P12V                         D0220PA01X+009940Y+116040               S0      
317P12V                         D0220PA01X+009870Y+155650               S0      
317P12V                         D0220PA01X+006550Y+193620               S0      
317P12V                         D0220PA01X+006920Y+194050               S0      
327P12V                               A01X+098380Y+142530X0650Y0500     S0      
317P12V                         D0340PA01X+003150Y+182730               S0      
317P12V                         D0340PA01X+003150Y+183210               S0      
317P12V                         D0340PA01X+099050Y+142230               S0      
317P12V                         D0240PA01X+099460Y+142110               S0      
317P12V                         D0240PA01X+003260Y+181970               S0      
317P12V                         D0240PA01X+003260Y+182320               S0      
317P12V                         D0240PA01X+079284Y+193531               S0      
317P12V                         D0240PA01X+082800Y+115580               S0      
317P12V                         D0240PA01X+082800Y+075030               S0      
317P12V                         D0240PA01X+082800Y+034480               S0      
317P12V                         D0240PA01X+082800Y+156130               S0      
317P12V                         D0240PA01X+019300Y+005670               S0      
317P12V                         D0240PA01X+014440Y+043080               S0      
317P12V                         D0240PA01X+014440Y+083630               S0      
317P12V                         D0240PA01X+014470Y+124180               S0      
317P12V                         D0240PA01X+014590Y+164730               S0      
317P12V                         D0240PA01X+009970Y+034480               S0      
317P12V                         D0240PA01X+009970Y+075030               S0      
317P12V                         D0240PA01X+009970Y+115620               S0      
317P12V                         D0240PA01X+009900Y+155230               S0      
317P12V                         D0240PA01X+006950Y+193630               S0      
327P12V                               A08X+099025Y+144798X0010Y0010     S0      
317P12V                         D1767PA08X+100155Y+144256               S0      
327P12V                               A08X+099025Y+145698X0010Y0010     S0      
327P12V                               A08X+099025Y+146098X0010Y0010     S0      
327P12V                               A08X+099025Y+148798X0010Y0010     S0      
317P12V                         D1767PA08X+100155Y+148256               S0      
327P12V                               A08X+099025Y+149698X0010Y0010     S0      
327P12V                               A08X+099025Y+150098X0010Y0010     S0      
327P12V                               A01X+098875Y+150098X0010Y0010     S0      
327P12V                               A01X+098875Y+149698X0010Y0010     S0      
317P12V                         D1767PA01X+100155Y+148256               S0      
327P12V                               A01X+098875Y+148798X0010Y0010     S0      
327P12V                               A01X+098875Y+146098X0010Y0010     S0      
327P12V                               A01X+098875Y+145698X0010Y0010     S0      
317P12V                         D1767PA01X+100155Y+144256               S0      
327P12V                               A01X+098875Y+144798X0010Y0010     S0      
317P12V             VIA        MD0280PA08X+095000Y+144000               S0      
317P12V             VIA        MD0280PA08X+095000Y+147000               S0      
317P12V             VIA        MD0280PA08X+095000Y+150000               S0      
317P12V             VIA        MD0280PA08X+096000Y+146000               S0      
317P12V             VIA        MD0280PA08X+097500Y+142500               S0      
317P12V             VIA        MD0100PA00X+010030Y+182080               S0      
317P12V             VIA        MD0100PA00X+010350Y+157320               S0      
317P12V             VIA        MD0100PA00X+010350Y+157670               S0      
317P12V             VIA        MD0100PA00X+010650Y+117350               S0      
317P12V             VIA        MD0100PA00X+010650Y+117700               S0      
317P12V             VIA        MD0100PA00X+010650Y+036250               S0      
317P12V             VIA        MD0100PA00X+010650Y+036600               S0      
317P12V             VIA        MD0100PA00X+010650Y+076800               S0      
317P12V             VIA        MD0100PA00X+010650Y+077150               S0      
317P12V             VIA        MD0100PA00X+010700Y+157320               S0      
317P12V             VIA        MD0100PA00X+010700Y+157670               S0      
317P12V             VIA        MD0100PA00X+011000Y+117350               S0      
317P12V             VIA        MD0100PA00X+011000Y+117700               S0      
317P12V             VIA        MD0100PA00X+011000Y+036250               S0      
317P12V             VIA        MD0100PA00X+011000Y+036600               S0      
317P12V             VIA        MD0100PA00X+011000Y+076800               S0      
317P12V             VIA        MD0100PA00X+011000Y+077150               S0      
317P12V             VIA        MD0100PA00X+011050Y+157320               S0      
317P12V             VIA        MD0100PA00X+011050Y+157670               S0      
317P12V             VIA        MD0100PA00X+011350Y+117350               S0      
317P12V             VIA        MD0100PA00X+011350Y+117700               S0      
317P12V             VIA        MD0100PA00X+011350Y+036250               S0      
317P12V             VIA        MD0100PA00X+011350Y+036600               S0      
317P12V             VIA        MD0100PA00X+011350Y+076800               S0      
317P12V             VIA        MD0100PA00X+011350Y+077150               S0      
317P12V             VIA        MD0100PA00X+011400Y+157320               S0      
317P12V             VIA        MD0100PA00X+011400Y+157670               S0      
317P12V             VIA        MD0100PA00X+011700Y+117350               S0      
317P12V             VIA        MD0100PA00X+011700Y+117700               S0      
317P12V             VIA        MD0100PA00X+011700Y+036250               S0      
317P12V             VIA        MD0100PA00X+011700Y+036600               S0      
317P12V             VIA        MD0100PA00X+011700Y+076800               S0      
317P12V             VIA        MD0100PA00X+011700Y+077150               S0      
317P12V             VIA        MD0100PA00X+012680Y+162660               S0      
317P12V             VIA        MD0100PA00X+012680Y+163010               S0      
317P12V             VIA        MD0100PA00X+012700Y+122050               S0      
317P12V             VIA        MD0100PA00X+012700Y+122400               S0      
317P12V             VIA        MD0100PA00X+012700Y+040950               S0      
317P12V             VIA        MD0100PA00X+012700Y+041300               S0      
317P12V             VIA        MD0100PA00X+012700Y+081500               S0      
317P12V             VIA        MD0100PA00X+012700Y+081850               S0      
317P12V             VIA        MD0100PA00X+013030Y+162660               S0      
317P12V             VIA        MD0100PA00X+013030Y+163010               S0      
317P12V             VIA        MD0100PA00X+013050Y+122050               S0      
317P12V             VIA        MD0100PA00X+013050Y+122400               S0      
317P12V             VIA        MD0100PA00X+013050Y+040950               S0      
317P12V             VIA        MD0100PA00X+013050Y+041300               S0      
317P12V             VIA        MD0100PA00X+013050Y+081500               S0      
317P12V             VIA        MD0100PA00X+013050Y+081850               S0      
317P12V             VIA        MD0100PA00X+013380Y+162660               S0      
317P12V             VIA        MD0100PA00X+013380Y+163010               S0      
317P12V             VIA        MD0100PA00X+013400Y+122050               S0      
317P12V             VIA        MD0100PA00X+013400Y+122400               S0      
317P12V             VIA        MD0100PA00X+013400Y+040950               S0      
317P12V             VIA        MD0100PA00X+013400Y+041300               S0      
317P12V             VIA        MD0100PA00X+013400Y+081500               S0      
317P12V             VIA        MD0100PA00X+013400Y+081850               S0      
317P12V             VIA        MD0100PA00X+013730Y+162660               S0      
317P12V             VIA        MD0100PA00X+013730Y+163010               S0      
317P12V             VIA        MD0100PA00X+013750Y+122050               S0      
317P12V             VIA        MD0100PA00X+013750Y+122400               S0      
317P12V             VIA        MD0100PA00X+013750Y+040950               S0      
317P12V             VIA        MD0100PA00X+013750Y+041300               S0      
317P12V             VIA        MD0100PA00X+013750Y+081500               S0      
317P12V             VIA        MD0100PA00X+013750Y+081850               S0      
317P12V             VIA        MD0100PA00X+017730Y+003550               S0      
317P12V             VIA        MD0100PA00X+017730Y+003900               S0      
317P12V             VIA        MD0100PA00X+018080Y+003550               S0      
317P12V             VIA        MD0100PA00X+018080Y+003900               S0      
317P12V             VIA        MD0100PA00X+018430Y+003550               S0      
317P12V             VIA        MD0100PA00X+018430Y+003900               S0      
317P12V             VIA        MD0100PA00X+018780Y+003550               S0      
317P12V             VIA        MD0100PA00X+018780Y+003900               S0      
317P12V             VIA        MD0100PA00X+019340Y+137300               S0      
317P12V             VIA        MD0100PA00X+019525Y+056130               S0      
317P12V             VIA        MD0100PA00X+019790Y+178150               S0      
317P12V             VIA        MD0100PA00X+019880Y+015800               S0      
317P12V             VIA        MD0100PA00X+019890Y+096950               S0      
317P12V             VIA        MD0100PA00X+036375Y+005425               S0      
317P12V             VIA        MD0100PA00X+005780Y+196180               S0      
317P12V             VIA        MD0100PA00X+007340Y+195440               S0      
317P12V             VIA        MD0100PA00X+007340Y+195790               S0      
317P12V             VIA        MD0100PA00X+007690Y+195440               S0      
317P12V             VIA        MD0100PA00X+007690Y+195790               S0      
317P12V             VIA        MD0100PA00X+078524Y+196091               S0      
317P12V             VIA        MD0100PA00X+079634Y+193701               S0      
317P12V             VIA        MD0100PA00X+079634Y+194051               S0      
317P12V             VIA        MD0100PA00X+079724Y+195331               S0      
317P12V             VIA        MD0100PA00X+079724Y+195681               S0      
317P12V             VIA        MD0100PA00X+080074Y+195331               S0      
317P12V             VIA        MD0100PA00X+080074Y+195681               S0      
317P12V             VIA        MD0100PA00X+008040Y+195440               S0      
317P12V             VIA        MD0100PA00X+008040Y+195790               S0      
317P12V             VIA        MD0100PA00X+080424Y+195331               S0      
317P12V             VIA        MD0100PA00X+080424Y+195681               S0      
317P12V             VIA        MD0100PA00X+083300Y+117700               S0      
317P12V             VIA        MD0100PA00X+083300Y+157900               S0      
317P12V             VIA        MD0100PA00X+083300Y+158250               S0      
317P12V             VIA        MD0100PA00X+083300Y+036250               S0      
317P12V             VIA        MD0100PA00X+083300Y+036600               S0      
317P12V             VIA        MD0100PA00X+083300Y+076800               S0      
317P12V             VIA        MD0100PA00X+083300Y+077150               S0      
317P12V             VIA        MD0100PA00X+083650Y+117700               S0      
317P12V             VIA        MD0100PA00X+083650Y+157900               S0      
317P12V             VIA        MD0100PA00X+083650Y+158250               S0      
317P12V             VIA        MD0100PA00X+083650Y+036250               S0      
317P12V             VIA        MD0100PA00X+083650Y+036600               S0      
317P12V             VIA        MD0100PA00X+083650Y+076800               S0      
317P12V             VIA        MD0100PA00X+083650Y+077150               S0      
317P12V             VIA        MD0100PA00X+008390Y+195440               S0      
317P12V             VIA        MD0100PA00X+084000Y+117700               S0      
317P12V             VIA        MD0100PA00X+084000Y+157900               S0      
317P12V             VIA        MD0100PA00X+084000Y+158250               S0      
317P12V             VIA        MD0100PA00X+084000Y+036250               S0      
317P12V             VIA        MD0100PA00X+084000Y+036600               S0      
317P12V             VIA        MD0100PA00X+084000Y+076800               S0      
317P12V             VIA        MD0100PA00X+084000Y+077150               S0      
317P12V             VIA        MD0100PA00X+084350Y+117700               S0      
317P12V             VIA        MD0100PA00X+084350Y+157900               S0      
317P12V             VIA        MD0100PA00X+084350Y+158250               S0      
317P12V             VIA        MD0100PA00X+084350Y+036250               S0      
317P12V             VIA        MD0100PA00X+084350Y+036600               S0      
317P12V             VIA        MD0100PA00X+084350Y+076800               S0      
317P12V             VIA        MD0100PA00X+084350Y+077150               S0      
317P12V             VIA        MD0100PA00X+008750Y+195430               S0      
317P12V             VIA        MD0100PA00X+087785Y+165075               S0      
317P12V             VIA        MD0100PA00X+087785Y+165425               S0      
317P12V             VIA        MD0100PA00X+088135Y+165075               S0      
317P12V             VIA        MD0100PA00X+088135Y+165425               S0      
317P12V             VIA        MD0100PA00X+008940Y+060325               S0      
317P12V             VIA        MD0100PA00X+089850Y+173400               S0      
317P12V             VIA        MD0100PA00X+090150Y+168150               S0      
317P12V             VIA        MD0100PA00X+092630Y+137200               S0      
317P12V             VIA        MD0100PA00X+092635Y+015550               S0      
317P12V             VIA        MD0100PA00X+092637Y+056100               S0      
317P12V             VIA        MD0100PA00X+092640Y+177750               S0      
317P12V             VIA        MD0100PA00X+092648Y+096650               S0      
317P12V             VIA        MD0100PA00X+009300Y+100570               S0      
317P12V             VIA        MD0100PA00X+009625Y+141440               S0      
317P12V             VIA        MD0100PA00X+009930Y+020100               S0      
317P12V             VIA        MD0160PA00X+100500Y+142500               S0      
317P12V             VIA        MD0160PA00X+001250Y+184000               S0      
317P12V             VIA        MD0160PA00X+001250Y+184500               S0      
317P12V             VIA        MD0160PA00X+001250Y+185000               S0      
317P12V             VIA        MD0160PA00X+001250Y+185500               S0      
317P12V             VIA        MD0160PA00X+001250Y+187000               S0      
317P12V             VIA        MD0160PA00X+001750Y+182750               S0      
317P12V             VIA        MD0160PA00X+001750Y+183250               S0      
317P12V             VIA        MD0160PA00X+001750Y+183750               S0      
317P12V             VIA        MD0160PA00X+001750Y+184250               S0      
317P12V             VIA        MD0160PA00X+001750Y+184750               S0      
317P12V             VIA        MD0160PA00X+001750Y+185250               S0      
317P12V             VIA        MD0160PA00X+001750Y+185750               S0      
317P12V             VIA        MD0160PA00X+001750Y+186750               S0      
317P12V             VIA        MD0160PA00X+001750Y+187250               S0      
317P12V             VIA        MD0160PA00X+002250Y+183000               S0      
317P12V             VIA        MD0160PA00X+002250Y+183500               S0      
317P12V             VIA        MD0160PA00X+002250Y+184000               S0      
317P12V             VIA        MD0160PA00X+002250Y+184500               S0      
317P12V             VIA        MD0160PA00X+002250Y+185000               S0      
317P12V             VIA        MD0160PA00X+002250Y+185500               S0      
317P12V             VIA        MD0160PA00X+002250Y+186000               S0      
317P12V             VIA        MD0160PA00X+002250Y+186500               S0      
317P12V             VIA        MD0160PA00X+002250Y+187000               S0      
317P12V             VIA        MD0160PA00X+002260Y+182520               S0      
317P12V             VIA        MD0160PA00X+000760Y+185500               S0      
317P12V             VIA        MD0160PA00X+093500Y+142500               S0      
317P12V             VIA        MD0160PA00X+093500Y+143500               S0      
317P12V             VIA        MD0160PA00X+093500Y+144500               S0      
317P12V             VIA        MD0160PA00X+093500Y+145500               S0      
317P12V             VIA        MD0160PA00X+093500Y+146500               S0      
317P12V             VIA        MD0160PA00X+093500Y+147500               S0      
317P12V             VIA        MD0160PA00X+093500Y+148500               S0      
317P12V             VIA        MD0160PA00X+093500Y+149500               S0      
317P12V             VIA        MD0160PA00X+093500Y+150500               S0      
317P12V             VIA        MD0160PA00X+094500Y+142500               S0      
317P12V             VIA        MD0160PA00X+094500Y+143500               S0      
317P12V             VIA        MD0160PA00X+094500Y+144500               S0      
317P12V             VIA        MD0160PA00X+094500Y+145500               S0      
317P12V             VIA        MD0160PA00X+094500Y+146500               S0      
317P12V             VIA        MD0160PA00X+094500Y+147500               S0      
317P12V             VIA        MD0160PA00X+094500Y+148500               S0      
317P12V             VIA        MD0160PA00X+094500Y+149500               S0      
317P12V             VIA        MD0160PA00X+094500Y+150500               S0      
317P12V             VIA        MD0160PA00X+095380Y+142490               S0      
317P12V             VIA        MD0160PA00X+095500Y+143500               S0      
317P12V             VIA        MD0160PA00X+095500Y+144500               S0      
317P12V             VIA        MD0160PA00X+095500Y+145500               S0      
317P12V             VIA        MD0160PA00X+095500Y+146500               S0      
317P12V             VIA        MD0160PA00X+095500Y+147500               S0      
317P12V             VIA        MD0160PA00X+095500Y+148500               S0      
317P12V             VIA        MD0160PA00X+095500Y+149500               S0      
317P12V             VIA        MD0160PA00X+095500Y+150500               S0      
317P12V             VIA        MD0160PA00X+096500Y+143500               S0      
317P12V             VIA        MD0160PA00X+096500Y+144500               S0      
317P12V             VIA        MD0160PA00X+096500Y+145500               S0      
317P12V             VIA        MD0160PA00X+096500Y+146500               S0      
317P12V             VIA        MD0160PA00X+096500Y+147500               S0      
317P12V             VIA        MD0160PA00X+096500Y+148500               S0      
317P12V             VIA        MD0160PA00X+096500Y+149500               S0      
317P12V             VIA        MD0160PA00X+096500Y+150500               S0      
317P12V             VIA        MD0160PA00X+097500Y+143500               S0      
317P12V             VIA        MD0160PA00X+097500Y+144500               S0      
317P12V             VIA        MD0160PA00X+097500Y+145500               S0      
317P12V             VIA        MD0160PA00X+097500Y+146500               S0      
317P12V             VIA        MD0160PA00X+097500Y+147500               S0      
317P12V             VIA        MD0160PA00X+097500Y+148500               S0      
317P12V             VIA        MD0160PA00X+097500Y+149500               S0      
317P12V             VIA        MD0160PA00X+098490Y+143040               S0      
317P12V             VIA        MD0160PA00X+099060Y+142710               S0      
317P12V             VIA        MD0160PA00X+099500Y+142500               S0      
317I2C_C_SDA                    D0220PA01X+095900Y+166370               S0      
317I2C_C_SDA                    D0220PA01X+095470Y+166350               S0      
317I2C_C_SDA                    D0340PA01X+096930Y+166100               S0      
327I2C_C_SDA                          A08X+100974Y+166110X2300Y0320     S0      
317I2C_C_SDA        VIA        MD0120PA00X+097950Y+166225               S0      
317I2C_C_SCL                    D0220PA01X+095900Y+166830               S0      
317I2C_C_SCL                    D0220PA01X+095470Y+166850               S0      
317I2C_C_SCL                    D0340PA01X+096930Y+167100               S0      
327I2C_C_SCL                          A08X+100974Y+167110X2300Y0320     S0      
317I2C_C_SCL        VIA        MD0120PA00X+097950Y+166975               S0      
327P12V_SENSE                         A01X+036047Y+008835X0120Y0600     S0      
317P12V_SENSE                   D0220PA01X+036720Y+006850               S0      
317P12V_SENSE                   D0220PA01X+036720Y+005800               S0      
317P12V_SENSE                   D0240PA01X+036730Y+007650               S0      
317P12V_SENSE       VIA        MD0280PA01X+036350Y+008150               S0      
317P12V_SENSE       VIA        MD0280PA01X+036725Y+006300               S0      
327P3V3_SENSE                         A01X+036244Y+010465X0120Y0600     S0      
317P3V3_SENSE                   D0220PA01X+037750Y+010470               S0      
317P3V3_SENSE                   D0220PA01X+038200Y+010470               S0      
317P3V3_SENSE                   D0240PA01X+037350Y+010480               S0      
317P3V3_SENSE       VIA        MD0280PA01X+036835Y+010465               S0      
327NNAME00002                         A01X+036244Y+008835X0120Y0600     S0      
317NNAME00002                   D0220PA01X+037810Y+008810               S0      
317NNAME00002                   D0220PA01X+038220Y+008810               S0      
317NNAME00002                   D0240PA01X+037430Y+008820               S0      
317NNAME00002       VIA        MD0280PA01X+036880Y+008830               S0      
327SW_SSD0_N                          A01X+077784Y+193851X0220Y0400     S0      
327SW_SSD0_N                          A01X+080244Y+193411X0650Y0250     S0      
317SW_SSD0_N                    D0220PA01X+078884Y+193181               S0      
317SW_SSD0_N                    D0220PA01X+078434Y+193181               S0      
317SW_SSD0_N                    D0240PA01X+079284Y+193171               S0      
317SW_SSD0_N        VIA        MD0280PA01X+077909Y+193176               S0      
327SW_SSD1_N                          A01X+081300Y+156450X0220Y0400     S0      
327SW_SSD1_N                          A01X+083550Y+155900X0650Y0250     S0      
317SW_SSD1_N                    D0220PA01X+081950Y+155780               S0      
317SW_SSD1_N                    D0220PA01X+082400Y+155780               S0      
317SW_SSD1_N                    D0240PA01X+082800Y+155770               S0      
317SW_SSD1_N        VIA        MD0280PA01X+081425Y+155775               S0      
327SW_SSD2_N                          A01X+081300Y+115900X0220Y0400     S0      
327SW_SSD2_N                          A01X+083550Y+115350X0650Y0250     S0      
317SW_SSD2_N                    D0220PA01X+081950Y+115230               S0      
317SW_SSD2_N                    D0220PA01X+082400Y+115230               S0      
317SW_SSD2_N                    D0240PA01X+082800Y+115220               S0      
317SW_SSD2_N        VIA        MD0280PA01X+081425Y+115225               S0      
327SW_SSD3_N                          A01X+081300Y+075350X0220Y0400     S0      
327SW_SSD3_N                          A01X+083550Y+074800X0650Y0250     S0      
317SW_SSD3_N                    D0220PA01X+081950Y+074680               S0      
317SW_SSD3_N                    D0220PA01X+082400Y+074680               S0      
317SW_SSD3_N                    D0240PA01X+082800Y+074670               S0      
317SW_SSD3_N        VIA        MD0280PA01X+081425Y+074675               S0      
327SW_SSD4_N                          A01X+081300Y+034800X0220Y0400     S0      
327SW_SSD4_N                          A01X+083550Y+034250X0650Y0250     S0      
317SW_SSD4_N                    D0220PA01X+081950Y+034130               S0      
317SW_SSD4_N                    D0220PA01X+082400Y+034130               S0      
317SW_SSD4_N                    D0240PA01X+082800Y+034120               S0      
317SW_SSD4_N        VIA        MD0280PA01X+081425Y+034125               S0      
327SW_SSD5_N                          A01X+005450Y+193950X0220Y0400     S0      
327SW_SSD5_N                          A01X+007950Y+193400X0650Y0250     S0      
317SW_SSD5_N                    D0220PA01X+006550Y+193280               S0      
317SW_SSD5_N                    D0220PA01X+006100Y+193280               S0      
317SW_SSD5_N                    D0240PA01X+006950Y+193270               S0      
317SW_SSD5_N        VIA        MD0280PA01X+005575Y+193275               S0      
327SW_SSD6_N                          A01X+008400Y+155550X0220Y0400     S0      
327SW_SSD6_N                          A01X+010670Y+155410X0650Y0250     S0      
317SW_SSD6_N                    D0220PA01X+009500Y+154880               S0      
317SW_SSD6_N                    D0220PA01X+009050Y+154880               S0      
317SW_SSD6_N                    D0240PA01X+009900Y+154870               S0      
317SW_SSD6_N        VIA        MD0280PA01X+008525Y+154875               S0      
327SW_SSD7_N                          A01X+008470Y+115940X0220Y0400     S0      
327SW_SSD7_N                          A01X+010720Y+115390X0650Y0250     S0      
317SW_SSD7_N                    D0220PA01X+009570Y+115270               S0      
317SW_SSD7_N                    D0220PA01X+009120Y+115270               S0      
317SW_SSD7_N                    D0240PA01X+009970Y+115260               S0      
317SW_SSD7_N        VIA        MD0280PA01X+008595Y+115265               S0      
327SW_SSD8_N                          A01X+008470Y+075350X0220Y0400     S0      
327SW_SSD8_N                          A01X+010720Y+074800X0650Y0250     S0      
317SW_SSD8_N                    D0220PA01X+009570Y+074680               S0      
317SW_SSD8_N                    D0220PA01X+009120Y+074680               S0      
317SW_SSD8_N                    D0240PA01X+009970Y+074670               S0      
317SW_SSD8_N        VIA        MD0280PA01X+008595Y+074675               S0      
327SW_SSD9_N                          A01X+008470Y+034800X0220Y0400     S0      
327SW_SSD9_N                          A01X+010720Y+034250X0650Y0250     S0      
317SW_SSD9_N                    D0220PA01X+009570Y+034130               S0      
317SW_SSD9_N                    D0220PA01X+009120Y+034130               S0      
317SW_SSD9_N                    D0240PA01X+009970Y+034120               S0      
317SW_SSD9_N        VIA        MD0280PA01X+008595Y+034125               S0      
327SW_SSD10_N                         A01X+016090Y+164410X0220Y0400     S0      
327SW_SSD10_N                         A01X+013840Y+164960X0650Y0250     S0      
317SW_SSD10_N                   D0220PA01X+014990Y+165080               S0      
317SW_SSD10_N                   D0220PA01X+015440Y+165080               S0      
317SW_SSD10_N                   D0240PA01X+014590Y+165090               S0      
317SW_SSD10_N       VIA        MD0280PA01X+015965Y+165085               S0      
327SW_SSD11_N                         A01X+015970Y+123860X0220Y0400     S0      
327SW_SSD11_N                         A01X+013720Y+124410X0650Y0250     S0      
317SW_SSD11_N                   D0220PA01X+014870Y+124530               S0      
317SW_SSD11_N                   D0220PA01X+015320Y+124530               S0      
317SW_SSD11_N                   D0240PA01X+014470Y+124540               S0      
317SW_SSD11_N       VIA        MD0280PA01X+015845Y+124535               S0      
327SW_SSD12_N                         A01X+015940Y+083310X0220Y0400     S0      
327SW_SSD12_N                         A01X+013690Y+083860X0650Y0250     S0      
317SW_SSD12_N                   D0220PA01X+014840Y+083980               S0      
317SW_SSD12_N                   D0220PA01X+015290Y+083980               S0      
317SW_SSD12_N                   D0240PA01X+014440Y+083990               S0      
317SW_SSD12_N       VIA        MD0280PA01X+015815Y+083985               S0      
327SW_SSD13_N                         A01X+015940Y+042760X0220Y0400     S0      
327SW_SSD13_N                         A01X+013690Y+043310X0650Y0250     S0      
317SW_SSD13_N                   D0220PA01X+014840Y+043430               S0      
317SW_SSD13_N                   D0220PA01X+015290Y+043430               S0      
317SW_SSD13_N                   D0240PA01X+014440Y+043440               S0      
317SW_SSD13_N       VIA        MD0280PA01X+015815Y+043435               S0      
327SW_SSD14_N                         A01X+020800Y+005350X0220Y0400     S0      
327SW_SSD14_N                         A01X+018550Y+005900X0650Y0250     S0      
317SW_SSD14_N                   D0220PA01X+019700Y+006020               S0      
317SW_SSD14_N                   D0220PA01X+020150Y+006020               S0      
317SW_SSD14_N                   D0240PA01X+019300Y+006030               S0      
317SW_SSD14_N       VIA        MD0280PA01X+020675Y+006025               S0      
327VDD_IO_1                           A01X+037099Y+168259X0120Y0460     S0      
327VDD_IO_1                           A01X+038477Y+168208X0120Y0360     S0      
327VDD_IO_1                           A01X+038477Y+171792X0120Y0360     S0      
327VDD_IO_1                           A01X+037099Y+171742X0120Y0460     S0      
327VDD_IO_1                           A01X+038800Y+172870X0550Y0450     S0      
317VDD_IO_1                     D0240PA01X+038620Y+172350               S0      
317VDD_IO_1                     D0240PA01X+037250Y+172770               S0      
317VDD_IO_1                     D0240PA01X+038520Y+167650               S0      
317VDD_IO_1                     D0240PA01X+037600Y+167380               S0      
317VDD_IO_1         VIA        MD0120PA00X+037950Y+167375               S0      
317VDD_IO_1         VIA        MD0100PA00X+037570Y+172775               S0      
317VDD_IO_1         VIA        MD0100PA00X+038300Y+172870               S0      
317VDD_IO_1         VIA        MD0100PA00X+038525Y+167300               S0      
327VDD_IO_2                           A01X+037099Y+118409X0120Y0460     S0      
327VDD_IO_2                           A01X+038477Y+118358X0120Y0360     S0      
327VDD_IO_2                           A01X+038477Y+121942X0120Y0360     S0      
327VDD_IO_2                           A01X+037099Y+121892X0120Y0460     S0      
327VDD_IO_2                           A01X+040070Y+123250X0450Y0550     S0      
317VDD_IO_2                     D0240PA01X+039350Y+122530               S0      
317VDD_IO_2                     D0240PA01X+037200Y+122970               S0      
317VDD_IO_2                     D0240PA01X+039350Y+117770               S0      
317VDD_IO_2                     D0240PA01X+037100Y+117480               S0      
317VDD_IO_2         VIA        MD0120PA00X+039664Y+117600               S0      
317VDD_IO_2         VIA        MD0100PA00X+037420Y+117475               S0      
317VDD_IO_2         VIA        MD0100PA00X+037520Y+122975               S0      
317VDD_IO_2         VIA        MD0100PA00X+040070Y+123750               S0      
327VDD_IO_3                           A01X+037099Y+081259X0120Y0460     S0      
327VDD_IO_3                           A01X+038477Y+081208X0120Y0360     S0      
327VDD_IO_3                           A01X+038477Y+084792X0120Y0360     S0      
327VDD_IO_3                           A01X+037099Y+084742X0120Y0460     S0      
327VDD_IO_3                           A01X+039870Y+085050X0450Y0550     S0      
317VDD_IO_3                     D0240PA01X+036550Y+080380               S0      
317VDD_IO_3                     D0240PA01X+038820Y+080650               S0      
317VDD_IO_3                     D0240PA01X+039350Y+084830               S0      
317VDD_IO_3                     D0240PA01X+037200Y+085820               S0      
317VDD_IO_3         VIA        MD0120PA00X+039350Y+085200               S0      
317VDD_IO_3         VIA        MD0100PA00X+036870Y+080375               S0      
317VDD_IO_3         VIA        MD0100PA00X+037520Y+085825               S0      
317VDD_IO_3         VIA        MD0100PA00X+038825Y+080330               S0      
327VDD_IO_4                           A01X+037099Y+038259X0120Y0460     S0      
327VDD_IO_4                           A01X+038477Y+038208X0120Y0360     S0      
327VDD_IO_4                           A01X+038477Y+041792X0120Y0360     S0      
327VDD_IO_4                           A01X+037099Y+041742X0120Y0460     S0      
327VDD_IO_4                           A01X+039870Y+042050X0450Y0550     S0      
317VDD_IO_4                     D0240PA01X+037200Y+037130               S0      
317VDD_IO_4                     D0240PA01X+039350Y+038020               S0      
317VDD_IO_4                     D0240PA01X+039350Y+041830               S0      
317VDD_IO_4                     D0240PA01X+037200Y+042920               S0      
317VDD_IO_4         VIA        MD0120PA00X+039350Y+042200               S0      
317VDD_IO_4         VIA        MD0100PA00X+037520Y+037125               S0      
317VDD_IO_4         VIA        MD0100PA00X+037520Y+042925               S0      
317VDD_IO_4         VIA        MD0100PA00X+039700Y+038025               S0      
327VDDA_1                             A01X+035208Y+171477X0360Y0120     S0      
317VDDA_1                       D0220PA01X+032820Y+172500               S0      
317VDDA_1                       D0240PA01X+034650Y+172030               S0      
317VDDA_1                       D0240PA01X+034300Y+172030               S0      
317VDDA_1           VIA        MD0280PA01X+034050Y+172500               S0      
327VDDR_1                             A01X+035259Y+170099X0460Y0120     S0      
317VDDR_1                       D0220PA01X+032820Y+170430               S0      
317VDDR_1                       D0240PA01X+034450Y+170270               S0      
317VDDR_1                       D0240PA01X+034100Y+170270               S0      
317VDDR_1           VIA        MD0280PA01X+033360Y+170350               S0      
317VDD_DIFF_1                   D0340PA01X+031480Y+171570               S0      
327VDD_DIFF_1                         A01X+031530Y+172210X0450Y0550     S0      
327VDD_DIFF_1                         A01X+036902Y+168259X0120Y0460     S0      
327VDD_DIFF_1                         A01X+038742Y+169902X0460Y0120     S0      
327VDD_DIFF_1                         A01X+036902Y+171742X0120Y0460     S0      
317VDD_DIFF_1                   D0220PA01X+031030Y+169255               S0      
317VDD_DIFF_1                   D0220PA01X+031030Y+170345               S0      
317VDD_DIFF_1                   D0220PA01X+032480Y+172500               S0      
317VDD_DIFF_1                   D0220PA01X+032480Y+170430               S0      
317VDD_DIFF_1                   D0220PA01X+032480Y+171700               S0      
317VDD_DIFF_1                   D0220PA01X+032480Y+170850               S0      
317VDD_DIFF_1                   D0220PA01X+032480Y+172100               S0      
317VDD_DIFF_1                   D0220PA01X+033480Y+169100               S0      
317VDD_DIFF_1                   D0220PA01X+033080Y+167700               S0      
317VDD_DIFF_1                   D0240PA01X+037250Y+167380               S0      
317VDD_DIFF_1                   D0240PA01X+039570Y+169720               S0      
317VDD_DIFF_1                   D0240PA01X+036900Y+172770               S0      
317VDD_DIFF_1       VIA        MD0280PA01X+031520Y+170490               S0      
317VDD_DIFF_1       VIA        MD0120PA00X+040200Y+169500               S0      
317VDD_DIFF_1       VIA        MD0100PA00X+031320Y+172730               S0      
317VDD_DIFF_1       VIA        MD0100PA00X+031350Y+169250               S0      
317VDD_DIFF_1       VIA        MD0100PA00X+031500Y+171200               S0      
317VDD_DIFF_1       VIA        MD0100PA00X+031700Y+172730               S0      
317VDD_DIFF_1       VIA        MD0100PA00X+032140Y+170440               S0      
317VDD_DIFF_1       VIA        MD0100PA00X+032150Y+170850               S0      
317VDD_DIFF_1       VIA        MD0100PA00X+032150Y+171700               S0      
317VDD_DIFF_1       VIA        MD0100PA00X+032150Y+172100               S0      
317VDD_DIFF_1       VIA        MD0100PA00X+032150Y+172520               S0      
317VDD_DIFF_1       VIA        MD0100PA00X+032750Y+167700               S0      
317VDD_DIFF_1       VIA        MD0100PA00X+033150Y+169100               S0      
317VDD_DIFF_1       VIA        MD0100PA00X+036570Y+172770               S0      
317VDD_DIFF_1       VIA        MD0100PA00X+036910Y+167370               S0      
327VDDA_2                             A01X+035208Y+121627X0360Y0120     S0      
317VDDA_2                       D0220PA01X+032820Y+122650               S0      
317VDDA_2                       D0240PA01X+034650Y+122180               S0      
317VDDA_2                       D0240PA01X+034300Y+122180               S0      
317VDDA_2           VIA        MD0280PA01X+034050Y+122650               S0      
327VDDR_2                             A01X+035259Y+120248X0460Y0120     S0      
317VDDR_2                       D0220PA01X+032820Y+120580               S0      
317VDDR_2                       D0240PA01X+034450Y+120420               S0      
317VDDR_2                       D0240PA01X+034100Y+120420               S0      
317VDDR_2           VIA        MD0280PA01X+033450Y+120425               S0      
327VDDA_3                             A01X+035208Y+084477X0360Y0120     S0      
317VDDA_3                       D0220PA01X+032820Y+085500               S0      
317VDDA_3                       D0240PA01X+034650Y+085030               S0      
317VDDA_3                       D0240PA01X+034300Y+085030               S0      
317VDDA_3           VIA        MD0280PA01X+034050Y+085500               S0      
317VDD_DIFF_2                   D0340PA01X+031380Y+121750               S0      
327VDD_DIFF_2                         A01X+031480Y+122400X0450Y0550     S0      
327VDD_DIFF_2                         A01X+036902Y+118409X0120Y0460     S0      
327VDD_DIFF_2                         A01X+038742Y+120051X0460Y0120     S0      
327VDD_DIFF_2                         A01X+036902Y+121892X0120Y0460     S0      
317VDD_DIFF_2                   D0220PA01X+030930Y+119405               S0      
317VDD_DIFF_2                   D0220PA01X+030930Y+120495               S0      
317VDD_DIFF_2                   D0220PA01X+032480Y+122650               S0      
317VDD_DIFF_2                   D0220PA01X+032480Y+120580               S0      
317VDD_DIFF_2                   D0220PA01X+032480Y+121850               S0      
317VDD_DIFF_2                   D0220PA01X+032480Y+121000               S0      
317VDD_DIFF_2                   D0220PA01X+032480Y+122250               S0      
317VDD_DIFF_2                   D0220PA01X+033080Y+117850               S0      
317VDD_DIFF_2                   D0220PA01X+033480Y+119050               S0      
317VDD_DIFF_2                   D0240PA01X+039560Y+119870               S0      
317VDD_DIFF_2                   D0240PA01X+036850Y+122970               S0      
317VDD_DIFF_2                   D0240PA01X+036750Y+117480               S0      
317VDD_DIFF_2       VIA        MD0280PA01X+031460Y+120480               S0      
317VDD_DIFF_2       VIA        MD0120PA00X+040200Y+119650               S0      
317VDD_DIFF_2       VIA        MD0100PA00X+031250Y+119400               S0      
317VDD_DIFF_2       VIA        MD0100PA00X+031320Y+122880               S0      
317VDD_DIFF_2       VIA        MD0100PA00X+031444Y+121338               S0      
317VDD_DIFF_2       VIA        MD0100PA00X+031700Y+122880               S0      
317VDD_DIFF_2       VIA        MD0100PA00X+032140Y+120590               S0      
317VDD_DIFF_2       VIA        MD0100PA00X+032150Y+121000               S0      
317VDD_DIFF_2       VIA        MD0100PA00X+032150Y+121850               S0      
317VDD_DIFF_2       VIA        MD0100PA00X+032150Y+122250               S0      
317VDD_DIFF_2       VIA        MD0100PA00X+032160Y+122660               S0      
317VDD_DIFF_2       VIA        MD0100PA00X+032750Y+117850               S0      
317VDD_DIFF_2       VIA        MD0100PA00X+033150Y+119050               S0      
317VDD_DIFF_2       VIA        MD0100PA00X+036430Y+117490               S0      
317VDD_DIFF_2       VIA        MD0100PA00X+036520Y+122980               S0      
327VDDR_3                             A01X+035259Y+083099X0460Y0120     S0      
317VDDR_3                       D0220PA01X+032820Y+083440               S0      
317VDDR_3                       D0240PA01X+034450Y+083270               S0      
317VDDR_3                       D0240PA01X+034100Y+083270               S0      
317VDDR_3           VIA        MD0280PA01X+033380Y+083300               S0      
317VDD_DIFF_3                   D0340PA01X+031370Y+084670               S0      
327VDD_DIFF_3                         A01X+031550Y+085310X0450Y0550     S0      
327VDD_DIFF_3                         A01X+036902Y+081259X0120Y0460     S0      
327VDD_DIFF_3                         A01X+038742Y+082902X0460Y0120     S0      
327VDD_DIFF_3                         A01X+036902Y+084742X0120Y0460     S0      
317VDD_DIFF_3                   D0220PA01X+030860Y+082260               S0      
317VDD_DIFF_3                   D0220PA01X+030860Y+083350               S0      
317VDD_DIFF_3                   D0220PA01X+032480Y+085500               S0      
317VDD_DIFF_3                   D0220PA01X+032480Y+083440               S0      
317VDD_DIFF_3                   D0220PA01X+032480Y+084700               S0      
317VDD_DIFF_3                   D0220PA01X+032480Y+083850               S0      
317VDD_DIFF_3                   D0220PA01X+032480Y+085100               S0      
317VDD_DIFF_3                   D0220PA01X+033480Y+081900               S0      
317VDD_DIFF_3                   D0220PA01X+033080Y+080700               S0      
317VDD_DIFF_3                   D0240PA01X+039350Y+082970               S0      
317VDD_DIFF_3                   D0240PA01X+036200Y+080380               S0      
317VDD_DIFF_3                   D0240PA01X+036850Y+085820               S0      
317VDD_DIFF_3       VIA        MD0280PA01X+031400Y+083400               S0      
317VDD_DIFF_3       VIA        MD0120PA00X+040150Y+083000               S0      
317VDD_DIFF_3       VIA        MD0100PA00X+031200Y+082450               S0      
317VDD_DIFF_3       VIA        MD0100PA00X+031320Y+085790               S0      
317VDD_DIFF_3       VIA        MD0100PA00X+031500Y+084200               S0      
317VDD_DIFF_3       VIA        MD0100PA00X+031700Y+085790               S0      
317VDD_DIFF_3       VIA        MD0100PA00X+032140Y+083440               S0      
317VDD_DIFF_3       VIA        MD0100PA00X+032150Y+083850               S0      
317VDD_DIFF_3       VIA        MD0100PA00X+032150Y+084700               S0      
317VDD_DIFF_3       VIA        MD0100PA00X+032150Y+085100               S0      
317VDD_DIFF_3       VIA        MD0100PA00X+032150Y+085520               S0      
317VDD_DIFF_3       VIA        MD0100PA00X+032750Y+080700               S0      
317VDD_DIFF_3       VIA        MD0100PA00X+033150Y+081900               S0      
317VDD_DIFF_3       VIA        MD0100PA00X+035880Y+080360               S0      
317VDD_DIFF_3       VIA        MD0100PA00X+036080Y+085850               S0      
327VDDA_4                             A01X+035208Y+041477X0360Y0120     S0      
317VDDA_4                       D0220PA01X+032820Y+042500               S0      
317VDDA_4                       D0240PA01X+034650Y+042030               S0      
317VDDA_4                       D0240PA01X+034300Y+042030               S0      
317VDDA_4           VIA        MD0280PA01X+034050Y+042500               S0      
327VDDR_4                             A01X+035259Y+040099X0460Y0120     S0      
317VDDR_4                       D0220PA01X+032820Y+040440               S0      
317VDDR_4                       D0240PA01X+034450Y+040270               S0      
317VDDR_4                       D0240PA01X+034100Y+040270               S0      
317VDDR_4           VIA        MD0280PA01X+033330Y+040340               S0      
317VDD_DIFF_4                   D0340PA01X+031370Y+041620               S0      
327VDD_DIFF_4                         A01X+031520Y+042260X0450Y0550     S0      
327VDD_DIFF_4                         A01X+036902Y+038259X0120Y0460     S0      
327VDD_DIFF_4                         A01X+038742Y+039902X0460Y0120     S0      
327VDD_DIFF_4                         A01X+036902Y+041742X0120Y0460     S0      
317VDD_DIFF_4                   D0220PA01X+030930Y+039310               S0      
317VDD_DIFF_4                   D0220PA01X+030930Y+040400               S0      
317VDD_DIFF_4                   D0220PA01X+032480Y+042500               S0      
317VDD_DIFF_4                   D0220PA01X+032480Y+040440               S0      
317VDD_DIFF_4                   D0220PA01X+032480Y+040850               S0      
317VDD_DIFF_4                   D0220PA01X+032480Y+041700               S0      
317VDD_DIFF_4                   D0220PA01X+032480Y+042100               S0      
317VDD_DIFF_4                   D0220PA01X+033480Y+038900               S0      
317VDD_DIFF_4                   D0220PA01X+033080Y+037700               S0      
317VDD_DIFF_4                   D0240PA01X+036850Y+037130               S0      
317VDD_DIFF_4                   D0240PA01X+036850Y+042920               S0      
317VDD_DIFF_4                   D0240PA01X+039560Y+039810               S0      
317VDD_DIFF_4       VIA        MD0280PA01X+031510Y+040340               S0      
317VDD_DIFF_4       VIA        MD0120PA00X+040150Y+039550               S0      
317VDD_DIFF_4       VIA        MD0100PA00X+031250Y+039305               S0      
317VDD_DIFF_4       VIA        MD0100PA00X+031320Y+042750               S0      
317VDD_DIFF_4       VIA        MD0100PA00X+031500Y+041200               S0      
317VDD_DIFF_4       VIA        MD0100PA00X+031700Y+042750               S0      
317VDD_DIFF_4       VIA        MD0100PA00X+032140Y+040440               S0      
317VDD_DIFF_4       VIA        MD0100PA00X+032150Y+040850               S0      
317VDD_DIFF_4       VIA        MD0100PA00X+032150Y+041700               S0      
317VDD_DIFF_4       VIA        MD0100PA00X+032150Y+042100               S0      
317VDD_DIFF_4       VIA        MD0100PA00X+032150Y+042520               S0      
317VDD_DIFF_4       VIA        MD0100PA00X+032750Y+037700               S0      
317VDD_DIFF_4       VIA        MD0100PA00X+033150Y+038900               S0      
317VDD_DIFF_4       VIA        MD0100PA00X+036476Y+042925               S0      
317VDD_DIFF_4       VIA        MD0100PA00X+036510Y+037120               S0      
327SSD_PRSNT9                         A01X+035918Y+038259X0120Y0460     S0      
317SSD_PRSNT9                   D0220PA01X+034500Y+034870               S0      
317SSD_PRSNT9                   D0240PA01X+034470Y+035250               S0      
317SSD_PRSNT9       VIA        MD0280PA01X+034600Y+035750               S0      
327NNAME00003                         A01X+000886Y+065804X0980Y0200     S0      
327NNAME00003                         A01X+036114Y+038259X0120Y0460     S0      
317NNAME00003                   D0220PA01X+035300Y+034870               S0      
317NNAME00003                   D0300PA01X+015487Y+015625               S0      
317NNAME00003                   D0240PA01X+035270Y+035250               S0      
317NNAME00003       VIA        MD0280PA01X+011144Y+026016               S0      
317NNAME00003       VIA        MD0100PA00X+012900Y+025550               S0      
317NNAME00003       VIA        MD0100PA00X+015487Y+016050               S0      
317NNAME00003       VIA        MD0100PA00X+034987Y+034887               S0      
327SSD_PRSNT4                         A01X+037689Y+081259X0120Y0460     S0      
317SSD_PRSNT4                   D0220PA01X+037400Y+077870               S0      
317SSD_PRSNT4                   D0240PA01X+037370Y+078250               S0      
317SSD_PRSNT4       VIA        MD0280PA01X+037510Y+078770               S0      
327SSD_PRSNT5                         A01X+036114Y+171742X0120Y0460     S0      
317SSD_PRSNT5                   D0220PA01X+035500Y+175130               S0      
317SSD_PRSNT5                   D0240PA01X+035530Y+174750               S0      
317SSD_PRSNT5       VIA        MD0280PA01X+035400Y+174250               S0      
327SSD_PRSNT13                        A01X+036114Y+041742X0120Y0460     S0      
317SSD_PRSNT13                  D0220PA01X+035500Y+045130               S0      
317SSD_PRSNT13                  D0240PA01X+035530Y+044750               S0      
317SSD_PRSNT13      VIA        MD0280PA01X+035400Y+044250               S0      
327SSD_PRSNT8                         A01X+037886Y+041742X0120Y0460     S0      
317SSD_PRSNT8                   D0220PA01X+039050Y+045130               S0      
317SSD_PRSNT8                   D0240PA01X+039080Y+044750               S0      
317SSD_PRSNT8       VIA        MD0280PA01X+038950Y+044250               S0      
327SSD_PRSNT11                        A01X+036114Y+121892X0120Y0460     S0      
317SSD_PRSNT11                  D0220PA01X+035500Y+125280               S0      
317SSD_PRSNT11                  D0240PA01X+035530Y+124900               S0      
317SSD_PRSNT11      VIA        MD0280PA01X+035400Y+124400               S0      
327SSD_PRSNT3                         A01X+038742Y+082114X0460Y0120     S0      
317SSD_PRSNT3                   D0220PA01X+042130Y+080950               S0      
317SSD_PRSNT3                   D0240PA01X+041750Y+080920               S0      
317SSD_PRSNT3       VIA        MD0280PA01X+041250Y+081050               S0      
327SSD_PRSNT1                         A01X+038742Y+120839X0460Y0120     S0      
317SSD_PRSNT1                   D0220PA01X+042130Y+121200               S0      
317SSD_PRSNT1                   D0240PA01X+041750Y+121170               S0      
317SSD_PRSNT1       VIA        MD0280PA01X+041250Y+121300               S0      
327SSD_PRSNT14                        A01X+037689Y+038259X0120Y0460     S0      
317SSD_PRSNT14                  D0220PA01X+038050Y+034870               S0      
317SSD_PRSNT14                  D0240PA01X+038020Y+035250               S0      
317SSD_PRSNT14      VIA        MD0280PA01X+038150Y+035750               S0      
327SSD_PRSNT7                         A01X+037886Y+084742X0120Y0460     S0      
317SSD_PRSNT7                   D0220PA01X+039050Y+088130               S0      
317SSD_PRSNT7                   D0240PA01X+039080Y+087750               S0      
317SSD_PRSNT7       VIA        MD0280PA01X+038950Y+087250               S0      
327SSD_PRSNT6                         A01X+037886Y+121892X0120Y0460     S0      
317SSD_PRSNT6                   D0220PA01X+039050Y+125280               S0      
317SSD_PRSNT6                   D0240PA01X+039080Y+124900               S0      
317SSD_PRSNT6       VIA        MD0280PA01X+038950Y+124400               S0      
327SSD_PRSNT12                        A01X+036114Y+084742X0120Y0460     S0      
317SSD_PRSNT12                  D0220PA01X+035500Y+088130               S0      
317SSD_PRSNT12                  D0240PA01X+035530Y+087750               S0      
317SSD_PRSNT12      VIA        MD0280PA01X+035400Y+087250               S0      
327NNAME00004                         A01X+000886Y+112891X0980Y0200     S0      
327NNAME00004                         A01X+038742Y+082311X0460Y0120     S0      
317NNAME00004                   D0220PA01X+042130Y+081750               S0      
317NNAME00004                   D0300PA01X+086512Y+053972               S0      
317NNAME00004                   D0240PA01X+041750Y+081720               S0      
317NNAME00004       VIA        MD0280PA08X+014125Y+097805               S0      
317NNAME00004       VIA        MD0100PA00X+016170Y+095080               S0      
317NNAME00004       VIA        MD0100PA00X+003397Y+113174               S0      
317NNAME00004       VIA        MD0100PA00X+042072Y+082063               S0      
317NNAME00004       VIA        MD0100PA00X+086512Y+054400               S0      
327NNAME00005                         A01X+000886Y+157143X0980Y0200     S0      
327NNAME00005                         A01X+038742Y+121036X0460Y0120     S0      
317NNAME00005                   D0220PA01X+042130Y+122000               S0      
317NNAME00005                   D0300PA01X+086512Y+135074               S0      
317NNAME00005                   D0240PA01X+041750Y+121970               S0      
317NNAME00005       VIA        MD0280PA01X+003980Y+154740               S0      
317NNAME00005       VIA        MD0100PA00X+042076Y+122319               S0      
317NNAME00005       VIA        MD0100PA00X+004296Y+151741               S0      
317NNAME00005       VIA        MD0100PA00X+086512Y+134649               S0      
327NNAME00006                         A08X+000886Y+077458X0980Y0200     S0      
327NNAME00006                         A01X+037886Y+081259X0120Y0460     S0      
317NNAME00006                   D0220PA01X+038200Y+077870               S0      
317NNAME00006                   D0300PA01X+086925Y+014888               S0      
317NNAME00006                   D0240PA01X+038170Y+078250               S0      
317NNAME00006       VIA        MD0280PA01X+037960Y+079530               S0      
317NNAME00006       VIA        MD0100PA00X+038520Y+077911               S0      
317NNAME00006       VIA        MD0100PA00X+086498Y+014888               S0      
327NNAME00007                         A08X+000886Y+170056X0980Y0200     S0      
327NNAME00007                         A01X+035918Y+171742X0120Y0460     S0      
317NNAME00007                   D0220PA01X+034700Y+175130               S0      
317NNAME00007                   D0300PA01X+022487Y+176375               S0      
317NNAME00007                   D0240PA01X+034730Y+174750               S0      
317NNAME00007       VIA        MD0280PA08X+008360Y+173660               S0      
317NNAME00007       VIA        MD0100PA00X+014720Y+172440               S0      
317NNAME00007       VIA        MD0100PA00X+022487Y+176810               S0      
317NNAME00007       VIA        MD0100PA00X+034367Y+175074               S0      
327NNAME00008                         A01X+000886Y+141237X0980Y0200     S0      
327NNAME00008                         A01X+037689Y+121892X0120Y0460     S0      
317NNAME00008                   D0220PA01X+038250Y+125280               S0      
317NNAME00008                   D0300PA01X+015888Y+137179               S0      
317NNAME00008                   D0240PA01X+038280Y+124900               S0      
317NNAME00008       VIA        MD0280PA08X+009464Y+145610               S0      
317NNAME00008       VIA        MD0100PA00X+015888Y+137610               S0      
317NNAME00008       VIA        MD0100PA00X+003250Y+141760               S0      
317NNAME00008       VIA        MD0100PA00X+037940Y+125227               S0      
327NNAME00009                         A01X+000886Y+124859X0980Y0200     S0      
327NNAME00009                         A01X+037689Y+084742X0120Y0460     S0      
317NNAME00009                   D0220PA01X+038250Y+088130               S0      
317NNAME00009                   D0300PA01X+020888Y+095273               S0      
317NNAME00009                   D0240PA01X+038280Y+087750               S0      
317NNAME00009       VIA        MD0280PA08X+011270Y+107960               S0      
317NNAME00009       VIA        MD0100PA00X+013930Y+106700               S0      
317NNAME00009       VIA        MD0100PA00X+019600Y+107030               S0      
317NNAME00009       VIA        MD0100PA00X+020888Y+095720               S0      
317NNAME00009       VIA        MD0100PA00X+003600Y+123600               S0      
317NNAME00009       VIA        MD0100PA00X+037937Y+088073               S0      
327NNAME00010                         A08X+000886Y+088481X0980Y0200     S0      
327NNAME00010                         A01X+037689Y+041742X0120Y0460     S0      
317NNAME00010                   D0220PA01X+038250Y+045130               S0      
317NNAME00010                   D0300PA01X+014388Y+056375               S0      
317NNAME00010                   D0240PA01X+038280Y+044750               S0      
317NNAME00010       VIA        MD0280PA08X+004009Y+078840               S0      
317NNAME00010       VIA        MD0100PA00X+015085Y+057435               S0      
317NNAME00010       VIA        MD0100PA00X+038561Y+045123               S0      
327NNAME00011                         A08X+000886Y+131473X0980Y0200     S0      
327NNAME00011                         A01X+035918Y+121892X0120Y0460     S0      
317NNAME00011                   D0220PA01X+034700Y+125280               S0      
317NNAME00011                   D0300PA01X+010175Y+143663               S0      
317NNAME00011                   D0240PA01X+034730Y+124900               S0      
317NNAME00011       VIA        MD0280PA08X+005010Y+131740               S0      
317NNAME00011       VIA        MD0100PA00X+034382Y+125222               S0      
317NNAME00011       VIA        MD0100PA00X+005890Y+131700               S0      
327NNAME00012                         A08X+000886Y+113521X0980Y0200     S0      
327NNAME00012                         A01X+035918Y+084742X0120Y0460     S0      
317NNAME00012                   D0220PA01X+034700Y+088130               S0      
317NNAME00012                   D0300PA01X+010175Y+103111               S0      
317NNAME00012                   D0240PA01X+034730Y+087750               S0      
317NNAME00012       VIA        MD0280PA08X+014207Y+095823               S0      
317NNAME00012       VIA        MD0100PA00X+010610Y+103000               S0      
317NNAME00012       VIA        MD0100PA00X+016120Y+094610               S0      
317NNAME00012       VIA        MD0100PA00X+034389Y+088071               S0      
327NNAME00013                         A01X+000886Y+078717X0980Y0200     S0      
327NNAME00013                         A01X+035918Y+041742X0120Y0460     S0      
317NNAME00013                   D0220PA01X+034700Y+045130               S0      
317NNAME00013                   D0300PA01X+010175Y+062560               S0      
317NNAME00013                   D0240PA01X+034730Y+044750               S0      
317NNAME00013       VIA        MD0280PA01X+029196Y+050502               S0      
317NNAME00013       VIA        MD0100PA00X+029730Y+050502               S0      
317NNAME00013       VIA        MD0100PA00X+035014Y+045125               S0      
317NNAME00013       VIA        MD0100PA00X+005056Y+065350               S0      
317NNAME00013       VIA        MD0100PA00X+008860Y+062330               S0      
327NNAME00014                         A01X+000886Y+064859X0980Y0200     S0      
327NNAME00014                         A01X+037886Y+038259X0120Y0460     S0      
317NNAME00014                   D0220PA01X+038850Y+034870               S0      
317NNAME00014                   D0300PA01X+010175Y+022009               S0      
317NNAME00014                   D0240PA01X+038820Y+035250               S0      
317NNAME00014       VIA        MD0280PA08X+010575Y+021775               S0      
317NNAME00014       VIA        MD0100PA00X+029260Y+016696               S0      
317NNAME00014       VIA        MD0100PA00X+005602Y+029255               S0      
317NNAME00014       VIA        MD0100PA00X+009740Y+022020               S0      
327SSD_PRSNT2                         A01X+037689Y+118409X0120Y0460     S0      
317SSD_PRSNT2                   D0220PA01X+038050Y+115020               S0      
317SSD_PRSNT2                   D0240PA01X+038020Y+115400               S0      
317SSD_PRSNT2       VIA        MD0280PA01X+038150Y+115900               S0      
327NNAME00015                         A01X+000886Y+130843X0980Y0200     S0      
327NNAME00015                         A01X+037886Y+118409X0120Y0460     S0      
317NNAME00015                   D0220PA01X+038850Y+115020               S0      
317NNAME00015                   D0300PA01X+086512Y+094523               S0      
317NNAME00015                   D0240PA01X+038820Y+115400               S0      
317NNAME00015       VIA        MD0280PA01X+038590Y+116610               S0      
317NNAME00015       VIA        MD0100PA00X+003070Y+130860               S0      
317NNAME00015       VIA        MD0100PA00X+039190Y+115025               S0      
317NNAME00015       VIA        MD0100PA00X+086512Y+094960               S0      
317PE_100M_CLK1_N               D0120PA01X+033780Y+039750               S0      
327PE_100M_CLK1_N                     A01X+035259Y+039704X0460Y0120     S0      
317PE_100M_CLK1_N               D0220PA01X+030930Y+039650               S0      
317PE_100M_CLK1_N               D0220PA01X+030510Y+039650               S0      
317PE_100M_CLK1_N               D0240PA01X+002660Y+148830               S0      
327NNAME00016                         A01X+000886Y+151473X0980Y0200     S0      
317NNAME00016                   D0240PA01X+002660Y+149190               S0      
317PE_100M_CLK1_P               D0120PA01X+033780Y+039970               S0      
327PE_100M_CLK1_P                     A01X+035259Y+039902X0460Y0120     S0      
317PE_100M_CLK1_P               D0220PA01X+030930Y+040060               S0      
317PE_100M_CLK1_P               D0220PA01X+030510Y+040060               S0      
317PE_100M_CLK1_P               D0240PA01X+003020Y+148830               S0      
327NNAME00017                         A01X+000886Y+151788X0980Y0200     S0      
317NNAME00017                   D0240PA01X+003020Y+149190               S0      
317PE_100M_CLK2_P               D0120PA01X+033680Y+082915               S0      
327PE_100M_CLK2_P                     A01X+035259Y+082902X0460Y0120     S0      
317PE_100M_CLK2_P               D0220PA01X+030860Y+083010               S0      
317PE_100M_CLK2_P               D0220PA01X+030450Y+083010               S0      
317PE_100M_CLK2_P               D0240PA01X+003635Y+151040               S0      
327NNAME00018                         A08X+000886Y+151473X0980Y0200     S0      
317NNAME00018                   D0240PA01X+003635Y+151400               S0      
317NNAME00018       VIA        MD0100PA00X+003620Y+151812               S0      
317PE_100M_CLK2_N               D0120PA01X+033680Y+082695               S0      
327PE_100M_CLK2_N                     A01X+035259Y+082705X0460Y0120     S0      
317PE_100M_CLK2_N               D0220PA01X+030860Y+082600               S0      
317PE_100M_CLK2_N               D0220PA01X+030450Y+082600               S0      
317PE_100M_CLK2_N               D0240PA01X+003285Y+151040               S0      
327NNAME00019                         A08X+000886Y+151788X0980Y0200     S0      
317NNAME00019                   D0240PA01X+003285Y+151400               S0      
317NNAME00019       VIA        MD0100PA00X+003300Y+151812               S0      
317PE_100M_CLK3_P               D0120PA01X+033750Y+120065               S0      
327PE_100M_CLK3_P                     A01X+035259Y+120051X0460Y0120     S0      
317PE_100M_CLK3_P               D0220PA01X+030930Y+120155               S0      
317PE_100M_CLK3_P               D0220PA01X+030520Y+120155               S0      
317PE_100M_CLK3_P               D0240PA01X+005837Y+167475               S0      
327NNAME00020                         A08X+000886Y+176040X0980Y0200     S0      
317NNAME00020                   D0240PA01X+005837Y+167835               S0      
317NNAME00020       VIA        MD0100PA00X+002870Y+176956               S0      
317PE_100M_CLK3_N               D0120PA01X+033750Y+119845               S0      
327PE_100M_CLK3_N                     A01X+035259Y+119855X0460Y0120     S0      
317PE_100M_CLK3_N               D0220PA01X+030930Y+119745               S0      
317PE_100M_CLK3_N               D0220PA01X+030520Y+119745               S0      
317PE_100M_CLK3_N               D0240PA01X+005487Y+167475               S0      
327NNAME00021                         A08X+000886Y+176355X0980Y0200     S0      
317NNAME00021                   D0240PA01X+005487Y+167835               S0      
317NNAME00021       VIA        MD0100PA00X+002550Y+176956               S0      
317PE_100M_CLK4_P               D0120PA01X+032860Y+169915               S0      
327PE_100M_CLK4_P                     A01X+035259Y+169902X0460Y0120     S0      
317PE_100M_CLK4_P               D0220PA01X+031030Y+170005               S0      
317PE_100M_CLK4_P               D0220PA01X+030620Y+170005               S0      
317PE_100M_CLK4_P               D0240PA01X+003300Y+177535               S0      
317PE_100M_CLK4_P   VIA        MD0100PA00X+028500Y+169740               S0      
317PE_100M_CLK4_P   VIA        MD0100PA00X+029240Y+169340               S0      
327NNAME00022                         A01X+000886Y+176670X0980Y0200     S0      
317NNAME00022                   D0240PA01X+002940Y+177535               S0      
317PE_100M_CLK4_N               D0120PA01X+032860Y+169695               S0      
327PE_100M_CLK4_N                     A01X+035259Y+169705X0460Y0120     S0      
317PE_100M_CLK4_N               D0220PA01X+031030Y+169595               S0      
317PE_100M_CLK4_N               D0220PA01X+030620Y+169595               S0      
317PE_100M_CLK4_N               D0240PA01X+003300Y+177885               S0      
317PE_100M_CLK4_N   VIA        MD0100PA00X+028500Y+170060               S0      
317PE_100M_CLK4_N   VIA        MD0100PA00X+029560Y+169340               S0      
327NNAME00023                         A01X+000886Y+176985X0980Y0200     S0      
317NNAME00023                   D0240PA01X+002940Y+177885               S0      
327NNAME00024                         A08X+000886Y+179820X0980Y0200     S0      
327NNAME00024                         A08X+100974Y+163610X2300Y0320     S0      
317NNAME00024       VIA        MD0280PA08X+006358Y+189488               S0      
317N70914768                    D0280PA01X+096900Y+164150               S0      
327N70914768                          A08X+100974Y+164110X2300Y0320     S0      
317N70914768        VIA        MD0100PA00X+097300Y+164150               S0      
317NNAME00025                   D0220PA01X+004800Y+188420               S0      
327NNAME00025                         A08X+100974Y+164610X2300Y0320     S0      
317NNAME00025       VIA        MD0280PA08X+007065Y+189779               S0      
317NNAME00025       VIA        MD0100PA00X+004687Y+188777               S0      
327PWM_EXP_A                          A01X+000886Y+166276X0980Y0200     S0      
327PWM_EXP_A                          A08X+100974Y+165110X2300Y0320     S0      
317PWM_EXP_A        VIA        MD0280PA01X+004725Y+158796               S0      
317PWM_EXP_A        VIA        MD0100PA00X+004689Y+151998               S0      
317PWM_EXP_A        VIA        MD0100PA00X+094100Y+165300               S0      
327SELF_1A&2A_HB                      A08X+000886Y+178560X0980Y0200     S0      
327SELF_1A&2A_HB                      A01X+100974Y+167110X2300Y0320     S0      
317SELF_1A&2A_HB    VIA        MD0280PA08X+093950Y+169800               S0      
317SELF_1A&2A_HB    VIA        MD0100PA00X+093483Y+168229               S0      
317N70930468                    D0280PA01X+096950Y+167650               S0      
327N70930468                          A01X+100974Y+166610X2300Y0320     S0      
317TRAY_ID                      D0220PA01X+004500Y+106420               S0      
327TRAY_ID                            A01X+100974Y+166110X2300Y0320     S0      
317TRAY_ID          VIA        MD0280PA01X+004500Y+107650               S0      
317TRAY_ID          VIA        MD0100PA00X+003850Y+131100               S0      
317TRAY_ID          VIA        MD0100PA00X+094700Y+165450               S0      
327NNAME00026                         A08X+000886Y+178875X0980Y0200     S0      
327NNAME00026                         A01X+100974Y+165610X2300Y0320     S0      
317NNAME00026       VIA        MD0280PA08X+093100Y+167150               S0      
317NNAME00026       VIA        MD0100PA00X+093100Y+165900               S0      
317NNAME00027                   D0220PA01X+004100Y+106420               S0      
327NNAME00027                         A01X+100974Y+165110X2300Y0320     S0      
317NNAME00027       VIA        MD0280PA01X+004100Y+107000               S0      
317NNAME00027       VIA        MD0100PA00X+003617Y+130843               S0      
317NNAME00027       VIA        MD0100PA00X+094350Y+164699               S0      
327PEER_1A&2A_HB                      A08X+000886Y+178245X0980Y0200     S0      
327PEER_1A&2A_HB                      A01X+100974Y+164110X2300Y0320     S0      
317PEER_1A&2A_HB    VIA        MD0280PA08X+093000Y+168500               S0      
317PEER_1A&2A_HB    VIA        MD0100PA00X+092650Y+166000               S0      
317N70929042                    D0280PA01X+097600Y+163600               S0      
327N70929042                          A01X+100974Y+163610X2300Y0320     S0      
327SW_SSD0_R                          A01X+077784Y+194751X0220Y0400     S0      
317SW_SSD0_R                    D0220PA01X+078434Y+193521               S0      
317SW_SSD0_R                    D0220PA01X+078914Y+193951               S0      
317SW_SSD0_R                    D0300PA01X+078884Y+194576               S0      
317SW_SSD0_R        VIA        MD0280PA01X+078394Y+194011               S0      
327SW_SSD1_R                          A01X+081300Y+157350X0220Y0400     S0      
317SW_SSD1_R                    D0220PA01X+081950Y+156120               S0      
317SW_SSD1_R                    D0220PA01X+082430Y+156550               S0      
317SW_SSD1_R                    D0300PA01X+082400Y+157175               S0      
317SW_SSD1_R        VIA        MD0280PA01X+081920Y+156610               S0      
327SW_SSD2_R                          A01X+081300Y+116800X0220Y0400     S0      
317SW_SSD2_R                    D0220PA01X+081950Y+115570               S0      
317SW_SSD2_R                    D0220PA01X+082430Y+116000               S0      
317SW_SSD2_R                    D0300PA01X+082400Y+116625               S0      
317SW_SSD2_R        VIA        MD0280PA01X+081900Y+116060               S0      
327SW_SSD3_R                          A01X+081300Y+076250X0220Y0400     S0      
317SW_SSD3_R                    D0220PA01X+081950Y+075020               S0      
317SW_SSD3_R                    D0220PA01X+082430Y+075450               S0      
317SW_SSD3_R                    D0300PA01X+082400Y+076075               S0      
317SW_SSD3_R        VIA        MD0280PA01X+081900Y+075510               S0      
327SW_SSD4_R                          A01X+081300Y+035700X0220Y0400     S0      
317SW_SSD4_R                    D0220PA01X+081950Y+034470               S0      
317SW_SSD4_R                    D0220PA01X+082430Y+034900               S0      
317SW_SSD4_R                    D0300PA01X+082400Y+035525               S0      
317SW_SSD4_R        VIA        MD0280PA01X+081900Y+034960               S0      
327SW_SSD5_R                          A01X+005450Y+194850X0220Y0400     S0      
317SW_SSD5_R                    D0220PA01X+006100Y+193620               S0      
317SW_SSD5_R                    D0220PA01X+006580Y+194050               S0      
317SW_SSD5_R                    D0300PA01X+006550Y+194675               S0      
317SW_SSD5_R        VIA        MD0280PA01X+006050Y+194110               S0      
327SW_SSD6_R                          A01X+008400Y+156450X0220Y0400     S0      
317SW_SSD6_R                    D0220PA01X+009050Y+155220               S0      
317SW_SSD6_R                    D0220PA01X+009530Y+155650               S0      
317SW_SSD6_R                    D0300PA01X+009500Y+156275               S0      
317SW_SSD6_R        VIA        MD0280PA01X+009030Y+155710               S0      
327SW_SSD7_R                          A01X+008470Y+116840X0220Y0400     S0      
317SW_SSD7_R                    D0220PA01X+009120Y+115610               S0      
317SW_SSD7_R                    D0220PA01X+009600Y+116040               S0      
317SW_SSD7_R                    D0300PA01X+009570Y+116665               S0      
317SW_SSD7_R        VIA        MD0280PA01X+009070Y+116100               S0      
327SW_SSD8_R                          A01X+008470Y+076250X0220Y0400     S0      
317SW_SSD8_R                    D0220PA01X+009120Y+075020               S0      
317SW_SSD8_R                    D0220PA01X+009600Y+075450               S0      
317SW_SSD8_R                    D0300PA01X+009570Y+076075               S0      
317SW_SSD8_R        VIA        MD0280PA01X+009070Y+075510               S0      
327SW_SSD9_R                          A01X+008470Y+035700X0220Y0400     S0      
317SW_SSD9_R                    D0220PA01X+009120Y+034470               S0      
317SW_SSD9_R                    D0220PA01X+009600Y+034900               S0      
317SW_SSD9_R                    D0300PA01X+009570Y+035525               S0      
317SW_SSD9_R        VIA        MD0280PA01X+009070Y+034960               S0      
327SW_SSD10_R                         A01X+016090Y+163510X0220Y0400     S0      
317SW_SSD10_R                   D0220PA01X+015440Y+164740               S0      
317SW_SSD10_R                   D0220PA01X+014960Y+164310               S0      
317SW_SSD10_R                   D0300PA01X+014990Y+163685               S0      
317SW_SSD10_R       VIA        MD0280PA01X+015490Y+164250               S0      
327SW_SSD11_R                         A01X+015970Y+122960X0220Y0400     S0      
317SW_SSD11_R                   D0220PA01X+015320Y+124190               S0      
317SW_SSD11_R                   D0220PA01X+014840Y+123760               S0      
317SW_SSD11_R                   D0300PA01X+014870Y+123135               S0      
317SW_SSD11_R       VIA        MD0280PA01X+015370Y+123700               S0      
327SW_SSD12_R                         A01X+015940Y+082410X0220Y0400     S0      
317SW_SSD12_R                   D0220PA01X+015290Y+083640               S0      
317SW_SSD12_R                   D0220PA01X+014810Y+083210               S0      
317SW_SSD12_R                   D0300PA01X+014840Y+082585               S0      
317SW_SSD12_R       VIA        MD0280PA01X+015340Y+083110               S0      
327SW_SSD13_R                         A01X+015940Y+041860X0220Y0400     S0      
317SW_SSD13_R                   D0220PA01X+015290Y+043090               S0      
317SW_SSD13_R                   D0220PA01X+014810Y+042660               S0      
317SW_SSD13_R                   D0300PA01X+014840Y+042035               S0      
317SW_SSD13_R       VIA        MD0280PA01X+015340Y+042600               S0      
327SW_SSD14_R                         A01X+020800Y+004450X0220Y0400     S0      
317SW_SSD14_R                   D0220PA01X+020150Y+005680               S0      
317SW_SSD14_R                   D0220PA01X+019670Y+005250               S0      
317SW_SSD14_R                   D0300PA01X+019700Y+004625               S0      
317SW_SSD14_R       VIA        MD0280PA01X+020160Y+005190               S0      
327NNAME00028                         A01X+035259Y+170886X0460Y0120     S0      
317NNAME00028                   D0220PA01X+032820Y+172100               S0      
317NNAME00028       VIA        MD0280PA01X+033350Y+172100               S0      
327NNAME00029                         A01X+035259Y+170689X0460Y0120     S0      
317NNAME00029                   D0220PA01X+032820Y+171700               S0      
317NNAME00029                   D0220PA01X+032820Y+171300               S0      
317NNAME00029       VIA        MD0280PA01X+033350Y+171300               S0      
327P3V3_PG                            A01X+035259Y+040492X0460Y0120     S0      
327P3V3_PG                            A01X+035259Y+083492X0460Y0120     S0      
327P3V3_PG                            A01X+035259Y+120642X0460Y0120     S0      
327P3V3_PG                            A01X+035259Y+170492X0460Y0120     S0      
317P3V3_PG                      D0220PA01X+090250Y+173070               S0      
317P3V3_PG                      D0220PA01X+032820Y+040850               S0      
317P3V3_PG                      D0220PA01X+032820Y+083850               S0      
317P3V3_PG                      D0220PA01X+032820Y+121000               S0      
317P3V3_PG                      D0220PA01X+032820Y+170850               S0      
317P3V3_PG          VIA        MD0280PA08X+031880Y+082370               S0      
317P3V3_PG          VIA        MD0280PA08X+032825Y+123300               S0      
317P3V3_PG          VIA        MD0280PA08X+032825Y+044140               S0      
317P3V3_PG          VIA        MD0280PA08X+033503Y+170173               S0      
317P3V3_PG          VIA        MD0100PA00X+033130Y+121000               S0      
317P3V3_PG          VIA        MD0100PA00X+033130Y+040850               S0      
317P3V3_PG          VIA        MD0100PA00X+033130Y+083850               S0      
317P3V3_PG          VIA        MD0100PA00X+033150Y+170850               S0      
317P3V3_PG          VIA        MD0100PA00X+090250Y+173400               S0      
327NNAME00030                         A01X+035259Y+169508X0460Y0120     S0      
317NNAME00030                   D0220PA01X+033820Y+169500               S0      
317NNAME00030                   D0220PA01X+033820Y+169100               S0      
317NNAME00030       VIA        MD0280PA01X+034400Y+169360               S0      
327NNAME00031                         A01X+035259Y+169311X0460Y0120     S0      
317NNAME00031                   D0220PA01X+033420Y+168500               S0      
317NNAME00031       VIA        MD0280PA01X+034270Y+168620               S0      
327NNAME00032                         A01X+035259Y+169114X0460Y0120     S0      
317NNAME00032                   D0220PA01X+033420Y+168100               S0      
317NNAME00032       VIA        MD0280PA01X+033910Y+167960               S0      
327NNAME00033                         A01X+035259Y+168917X0460Y0120     S0      
317NNAME00033                   D0220PA01X+033420Y+167300               S0      
317NNAME00033                   D0220PA01X+033420Y+167700               S0      
317NNAME00033       VIA        MD0280PA01X+034600Y+167650               S0      
327NNAME00034                         A01X+035524Y+168208X0120Y0360     S0      
317NNAME00034                   D0220PA01X+034050Y+166770               S0      
327NNAME00035                         A01X+035721Y+168259X0120Y0460     S0      
317NNAME00035                   D0220PA01X+034450Y+166770               S0      
327NNAME00036                         A01X+036311Y+168259X0120Y0460     S0      
317NNAME00036                   D0220PA01X+035550Y+166770               S0      
327NNAME00037                         A01X+036508Y+168259X0120Y0460     S0      
317NNAME00037                   D0220PA01X+035950Y+166770               S0      
327NNAME00038                         A01X+037689Y+168259X0120Y0460     S0      
327NNAME00038                         A01X+037886Y+168259X0120Y0460     S0      
327NNAME00038                         A01X+038742Y+169114X0460Y0120     S0      
327NNAME00038                         A01X+038742Y+169311X0460Y0120     S0      
327NNAME00038                         A01X+037886Y+171742X0120Y0460     S0      
327NNAME00038                         A01X+037689Y+171742X0120Y0460     S0      
317NNAME00038                   D0220PA01X+037900Y+172930               S0      
317NNAME00038       VIA        MD0280PA08X+039550Y+170300               S0      
317NNAME00038       VIA        MD0100PA00X+037689Y+167800               S0      
317NNAME00038       VIA        MD0100PA00X+037900Y+172600               S0      
317NNAME00038       VIA        MD0100PA00X+039550Y+169050               S0      
327NNAME00039                         A01X+038742Y+170296X0460Y0120     S0      
317NNAME00039                   D0220PA01X+040230Y+170600               S0      
327NNAME00040                         A01X+038742Y+170492X0460Y0120     S0      
317NNAME00040                   D0220PA01X+040230Y+171000               S0      
327NNAME00041                         A01X+038742Y+171083X0460Y0120     S0      
317NNAME00041                   D0220PA01X+040230Y+172100               S0      
327NNAME00042                         A01X+038742Y+171280X0460Y0120     S0      
317NNAME00042                   D0220PA01X+040230Y+172500               S0      
327NNAME00043                         A01X+036508Y+171742X0120Y0460     S0      
317NNAME00043                   D0220PA01X+035950Y+173230               S0      
327NNAME00044                         A01X+036311Y+171742X0120Y0460     S0      
317NNAME00044                   D0220PA01X+035550Y+173230               S0      
327NNAME00045                         A01X+035721Y+171742X0120Y0460     S0      
317NNAME00045                   D0220PA01X+034450Y+173230               S0      
327NNAME00046                         A01X+035524Y+171792X0120Y0360     S0      
317NNAME00046                   D0220PA01X+034050Y+173230               S0      
327SDA_DR3                            A01X+030492Y+059360X0120Y0360     S0      
317SDA_DR3                      D0220PA01X+085280Y+073150               S0      
317SDA_DR3                      D0220PA01X+031600Y+060530               S0      
317SDA_DR3          VIA        MD0120PA00X+052016Y+062350               S0      
317SDA_DR3          VIA        MD0100PA00X+031383Y+061550               S0      
327SCL_DR3                            A01X+030295Y+059330X0120Y0420     S0      
317SCL_DR3                      D0220PA01X+085280Y+072650               S0      
317SCL_DR3                      D0220PA01X+030800Y+060530               S0      
317SCL_DR3          VIA        MD0120PA00X+051266Y+062350               S0      
317SCL_DR3          VIA        MD0100PA00X+031003Y+061550               S0      
327SDA_DR4                            A01X+030098Y+059330X0120Y0420     S0      
317SDA_DR4                      D0220PA01X+085280Y+032600               S0      
317SDA_DR4                      D0220PA01X+030400Y+060530               S0      
317SDA_DR4          VIA        MD0120PA00X+055500Y+053184               S0      
317SDA_DR4          VIA        MD0100PA00X+030183Y+062100               S0      
327SCL_DR4                            A01X+029902Y+059330X0120Y0420     S0      
317SCL_DR4                      D0220PA01X+085280Y+032100               S0      
317SCL_DR4                      D0220PA01X+029600Y+060530               S0      
317SCL_DR4          VIA        MD0120PA00X+055500Y+052434               S0      
317SCL_DR4          VIA        MD0100PA00X+029803Y+062100               S0      
327SDA_DR12                           A01X+029705Y+059330X0120Y0420     S0      
317SDA_DR12                     D0220PA01X+011920Y+085500               S0      
317SDA_DR12                     D0220PA01X+029200Y+060530               S0      
317SDA_DR12         VIA        MD0120PA00X+012622Y+085375               S0      
317SDA_DR12         VIA        MD0100PA00X+028993Y+061570               S0      
327SCL_DR12                           A01X+029508Y+059360X0120Y0360     S0      
317SCL_DR12                     D0220PA01X+011920Y+086000               S0      
317SCL_DR12                     D0220PA01X+028400Y+060530               S0      
317SCL_DR12         VIA        MD0120PA00X+012622Y+086125               S0      
317SCL_DR12         VIA        MD0100PA00X+028613Y+061570               S0      
327SDA_DR8                            A01X+029190Y+059042X0360Y0120     S0      
317SDA_DR8                      D0220PA01X+012480Y+073150               S0      
317SDA_DR8                      D0220PA01X+028020Y+059700               S0      
317SDA_DR8          VIA        MD0120PA00X+019084Y+080820               S0      
317SDA_DR8          VIA        MD0100PA00X+026980Y+059473               S0      
327SCL_DR8                            A01X+029220Y+058845X0420Y0120     S0      
317SCL_DR8                      D0220PA01X+012480Y+072650               S0      
317SCL_DR8                      D0220PA01X+028020Y+058900               S0      
317SCL_DR8          VIA        MD0120PA00X+018334Y+080820               S0      
317SCL_DR8          VIA        MD0100PA00X+026980Y+059093               S0      
327SDA_DR13                           A01X+029220Y+058452X0420Y0120     S0      
317SDA_DR13                     D0220PA01X+011920Y+044950               S0      
317SDA_DR13                     D0220PA01X+028020Y+058500               S0      
317SDA_DR13         VIA        MD0120PA00X+022066Y+043850               S0      
317SDA_DR13         VIA        MD0100PA00X+027000Y+058283               S0      
327SCL_DR13                           A01X+029220Y+058255X0420Y0120     S0      
317SCL_DR13                     D0220PA01X+011920Y+045450               S0      
317SCL_DR13                     D0220PA01X+028020Y+057700               S0      
317SCL_DR13         VIA        MD0120PA00X+022816Y+043850               S0      
317SCL_DR13         VIA        MD0100PA00X+027000Y+057903               S0      
327SDA_DR9                            A01X+029190Y+058058X0360Y0120     S0      
317SDA_DR9                      D0220PA01X+012480Y+032600               S0      
317SDA_DR9                      D0220PA01X+028020Y+057300               S0      
317SDA_DR9          VIA        MD0120PA00X+023566Y+038206               S0      
317SDA_DR9          VIA        MD0100PA00X+027000Y+057093               S0      
327SCL_DR9                            A01X+029508Y+057740X0120Y0360     S0      
317SCL_DR9                      D0220PA01X+012480Y+032100               S0      
317SCL_DR9                      D0220PA01X+028020Y+056500               S0      
317SCL_DR9          VIA        MD0120PA00X+024316Y+038206               S0      
317SCL_DR9          VIA        MD0100PA00X+027000Y+056713               S0      
327SDA_DR14                           A01X+029705Y+057770X0120Y0420     S0      
317SDA_DR14                     D0220PA01X+011930Y+006920               S0      
317SDA_DR14                     D0220PA01X+029058Y+056570               S0      
317SDA_DR14         VIA        MD0120PA00X+028400Y+054884               S0      
317SDA_DR14         VIA        MD0100PA00X+029267Y+055550               S0      
327SCL_DR14                           A01X+029902Y+057770X0120Y0420     S0      
317SCL_DR14                     D0220PA01X+011430Y+006920               S0      
317SCL_DR14                     D0220PA01X+029845Y+056570               S0      
317SCL_DR14         VIA        MD0120PA00X+028400Y+054134               S0      
317SCL_DR14         VIA        MD0100PA00X+029647Y+055550               S0      
327NNAME00047                         A01X+030492Y+057740X0120Y0360     S0      
317NNAME00047                   D0220PA01X+031750Y+056570               S0      
317NNAME00047                   D0220PA01X+031300Y+056570               S0      
317NNAME00047       VIA        MD0280PA01X+030650Y+056840               S0      
327NNAME00048                         A01X+030810Y+058058X0360Y0120     S0      
317NNAME00048                   D0220PA01X+032030Y+057250               S0      
317NNAME00048       VIA        MD0280PA01X+031500Y+057100               S0      
327NNAME00049                         A01X+030780Y+058255X0420Y0120     S0      
317NNAME00049                   D0220PA01X+032030Y+057650               S0      
317NNAME00049       VIA        MD0280PA01X+031500Y+057850               S0      
327NNAME00050                         A01X+030780Y+058648X0420Y0120     S0      
317NNAME00050                   D0220PA01X+032580Y+058900               S0      
317NNAME00050                   D0220PA01X+032580Y+059300               S0      
317NNAME00050       VIA        MD0280PA01X+031400Y+058700               S0      
327NNAME00051                         A01X+030780Y+058845X0420Y0120     S0      
317NNAME00051                   D0220PA01X+032580Y+060100               S0      
317NNAME00051                   D0220PA01X+032580Y+059700               S0      
317NNAME00051       VIA        MD0280PA01X+032090Y+059300               S0      
327NNAME00052                         A01X+030810Y+059042X0360Y0120     S0      
317NNAME00052                   D0220PA01X+032580Y+060500               S0      
317NNAME00052       VIA        MD0280PA01X+031540Y+059840               S0      
327SDA_DR2                            A01X+030810Y+141658X0360Y0120     S0      
317SDA_DR2                      D0220PA01X+085280Y+113700               S0      
317SDA_DR2                      D0220PA01X+031980Y+140540               S0      
317SDA_DR2          VIA        MD0120PA00X+041250Y+113825               S0      
317SDA_DR2          VIA        MD0100PA00X+033030Y+140730               S0      
327SCL_DR2                            A01X+030780Y+141855X0420Y0120     S0      
317SCL_DR2                      D0220PA01X+085280Y+113200               S0      
317SCL_DR2                      D0220PA01X+031980Y+141350               S0      
317SCL_DR2          VIA        MD0120PA00X+041250Y+113075               S0      
317SCL_DR2          VIA        MD0100PA00X+033030Y+141110               S0      
327SDA_DR1                            A01X+030780Y+142052X0420Y0120     S0      
317SDA_DR1                      D0220PA01X+085280Y+154250               S0      
317SDA_DR1                      D0220PA01X+031980Y+141750               S0      
317SDA_DR1          VIA        MD0120PA00X+035066Y+141100               S0      
317SDA_DR1          VIA        MD0100PA00X+033000Y+141967               S0      
327SCL_DR1                            A01X+030780Y+142248X0420Y0120     S0      
317SCL_DR1                      D0220PA01X+085280Y+153750               S0      
317SCL_DR1                      D0220PA01X+031980Y+142570               S0      
317SCL_DR1          VIA        MD0120PA00X+035816Y+141100               S0      
317SCL_DR1          VIA        MD0100PA00X+033000Y+142347               S0      
327SDA_DR0                            A01X+030780Y+142445X0420Y0120     S0      
317SDA_DR0                      D0220PA01X+085180Y+194080               S0      
317SDA_DR0                      D0220PA01X+031980Y+142970               S0      
317SDA_DR0          VIA        MD0120PA00X+045066Y+174300               S0      
317SDA_DR0          VIA        MD0100PA00X+033000Y+143137               S0      
327SCL_DR0                            A01X+030810Y+142642X0360Y0120     S0      
317SCL_DR0                      D0220PA01X+085180Y+193580               S0      
317SCL_DR0                      D0220PA01X+031980Y+143770               S0      
317SCL_DR0          VIA        MD0120PA00X+045816Y+174300               S0      
317SCL_DR0          VIA        MD0100PA00X+033000Y+143517               S0      
327SDA_DR5                            A01X+030492Y+142960X0120Y0360     S0      
317SDA_DR5                      D0220PA01X+012310Y+193910               S0      
317SDA_DR5                      D0220PA01X+031160Y+144130               S0      
317SDA_DR5          VIA        MD0120PA00X+023984Y+174000               S0      
317SDA_DR5          VIA        MD0100PA00X+030963Y+145130               S0      
327SCL_DR5                            A01X+030295Y+142930X0120Y0420     S0      
317SCL_DR5                      D0220PA01X+012310Y+193410               S0      
317SCL_DR5                      D0220PA01X+030360Y+144130               S0      
317SCL_DR5          VIA        MD0120PA00X+023234Y+174000               S0      
317SCL_DR5          VIA        MD0100PA00X+030583Y+145130               S0      
327SDA_DR10                           A01X+029902Y+142930X0120Y0420     S0      
317SDA_DR10                     D0220PA01X+011920Y+166600               S0      
317SDA_DR10                     D0220PA01X+029960Y+144130               S0      
317SDA_DR10         VIA        MD0120PA00X+013034Y+167240               S0      
317SDA_DR10         VIA        MD0100PA00X+029763Y+145150               S0      
327SCL_DR10                           A01X+029705Y+142930X0120Y0420     S0      
317SCL_DR10                     D0220PA01X+011920Y+167100               S0      
317SCL_DR10                     D0220PA01X+029160Y+144130               S0      
317SCL_DR10         VIA        MD0120PA00X+012284Y+167240               S0      
317SCL_DR10         VIA        MD0100PA00X+029383Y+145150               S0      
327SDA_DR6                            A01X+029508Y+142960X0120Y0360     S0      
317SDA_DR6                      D0220PA01X+012480Y+154250               S0      
317SDA_DR6                      D0220PA01X+028760Y+144130               S0      
317SDA_DR6          VIA        MD0120PA00X+011739Y+154375               S0      
317SDA_DR6          VIA        MD0100PA00X+028583Y+145140               S0      
327SCL_DR6                            A01X+029190Y+142642X0360Y0120     S0      
317SCL_DR6                      D0220PA01X+012480Y+153750               S0      
317SCL_DR6                      D0220PA01X+027965Y+144130               S0      
317SCL_DR6          VIA        MD0120PA00X+011739Y+153625               S0      
317SCL_DR6          VIA        MD0100PA00X+028203Y+145140               S0      
327SDA_DR11                           A01X+029220Y+142445X0420Y0120     S0      
317SDA_DR11                     D0220PA01X+011920Y+126050               S0      
317SDA_DR11                     D0220PA01X+028020Y+143150               S0      
317SDA_DR11         VIA        MD0120PA00X+024270Y+125916               S0      
317SDA_DR11         VIA        MD0100PA00X+027010Y+142950               S0      
327SCL_DR11                           A01X+029220Y+142248X0420Y0120     S0      
317SCL_DR11                     D0220PA01X+011920Y+126550               S0      
317SCL_DR11                     D0220PA01X+028020Y+142350               S0      
317SCL_DR11         VIA        MD0120PA00X+024270Y+126666               S0      
317SCL_DR11         VIA        MD0100PA00X+027010Y+142570               S0      
327SDA_DR7                            A01X+029220Y+142052X0420Y0120     S0      
317SDA_DR7                      D0220PA01X+012480Y+113700               S0      
317SDA_DR7                      D0220PA01X+028020Y+141950               S0      
317SDA_DR7          VIA        MD0120PA00X+026884Y+118306               S0      
317SDA_DR7          VIA        MD0100PA00X+027000Y+141733               S0      
327SCL_DR7                            A01X+029220Y+141855X0420Y0120     S0      
317SCL_DR7                      D0220PA01X+012480Y+113200               S0      
317SCL_DR7                      D0220PA01X+028020Y+141150               S0      
317SCL_DR7          VIA        MD0120PA00X+027634Y+118306               S0      
317SCL_DR7          VIA        MD0100PA00X+027000Y+141353               S0      
327NNAME00053                         A01X+029190Y+141658X0360Y0120     S0      
317NNAME00053                   D0220PA01X+028020Y+140350               S0      
317NNAME00053                   D0220PA01X+028020Y+140750               S0      
317NNAME00053       VIA        MD0280PA01X+028510Y+141220               S0      
327NNAME00054                         A01X+029508Y+141340X0120Y0360     S0      
317NNAME00054                   D0220PA01X+028700Y+139920               S0      
317NNAME00054       VIA        MD0280PA01X+028570Y+140410               S0      
327NNAME00055                         A01X+029705Y+141370X0120Y0420     S0      
317NNAME00055                   D0220PA01X+029100Y+139920               S0      
317NNAME00055       VIA        MD0280PA01X+029320Y+140610               S0      
327NNAME00056                         A01X+030098Y+141370X0120Y0420     S0      
317NNAME00056                   D0220PA01X+030750Y+139570               S0      
317NNAME00056                   D0220PA01X+030350Y+139570               S0      
317NNAME00056       VIA        MD0280PA01X+030150Y+140750               S0      
327NNAME00057                         A01X+030295Y+141370X0120Y0420     S0      
317NNAME00057                   D0220PA01X+031150Y+139570               S0      
317NNAME00057                   D0220PA01X+031550Y+139570               S0      
317NNAME00057       VIA        MD0280PA01X+030740Y+140080               S0      
327NNAME00058                         A01X+030492Y+141340X0120Y0360     S0      
317NNAME00058                   D0220PA01X+031950Y+139570               S0      
317NNAME00058       VIA        MD0280PA01X+031350Y+140630               S0      
327NNAME00059                         A01X+035259Y+121036X0460Y0120     S0      
317NNAME00059                   D0220PA01X+032820Y+122250               S0      
317NNAME00059       VIA        MD0280PA01X+033350Y+122250               S0      
327NNAME00060                         A01X+035259Y+120839X0460Y0120     S0      
317NNAME00060                   D0220PA01X+032820Y+121850               S0      
317NNAME00060                   D0220PA01X+032820Y+121450               S0      
317NNAME00060       VIA        MD0280PA01X+033350Y+121450               S0      
327NNAME00061                         A01X+035259Y+119658X0460Y0120     S0      
317NNAME00061                   D0220PA01X+033820Y+119450               S0      
317NNAME00061                   D0220PA01X+033820Y+119050               S0      
317NNAME00061       VIA        MD0280PA01X+034350Y+119450               S0      
327NNAME00062                         A01X+035259Y+119461X0460Y0120     S0      
317NNAME00062                   D0220PA01X+033420Y+118650               S0      
317NNAME00062       VIA        MD0280PA01X+034300Y+118700               S0      
327NNAME00063                         A01X+035259Y+119264X0460Y0120     S0      
317NNAME00063                   D0220PA01X+033420Y+118250               S0      
317NNAME00063       VIA        MD0280PA01X+033900Y+118050               S0      
327NNAME00064                         A01X+035259Y+119068X0460Y0120     S0      
317NNAME00064                   D0220PA01X+033420Y+117850               S0      
317NNAME00064                   D0220PA01X+033420Y+117450               S0      
317NNAME00064       VIA        MD0280PA01X+034560Y+117610               S0      
327NNAME00065                         A01X+035918Y+118409X0120Y0460     S0      
327NNAME00065                         A01X+036114Y+118409X0120Y0460     S0      
327NNAME00065                         A01X+038742Y+119264X0460Y0120     S0      
327NNAME00065                         A01X+038742Y+119461X0460Y0120     S0      
317NNAME00065                   D0220PA01X+039880Y+119200               S0      
317NNAME00065       VIA        MD0280PA08X+038314Y+117964               S0      
317NNAME00065       VIA        MD0100PA00X+035918Y+117964               S0      
317NNAME00065       VIA        MD0100PA00X+039875Y+118825               S0      
327NNAME00066                         A01X+037296Y+118409X0120Y0460     S0      
317NNAME00066                   D0220PA01X+037600Y+116920               S0      
327NNAME00067                         A01X+037492Y+118409X0120Y0460     S0      
317NNAME00067                   D0220PA01X+038000Y+116920               S0      
327NNAME00068                         A01X+038083Y+118409X0120Y0460     S0      
317NNAME00068                   D0220PA01X+039100Y+116920               S0      
327NNAME00069                         A01X+038280Y+118409X0120Y0460     S0      
317NNAME00069                   D0220PA01X+039500Y+116920               S0      
327NNAME00070                         A01X+038742Y+120445X0460Y0120     S0      
317NNAME00070                   D0220PA01X+040230Y+120750               S0      
327NNAME00071                         A01X+038742Y+120642X0460Y0120     S0      
317NNAME00071                   D0220PA01X+040230Y+121150               S0      
327NNAME00072                         A01X+038742Y+121233X0460Y0120     S0      
317NNAME00072                   D0220PA01X+040230Y+122250               S0      
327NNAME00073                         A01X+038742Y+121430X0460Y0120     S0      
317NNAME00073                   D0220PA01X+040230Y+122650               S0      
327NNAME00074                         A01X+038280Y+121892X0120Y0460     S0      
317NNAME00074                   D0220PA01X+039500Y+123380               S0      
327NNAME00075                         A01X+038083Y+121892X0120Y0460     S0      
317NNAME00075                   D0220PA01X+039100Y+123380               S0      
327NNAME00076                         A01X+037492Y+121892X0120Y0460     S0      
317NNAME00076                   D0220PA01X+038000Y+123380               S0      
327NNAME00077                         A01X+037296Y+121892X0120Y0460     S0      
317NNAME00077                   D0220PA01X+037600Y+123380               S0      
327NNAME00078                         A01X+036508Y+121892X0120Y0460     S0      
317NNAME00078                   D0220PA01X+035950Y+123380               S0      
327NNAME00079                         A01X+036311Y+121892X0120Y0460     S0      
317NNAME00079                   D0220PA01X+035550Y+123380               S0      
327NNAME00080                         A01X+035721Y+121892X0120Y0460     S0      
317NNAME00080                   D0220PA01X+034450Y+123380               S0      
327NNAME00081                         A01X+035524Y+121942X0120Y0360     S0      
317NNAME00081                   D0220PA01X+034050Y+123380               S0      
327NNAME00082                         A01X+035259Y+083886X0460Y0120     S0      
317NNAME00082                   D0220PA01X+032820Y+085100               S0      
317NNAME00082       VIA        MD0280PA01X+033350Y+085100               S0      
327NNAME00083                         A01X+035259Y+083689X0460Y0120     S0      
317NNAME00083                   D0220PA01X+032820Y+084700               S0      
317NNAME00083                   D0220PA01X+032820Y+084300               S0      
317NNAME00083       VIA        MD0280PA01X+033350Y+084300               S0      
327NNAME00084                         A01X+035259Y+082508X0460Y0120     S0      
317NNAME00084                   D0220PA01X+033820Y+081900               S0      
317NNAME00084                   D0220PA01X+033820Y+082300               S0      
317NNAME00084       VIA        MD0280PA01X+034350Y+082300               S0      
327NNAME00085                         A01X+035259Y+082311X0460Y0120     S0      
317NNAME00085                   D0220PA01X+033420Y+081500               S0      
317NNAME00085       VIA        MD0280PA01X+034300Y+081550               S0      
327NNAME00086                         A01X+035259Y+082114X0460Y0120     S0      
317NNAME00086                   D0220PA01X+033420Y+081100               S0      
317NNAME00086       VIA        MD0280PA01X+033900Y+080900               S0      
327NNAME00087                         A01X+035259Y+081917X0460Y0120     S0      
317NNAME00087                   D0220PA01X+033420Y+080300               S0      
317NNAME00087                   D0220PA01X+033420Y+080700               S0      
317NNAME00087       VIA        MD0280PA01X+034530Y+080440               S0      
327NNAME00088                         A01X+035918Y+081259X0120Y0460     S0      
327NNAME00088                         A01X+036114Y+081259X0120Y0460     S0      
327NNAME00088                         A01X+038742Y+083689X0460Y0120     S0      
327NNAME00088                         A01X+038742Y+083886X0460Y0120     S0      
317NNAME00088                   D0220PA01X+039730Y+084050               S0      
317NNAME00088       VIA        MD0280PA08X+039000Y+082050               S0      
317NNAME00088       VIA        MD0100PA00X+036010Y+080808               S0      
317NNAME00088       VIA        MD0100PA00X+040200Y+084400               S0      
327NNAME00089                         A01X+037296Y+081259X0120Y0460     S0      
317NNAME00089                   D0220PA01X+036950Y+079770               S0      
327NNAME00090                         A01X+037492Y+081259X0120Y0460     S0      
317NNAME00090                   D0220PA01X+037350Y+079770               S0      
327NNAME00091                         A01X+038083Y+081259X0120Y0460     S0      
317NNAME00091                   D0220PA01X+038450Y+079770               S0      
327NNAME00092                         A01X+038280Y+081259X0120Y0460     S0      
317NNAME00092                   D0220PA01X+038850Y+079770               S0      
327NNAME00093                         A01X+038742Y+081721X0460Y0120     S0      
317NNAME00093                   D0220PA01X+040230Y+080500               S0      
327NNAME00094                         A01X+038742Y+081917X0460Y0120     S0      
317NNAME00094                   D0220PA01X+040230Y+080900               S0      
327NNAME00095                         A01X+038742Y+082508X0460Y0120     S0      
317NNAME00095                   D0220PA01X+040230Y+082000               S0      
327NNAME00096                         A01X+038742Y+082705X0460Y0120     S0      
317NNAME00096                   D0220PA01X+040230Y+082400               S0      
327NNAME00097                         A01X+038280Y+084742X0120Y0460     S0      
317NNAME00097                   D0220PA01X+039500Y+086230               S0      
327NNAME00098                         A01X+038083Y+084742X0120Y0460     S0      
317NNAME00098                   D0220PA01X+039100Y+086230               S0      
327NNAME00099                         A01X+037492Y+084742X0120Y0460     S0      
317NNAME00099                   D0220PA01X+038000Y+086230               S0      
327NNAME00100                         A01X+037296Y+084742X0120Y0460     S0      
317NNAME00100                   D0220PA01X+037600Y+086230               S0      
327NNAME00101                         A01X+036508Y+084742X0120Y0460     S0      
317NNAME00101                   D0220PA01X+035950Y+086230               S0      
327NNAME00102                         A01X+036311Y+084742X0120Y0460     S0      
317NNAME00102                   D0220PA01X+035550Y+086230               S0      
327NNAME00103                         A01X+035721Y+084742X0120Y0460     S0      
317NNAME00103                   D0220PA01X+034450Y+086230               S0      
327NNAME00104                         A01X+035524Y+084792X0120Y0360     S0      
317NNAME00104                   D0220PA01X+034050Y+086230               S0      
327NNAME00105                         A01X+035259Y+040886X0460Y0120     S0      
317NNAME00105                   D0220PA01X+032820Y+042100               S0      
317NNAME00105       VIA        MD0280PA01X+033350Y+042100               S0      
327NNAME00106                         A01X+035259Y+040689X0460Y0120     S0      
317NNAME00106                   D0220PA01X+032820Y+041700               S0      
317NNAME00106                   D0220PA01X+032820Y+041300               S0      
317NNAME00106       VIA        MD0280PA01X+033350Y+041300               S0      
327NNAME00107                         A01X+035259Y+039508X0460Y0120     S0      
317NNAME00107                   D0220PA01X+033820Y+038900               S0      
317NNAME00107                   D0220PA01X+033820Y+039300               S0      
317NNAME00107       VIA        MD0280PA01X+034350Y+039300               S0      
327NNAME00108                         A01X+035259Y+039311X0460Y0120     S0      
317NNAME00108                   D0220PA01X+033420Y+038500               S0      
317NNAME00108       VIA        MD0280PA01X+034300Y+038550               S0      
327NNAME00109                         A01X+035259Y+039114X0460Y0120     S0      
317NNAME00109                   D0220PA01X+033420Y+038100               S0      
317NNAME00109       VIA        MD0280PA01X+033900Y+037900               S0      
327NNAME00110                         A01X+035259Y+038918X0460Y0120     S0      
317NNAME00110                   D0220PA01X+033420Y+037300               S0      
317NNAME00110                   D0220PA01X+033420Y+037700               S0      
317NNAME00110       VIA        MD0280PA01X+034590Y+037600               S0      
327NNAME00111                         A01X+035524Y+038208X0120Y0360     S0      
317NNAME00111                   D0220PA01X+034050Y+036770               S0      
327NNAME00112                         A01X+035721Y+038259X0120Y0460     S0      
317NNAME00112                   D0220PA01X+034450Y+036770               S0      
327NNAME00113                         A01X+036311Y+038259X0120Y0460     S0      
317NNAME00113                   D0220PA01X+035550Y+036770               S0      
327NNAME00114                         A01X+036508Y+038259X0120Y0460     S0      
317NNAME00114                   D0220PA01X+035950Y+036770               S0      
327NNAME00115                         A01X+037296Y+038259X0120Y0460     S0      
317NNAME00115                   D0220PA01X+037600Y+036770               S0      
327NNAME00116                         A01X+037492Y+038259X0120Y0460     S0      
317NNAME00116                   D0220PA01X+038000Y+036770               S0      
327NNAME00117                         A01X+038083Y+038259X0120Y0460     S0      
317NNAME00117                   D0220PA01X+039100Y+036770               S0      
327NNAME00118                         A01X+038280Y+038259X0120Y0460     S0      
317NNAME00118                   D0220PA01X+039500Y+036770               S0      
327NNAME00119                         A01X+038742Y+039114X0460Y0120     S0      
327NNAME00119                         A01X+038742Y+039311X0460Y0120     S0      
327NNAME00119                         A01X+038742Y+040689X0460Y0120     S0      
327NNAME00119                         A01X+038742Y+040886X0460Y0120     S0      
317NNAME00119                   D0220PA01X+039800Y+040680               S0      
317NNAME00119       VIA        MD0280PA01X+040600Y+039900               S0      
327NNAME00120                         A01X+038280Y+041742X0120Y0460     S0      
317NNAME00120                   D0220PA01X+039500Y+043230               S0      
327NNAME00121                         A01X+038083Y+041742X0120Y0460     S0      
317NNAME00121                   D0220PA01X+039100Y+043230               S0      
327NNAME00122                         A01X+037492Y+041742X0120Y0460     S0      
317NNAME00122                   D0220PA01X+038000Y+043230               S0      
327NNAME00123                         A01X+037296Y+041742X0120Y0460     S0      
317NNAME00123                   D0220PA01X+037600Y+043230               S0      
327NNAME00124                         A01X+036508Y+041742X0120Y0460     S0      
317NNAME00124                   D0220PA01X+035950Y+043230               S0      
327NNAME00125                         A01X+036311Y+041742X0120Y0460     S0      
317NNAME00125                   D0220PA01X+035550Y+043230               S0      
327NNAME00126                         A01X+035721Y+041742X0120Y0460     S0      
317NNAME00126                   D0220PA01X+034450Y+043230               S0      
327NNAME00127                         A01X+035524Y+041792X0120Y0360     S0      
317NNAME00127                   D0220PA01X+034050Y+043230               S0      
317NNAME00128                   D0220PA01X+040570Y+120750               S0      
327NNAME00128                         A01X+089524Y+145508X0790Y0200     S0      
317NNAME00128       VIA        MD0100PA00X+090515Y+145193               S0      
317NNAME00128       VIA        MD0100PA00X+091885Y+145824               S0      
317NNAME00129                   D0220PA01X+040570Y+121150               S0      
327NNAME00129                         A01X+089524Y+145823X0790Y0200     S0      
317NNAME00129       VIA        MD0100PA00X+090835Y+145193               S0      
317NNAME00129       VIA        MD0100PA00X+091885Y+145504               S0      
327SSD1_PERST_N                       A01X+000886Y+164387X0980Y0200     S0      
327SSD1_PERST_N                       A01X+089524Y+146453X0790Y0200     S0      
327SSD1_PERST_N                       A01X+089524Y+146768X0790Y0200     S0      
317SSD1_PERST_N     VIA        MD0280PA01X+003750Y+158100               S0      
317SSD1_PERST_N     VIA        MD0100PA00X+004737Y+152732               S0      
317SSD1_PERST_N     VIA        MD0100PA00X+090140Y+146610               S0      
317NNAME00130                   D0220PA01X+040570Y+122250               S0      
327NNAME00130                         A01X+088268Y+142201X0790Y0200     S0      
317NNAME00131                   D0220PA01X+040570Y+122650               S0      
327NNAME00131                         A01X+088268Y+142516X0790Y0200     S0      
327PE_TX1_DR1_N                       A01X+000886Y+152418X0980Y0200     S0      
327PE_TX1_DR1_N                       A01X+088268Y+143146X0790Y0200     S0      
317PE_TX1_DR1_N     VIA        MD0100PA00X+002753Y+152416               S0      
317PE_TX1_DR1_N     VIA        MD0100PA00X+086744Y+143143               S0      
327PE_TX1_DR1_P                       A01X+000886Y+152733X0980Y0200     S0      
327PE_TX1_DR1_P                       A01X+088268Y+143461X0790Y0200     S0      
317PE_TX1_DR1_P     VIA        MD0100PA00X+002753Y+152736               S0      
317PE_TX1_DR1_P     VIA        MD0100PA00X+086744Y+143463               S0      
327PE_RX1_DR1_N                       A08X+000886Y+153048X0980Y0200     S0      
327PE_RX1_DR1_N                       A01X+088268Y+144091X0790Y0200     S0      
317PE_RX1_DR1_N     VIA        MD0100PA00X+002000Y+153045               S0      
317PE_RX1_DR1_N     VIA        MD0100PA00X+087294Y+144028               S0      
327PE_RX1_DR1_P                       A08X+000886Y+153363X0980Y0200     S0      
327PE_RX1_DR1_P                       A01X+088268Y+144406X0790Y0200     S0      
317PE_RX1_DR1_P     VIA        MD0100PA00X+002000Y+153365               S0      
317PE_RX1_DR1_P     VIA        MD0100PA00X+087294Y+144468               S0      
327PE_TX4_DR1_N                       A01X+000886Y+156198X0980Y0200     S0      
327PE_TX4_DR1_N                       A01X+088268Y+151965X0790Y0200     S0      
317PE_TX4_DR1_N     VIA        MD0100PA00X+002753Y+156195               S0      
317PE_TX4_DR1_N     VIA        MD0100PA00X+086744Y+151962               S0      
327PE_TX4_DR1_P                       A01X+000886Y+156513X0980Y0200     S0      
327PE_TX4_DR1_P                       A01X+088268Y+152280X0790Y0200     S0      
317PE_TX4_DR1_P     VIA        MD0100PA00X+002753Y+156515               S0      
317PE_TX4_DR1_P     VIA        MD0100PA00X+086744Y+152282               S0      
327PE_RX4_DR1_N                       A08X+000886Y+156828X0980Y0200     S0      
327PE_RX4_DR1_N                       A01X+088268Y+152910X0790Y0200     S0      
317PE_RX4_DR1_N     VIA        MD0100PA00X+002000Y+156825               S0      
317PE_RX4_DR1_N     VIA        MD0100PA00X+087294Y+152847               S0      
327PE_RX4_DR1_P                       A08X+000886Y+157143X0980Y0200     S0      
327PE_RX4_DR1_P                       A01X+088268Y+153224X0790Y0200     S0      
317PE_RX4_DR1_P     VIA        MD0100PA00X+002000Y+157145               S0      
317PE_RX4_DR1_P     VIA        MD0100PA00X+087294Y+153287               S0      
317SCL_DR1_R                    D0220PA01X+085620Y+153750               S0      
327SCL_DR1_R                          A01X+088268Y+153854X0790Y0200     S0      
317SCL_DR1_R        VIA        MD0280PA01X+086444Y+153611               S0      
317SDA_DR1_R                    D0220PA01X+085620Y+154250               S0      
327SDA_DR1_R                          A01X+088268Y+154169X0790Y0200     S0      
317SDA_DR1_R        VIA        MD0280PA01X+086444Y+154361               S0      
317DUALPORTEN#1                 D0220PA01X+085550Y+154780               S0      
317DUALPORTEN#1                 D0220PA01X+084560Y+154780               S0      
327DUALPORTEN#1                       A01X+088268Y+154484X0790Y0200     S0      
317DUALPORTEN#1     VIA        MD0280PA01X+085055Y+154775               S0      
317SSD1_CLK0_OE_N               D0220PA01X+042470Y+122000               S0      
317SSD1_CLK0_OE_N               D0220PA01X+042900Y+121980               S0      
327SSD1_CLK0_OE_N                     A01X+089360Y+149045X0810Y0260     S0      
317SSD1_CLK0_OE_N   VIA        MD0280PA01X+043400Y+121975               S0      
317SSD_PRSNT_NET1               D0220PA01X+042470Y+121200               S0      
317SSD_PRSNT_NET1               D0220PA01X+042900Y+121180               S0      
327SSD_PRSNT_NET1                     A01X+089360Y+152045X0810Y0260     S0      
317SSD_PRSNT_NET1   VIA        MD0280PA01X+043390Y+121175               S0      
317SSD_ACT_DR1                  D0220PA01X+089875Y+136719               S0      
317SSD_ACT_DR1                  D0220PA01X+090630Y+136299               S0      
327SSD_ACT_DR1                        A01X+089360Y+152545X0810Y0260     S0      
317SSD_ACT_DR1      VIA        MD0280PA01X+090390Y+136766               S0      
317SSD_ACT_DR1      VIA        MD0100PA00X+089565Y+136734               S0      
317SSD_ACT_DR1      VIA        MD0100PA00X+089994Y+152545               S0      
32712V_PRECH_SSD1                     A01X+091055Y+158460X0450Y1100     S0      
32712V_PRECH_SSD1                     A01X+089360Y+153545X0810Y0260     S0      
31712V_PRECH_SSD1   VIA        MD0280PA01X+091860Y+158460               S0      
327P12V_SSD1                          A01X+086630Y+156318X0830Y0570     S0      
327P12V_SSD1                          A01X+087450Y+157202X0830Y0570     S0      
327P12V_SSD1                          A01X+089205Y+158460X0450Y1100     S0      
327P12V_SSD1                          A01X+085550Y+155900X0650Y0250     S0      
327P12V_SSD1                          A01X+085550Y+156400X0650Y0250     S0      
327P12V_SSD1                          A01X+085550Y+156900X0650Y0250     S0      
327P12V_SSD1                          A01X+085550Y+157400X0650Y0250     S0      
327P12V_SSD1                          A01X+087390Y+159440X0450Y0550     S0      
317P12V_SSD1                    D0340PA01X+086600Y+157470               S0      
317P12V_SSD1                    D0240PA01X+087420Y+155750               S0      
327P12V_SSD1                          A01X+089360Y+154045X0810Y0260     S0      
327P12V_SSD1                          A01X+089360Y+154545X0810Y0260     S0      
317P12V_SSD1        VIA        MD0280PA01X+088300Y+158250               S0      
317P12V_SSD1        VIA        MD0280PA01X+088530Y+159030               S0      
327PE_TX2_DR1_N                       A01X+000886Y+153678X0980Y0200     S0      
327PE_TX2_DR1_N                       A01X+088268Y+148185X0790Y0200     S0      
317PE_TX2_DR1_N     VIA        MD0100PA00X+002753Y+153676               S0      
317PE_TX2_DR1_N     VIA        MD0100PA00X+086744Y+148183               S0      
327PE_TX2_DR1_P                       A01X+000886Y+153993X0980Y0200     S0      
327PE_TX2_DR1_P                       A01X+088268Y+148500X0790Y0200     S0      
317PE_TX2_DR1_P     VIA        MD0100PA00X+002753Y+153996               S0      
317PE_TX2_DR1_P     VIA        MD0100PA00X+086744Y+148503               S0      
327PE_RX2_DR1_N                       A08X+000886Y+154308X0980Y0200     S0      
327PE_RX2_DR1_N                       A01X+088268Y+149130X0790Y0200     S0      
317PE_RX2_DR1_N     VIA        MD0100PA00X+002000Y+154305               S0      
317PE_RX2_DR1_N     VIA        MD0100PA00X+087294Y+149067               S0      
327PE_RX2_DR1_P                       A08X+000886Y+154623X0980Y0200     S0      
327PE_RX2_DR1_P                       A01X+088268Y+149445X0790Y0200     S0      
317PE_RX2_DR1_P     VIA        MD0100PA00X+002000Y+154625               S0      
317PE_RX2_DR1_P     VIA        MD0100PA00X+087294Y+149507               S0      
327PE_TX3_DR1_N                       A01X+000886Y+154938X0980Y0200     S0      
327PE_TX3_DR1_N                       A01X+088268Y+150075X0790Y0200     S0      
317PE_TX3_DR1_N     VIA        MD0100PA00X+002753Y+154935               S0      
317PE_TX3_DR1_N     VIA        MD0100PA00X+086744Y+150072               S0      
327PE_TX3_DR1_P                       A01X+000886Y+155253X0980Y0200     S0      
327PE_TX3_DR1_P                       A01X+088268Y+150390X0790Y0200     S0      
317PE_TX3_DR1_P     VIA        MD0100PA00X+002753Y+155255               S0      
317PE_TX3_DR1_P     VIA        MD0100PA00X+086744Y+150392               S0      
327PE_RX3_DR1_N                       A08X+000886Y+155568X0980Y0200     S0      
327PE_RX3_DR1_N                       A01X+088268Y+151020X0790Y0200     S0      
317PE_RX3_DR1_N     VIA        MD0100PA00X+002000Y+155565               S0      
317PE_RX3_DR1_N     VIA        MD0100PA00X+087294Y+150957               S0      
327PE_RX3_DR1_P                       A08X+000886Y+155883X0980Y0200     S0      
327PE_RX3_DR1_P                       A01X+088268Y+151335X0790Y0200     S0      
317PE_RX3_DR1_P     VIA        MD0100PA00X+002000Y+155885               S0      
317PE_RX3_DR1_P     VIA        MD0100PA00X+087294Y+151397               S0      
317NNAME00132                   D0220PA01X+034050Y+166430               S0      
327NNAME00132                         A01X+007721Y+175358X0790Y0200     S0      
317NNAME00132       VIA        MD0100PA00X+012500Y+175353               S0      
317NNAME00132       VIA        MD0100PA00X+006800Y+175361               S0      
317NNAME00133                   D0220PA01X+034450Y+166430               S0      
327NNAME00133                         A01X+007721Y+175043X0790Y0200     S0      
317NNAME00133       VIA        MD0100PA00X+012500Y+175033               S0      
317NNAME00133       VIA        MD0100PA00X+006800Y+175041               S0      
327SSD10_PERST_N                      A08X+000886Y+152418X0980Y0200     S0      
327SSD10_PERST_N                      A01X+007721Y+174413X0790Y0200     S0      
327SSD10_PERST_N                      A01X+007721Y+174099X0790Y0200     S0      
317SSD10_PERST_N    VIA        MD0280PA01X+005172Y+159556               S0      
317SSD10_PERST_N    VIA        MD0100PA00X+004685Y+151426               S0      
317SSD10_PERST_N    VIA        MD0100PA00X+005164Y+166536               S0      
317SSD10_PERST_N    VIA        MD0100PA00X+007101Y+173800               S0      
317NNAME00134                   D0220PA01X+035550Y+166430               S0      
327NNAME00134                         A01X+008976Y+178665X0790Y0200     S0      
317NNAME00135                   D0220PA01X+035950Y+166430               S0      
327NNAME00135                         A01X+008976Y+178350X0790Y0200     S0      
327PE_TX1_DR10_P                      A01X+000886Y+158402X0980Y0200     S0      
327PE_TX1_DR10_P                      A01X+008976Y+177721X0790Y0200     S0      
317PE_TX1_DR10_P    VIA        MD0100PA00X+010500Y+177723               S0      
317PE_TX1_DR10_P    VIA        MD0100PA00X+002753Y+158400               S0      
327PE_TX1_DR10_N                      A01X+000886Y+158717X0980Y0200     S0      
327PE_TX1_DR10_N                      A01X+008976Y+177406X0790Y0200     S0      
317PE_TX1_DR10_N    VIA        MD0100PA00X+010500Y+177403               S0      
317PE_TX1_DR10_N    VIA        MD0100PA00X+002753Y+158720               S0      
327PE_RX1_DR10_P                      A08X+000886Y+159032X0980Y0200     S0      
327PE_RX1_DR10_P                      A01X+008976Y+176776X0790Y0200     S0      
317PE_RX1_DR10_P    VIA        MD0100PA00X+002000Y+159030               S0      
317PE_RX1_DR10_P    VIA        MD0100PA00X+009950Y+176838               S0      
327PE_RX1_DR10_N                      A08X+000886Y+159347X0980Y0200     S0      
327PE_RX1_DR10_N                      A01X+008976Y+176461X0790Y0200     S0      
317PE_RX1_DR10_N    VIA        MD0100PA00X+002000Y+159350               S0      
317PE_RX1_DR10_N    VIA        MD0100PA00X+009950Y+176398               S0      
327PE_TX4_DR10_P                      A01X+000886Y+162182X0980Y0200     S0      
327PE_TX4_DR10_P                      A01X+008976Y+168902X0790Y0200     S0      
317PE_TX4_DR10_P    VIA        MD0100PA00X+010500Y+168904               S0      
317PE_TX4_DR10_P    VIA        MD0100PA00X+002753Y+162179               S0      
327PE_TX4_DR10_N                      A01X+000886Y+162497X0980Y0200     S0      
327PE_TX4_DR10_N                      A01X+008976Y+168587X0790Y0200     S0      
317PE_TX4_DR10_N    VIA        MD0100PA00X+010500Y+168584               S0      
317PE_TX4_DR10_N    VIA        MD0100PA00X+002753Y+162499               S0      
327PE_RX4_DR10_P                      A08X+000886Y+162812X0980Y0200     S0      
327PE_RX4_DR10_P                      A01X+008976Y+167957X0790Y0200     S0      
317PE_RX4_DR10_P    VIA        MD0100PA00X+002000Y+162809               S0      
317PE_RX4_DR10_P    VIA        MD0100PA00X+009950Y+168019               S0      
327PE_RX4_DR10_N                      A08X+000886Y+163127X0980Y0200     S0      
327PE_RX4_DR10_N                      A01X+008976Y+167642X0790Y0200     S0      
317PE_RX4_DR10_N    VIA        MD0100PA00X+002000Y+163129               S0      
317PE_RX4_DR10_N    VIA        MD0100PA00X+009950Y+167579               S0      
317SCL_DR10_R                   D0220PA01X+011580Y+167100               S0      
327SCL_DR10_R                         A01X+008976Y+167012X0790Y0200     S0      
317SCL_DR10_R       VIA        MD0280PA01X+010800Y+167255               S0      
317SDA_DR10_R                   D0220PA01X+011580Y+166600               S0      
327SDA_DR10_R                         A01X+008976Y+166697X0790Y0200     S0      
317SDA_DR10_R       VIA        MD0280PA01X+010800Y+166505               S0      
317DUALPORTEN#10                D0220PA01X+011700Y+166120               S0      
317DUALPORTEN#10                D0220PA01X+012690Y+166120               S0      
327DUALPORTEN#10                      A01X+008976Y+166382X0790Y0200     S0      
317DUALPORTEN#10    VIA        MD0280PA01X+012195Y+166125               S0      
317NNAME00136                   D0220PA01X+035300Y+164530               S0      
317NNAME00136                   D0220PA01X+035280Y+164100               S0      
327NNAME00136                         A01X+007884Y+171821X0810Y0260     S0      
317NNAME00136       VIA        MD0280PA01X+035275Y+163600               S0      
317NNAME00137                   D0220PA01X+034500Y+164530               S0      
317NNAME00137                   D0220PA01X+034480Y+164100               S0      
327NNAME00137                         A01X+007884Y+168821X0810Y0260     S0      
317NNAME00137       VIA        MD0280PA01X+034475Y+163610               S0      
317SSD_ACT_DR10                 D0220PA01X+009780Y+183990               S0      
317SSD_ACT_DR10                 D0220PA01X+010190Y+183990               S0      
327SSD_ACT_DR10                       A01X+007884Y+168321X0810Y0260     S0      
317SSD_ACT_DR10     VIA        MD0280PA08X+005550Y+176300               S0      
317SSD_ACT_DR10     VIA        MD0100PA00X+006700Y+173800               S0      
317SSD_ACT_DR10     VIA        MD0100PA00X+007250Y+168321               S0      
317SSD_ACT_DR10     VIA        MD0100PA00X+009800Y+184880               S0      
327NNAME00138                         A01X+006645Y+162400X0450Y1100     S0      
327NNAME00138                         A01X+007884Y+167321X0810Y0260     S0      
317NNAME00138       VIA        MD0280PA01X+006320Y+161330               S0      
327P12V_SSD10                         A01X+010000Y+163838X0830Y0570     S0      
327P12V_SSD10                         A01X+010700Y+164702X0830Y0570     S0      
327P12V_SSD10                         A01X+008495Y+162400X0450Y1100     S0      
327P12V_SSD10                         A01X+011840Y+164960X0650Y0250     S0      
327P12V_SSD10                         A01X+011840Y+164460X0650Y0250     S0      
327P12V_SSD10                         A01X+011840Y+163960X0650Y0250     S0      
327P12V_SSD10                         A01X+011840Y+163460X0650Y0250     S0      
327P12V_SSD10                         A01X+009740Y+161670X0450Y0550     S0      
317P12V_SSD10                   D0340PA01X+010860Y+163380               S0      
317P12V_SSD10                   D0240PA01X+009890Y+165250               S0      
327P12V_SSD10                         A01X+007884Y+166821X0810Y0260     S0      
327P12V_SSD10                         A01X+007884Y+166321X0810Y0260     S0      
317P12V_SSD10       VIA        MD0280PA01X+007810Y+161450               S0      
317P12V_SSD10       VIA        MD0280PA01X+008650Y+161470               S0      
327PE_TX2_DR10_P                      A01X+000886Y+159662X0980Y0200     S0      
327PE_TX2_DR10_P                      A01X+008976Y+172681X0790Y0200     S0      
317PE_TX2_DR10_P    VIA        MD0100PA00X+010500Y+172684               S0      
317PE_TX2_DR10_P    VIA        MD0100PA00X+002753Y+159660               S0      
327PE_TX2_DR10_N                      A01X+000886Y+159977X0980Y0200     S0      
327PE_TX2_DR10_N                      A01X+008976Y+172366X0790Y0200     S0      
317PE_TX2_DR10_N    VIA        MD0100PA00X+010500Y+172364               S0      
317PE_TX2_DR10_N    VIA        MD0100PA00X+002753Y+159980               S0      
327PE_RX2_DR10_P                      A08X+000886Y+160292X0980Y0200     S0      
327PE_RX2_DR10_P                      A01X+008976Y+171736X0790Y0200     S0      
317PE_RX2_DR10_P    VIA        MD0100PA00X+002000Y+160289               S0      
317PE_RX2_DR10_P    VIA        MD0100PA00X+009950Y+171799               S0      
327PE_RX2_DR10_N                      A08X+000886Y+160607X0980Y0200     S0      
327PE_RX2_DR10_N                      A01X+008976Y+171421X0790Y0200     S0      
317PE_RX2_DR10_N    VIA        MD0100PA00X+002000Y+160609               S0      
317PE_RX2_DR10_N    VIA        MD0100PA00X+009950Y+171359               S0      
327PE_TX3_DR10_P                      A01X+000886Y+160922X0980Y0200     S0      
327PE_TX3_DR10_P                      A01X+008976Y+170791X0790Y0200     S0      
317PE_TX3_DR10_P    VIA        MD0100PA00X+010500Y+170794               S0      
317PE_TX3_DR10_P    VIA        MD0100PA00X+002753Y+160920               S0      
327PE_TX3_DR10_N                      A01X+000886Y+161237X0980Y0200     S0      
327PE_TX3_DR10_N                      A01X+008976Y+170476X0790Y0200     S0      
317PE_TX3_DR10_N    VIA        MD0100PA00X+010500Y+170474               S0      
317PE_TX3_DR10_N    VIA        MD0100PA00X+002753Y+161240               S0      
327PE_RX3_DR10_P                      A08X+000886Y+161552X0980Y0200     S0      
327PE_RX3_DR10_P                      A01X+008976Y+169846X0790Y0200     S0      
317PE_RX3_DR10_P    VIA        MD0100PA00X+002000Y+161549               S0      
317PE_RX3_DR10_P    VIA        MD0100PA00X+009950Y+169909               S0      
327PE_RX3_DR10_N                      A08X+000886Y+161867X0980Y0200     S0      
327PE_RX3_DR10_N                      A01X+008976Y+169531X0790Y0200     S0      
317PE_RX3_DR10_N    VIA        MD0100PA00X+002000Y+161869               S0      
317PE_RX3_DR10_N    VIA        MD0100PA00X+009950Y+169469               S0      
317NNAME00139                   D0220PA01X+040570Y+170600               S0      
327NNAME00139                         A01X+089524Y+186059X0790Y0200     S0      
317NNAME00139       VIA        MD0100PA00X+090515Y+185744               S0      
317NNAME00139       VIA        MD0100PA00X+091885Y+186375               S0      
317NNAME00140                   D0220PA01X+040570Y+171000               S0      
327NNAME00140                         A01X+089524Y+186374X0790Y0200     S0      
317NNAME00140       VIA        MD0100PA00X+090835Y+185744               S0      
317NNAME00140       VIA        MD0100PA00X+091885Y+186055               S0      
327SSD0_PERST_N                       A01X+000886Y+164702X0980Y0200     S0      
327SSD0_PERST_N                       A01X+089524Y+187004X0790Y0200     S0      
327SSD0_PERST_N                       A01X+089524Y+187319X0790Y0200     S0      
317SSD0_PERST_N     VIA        MD0280PA01X+003893Y+158968               S0      
317SSD0_PERST_N     VIA        MD0100PA00X+013650Y+173300               S0      
317SSD0_PERST_N     VIA        MD0100PA00X+004292Y+158318               S0      
317SSD0_PERST_N     VIA        MD0100PA00X+090120Y+187160               S0      
317NNAME00141                   D0220PA01X+040570Y+172100               S0      
327NNAME00141                         A01X+088268Y+182752X0790Y0200     S0      
317NNAME00142                   D0220PA01X+040570Y+172500               S0      
327NNAME00142                         A01X+088268Y+183067X0790Y0200     S0      
327PE_TX1_DR0_N                       A01X+000886Y+163442X0980Y0200     S0      
327PE_TX1_DR0_N                       A01X+088268Y+183697X0790Y0200     S0      
317PE_TX1_DR0_N     VIA        MD0100PA00X+002753Y+163439               S0      
317PE_TX1_DR0_N     VIA        MD0100PA00X+086744Y+183694               S0      
327PE_TX1_DR0_P                       A01X+000886Y+163757X0980Y0200     S0      
327PE_TX1_DR0_P                       A01X+088268Y+184012X0790Y0200     S0      
317PE_TX1_DR0_P     VIA        MD0100PA00X+002753Y+163759               S0      
317PE_TX1_DR0_P     VIA        MD0100PA00X+086744Y+184014               S0      
327PE_RX1_DR0_N                       A08X+000886Y+164072X0980Y0200     S0      
327PE_RX1_DR0_N                       A01X+088268Y+184642X0790Y0200     S0      
317PE_RX1_DR0_N     VIA        MD0100PA00X+002000Y+164069               S0      
317PE_RX1_DR0_N     VIA        MD0100PA00X+087294Y+184579               S0      
327PE_RX1_DR0_P                       A08X+000886Y+164387X0980Y0200     S0      
327PE_RX1_DR0_P                       A01X+088268Y+184957X0790Y0200     S0      
317PE_RX1_DR0_P     VIA        MD0100PA00X+002000Y+164389               S0      
317PE_RX1_DR0_P     VIA        MD0100PA00X+087294Y+185019               S0      
327PE_TX4_DR0_N                       A01X+000886Y+169741X0980Y0200     S0      
327PE_TX4_DR0_N                       A01X+088268Y+192516X0790Y0200     S0      
317PE_TX4_DR0_N     VIA        MD0100PA00X+002753Y+169758               S0      
317PE_TX4_DR0_N     VIA        MD0100PA00X+086744Y+192513               S0      
327PE_TX4_DR0_P                       A01X+000886Y+170056X0980Y0200     S0      
327PE_TX4_DR0_P                       A01X+088268Y+192831X0790Y0200     S0      
317PE_TX4_DR0_P     VIA        MD0100PA00X+002753Y+170078               S0      
317PE_TX4_DR0_P     VIA        MD0100PA00X+086744Y+192833               S0      
327PE_RX4_DR0_N                       A08X+000886Y+169111X0980Y0200     S0      
327PE_RX4_DR0_N                       A01X+088268Y+193461X0790Y0200     S0      
317PE_RX4_DR0_N     VIA        MD0100PA00X+002000Y+169108               S0      
317PE_RX4_DR0_N     VIA        MD0100PA00X+087294Y+193398               S0      
327PE_RX4_DR0_P                       A08X+000886Y+169426X0980Y0200     S0      
327PE_RX4_DR0_P                       A01X+088268Y+193776X0790Y0200     S0      
317PE_RX4_DR0_P     VIA        MD0100PA00X+002000Y+169428               S0      
317PE_RX4_DR0_P     VIA        MD0100PA00X+087294Y+193838               S0      
317SCL_DR0_R                    D0220PA01X+085520Y+193580               S0      
327SCL_DR0_R                          A01X+088268Y+194406X0790Y0200     S0      
317SCL_DR0_R        VIA        MD0280PA01X+086224Y+193433               S0      
317SDA_DR0_R                    D0220PA01X+085520Y+194080               S0      
327SDA_DR0_R                          A01X+088268Y+194721X0790Y0200     S0      
317SDA_DR0_R        VIA        MD0280PA01X+086224Y+194183               S0      
317DUALPORTEN#0                 D0220PA01X+085130Y+194520               S0      
317DUALPORTEN#0                 D0220PA01X+085130Y+194970               S0      
327DUALPORTEN#0                       A01X+088268Y+195036X0790Y0200     S0      
317DUALPORTEN#0     VIA        MD0280PA01X+085690Y+194760               S0      
317SSD0_CLK0_OE_N               D0220PA01X+042470Y+171850               S0      
317SSD0_CLK0_OE_N               D0220PA01X+042900Y+171830               S0      
327SSD0_CLK0_OE_N                     A01X+089360Y+189597X0810Y0260     S0      
317SSD0_CLK0_OE_N   VIA        MD0280PA01X+043400Y+171825               S0      
317SSD_PRSNT_NET0               D0220PA01X+042470Y+171050               S0      
317SSD_PRSNT_NET0               D0220PA01X+042900Y+171030               S0      
327SSD_PRSNT_NET0                     A01X+089360Y+192597X0810Y0260     S0      
317SSD_PRSNT_NET0   VIA        MD0280PA01X+043390Y+171025               S0      
317SSD_ACT_DR0                  D0220PA01X+089880Y+177270               S0      
317SSD_ACT_DR0                  D0220PA01X+090630Y+176850               S0      
327SSD_ACT_DR0                        A01X+089360Y+193096X0810Y0260     S0      
317SSD_ACT_DR0      VIA        MD0280PA01X+090373Y+177323               S0      
317SSD_ACT_DR0      VIA        MD0100PA00X+089555Y+177285               S0      
317SSD_ACT_DR0      VIA        MD0100PA00X+089994Y+193096               S0      
32712V_PRECH_SSD0                     A01X+087175Y+196550X0450Y1100     S0      
32712V_PRECH_SSD0                     A01X+089360Y+194097X0810Y0260     S0      
31712V_PRECH_SSD0   VIA        MD0280PA01X+087175Y+197550               S0      
327P12V_SSD0                          A01X+082550Y+195702X0830Y0570     S0      
327P12V_SSD0                          A01X+083800Y+195702X0830Y0570     S0      
327P12V_SSD0                          A01X+085325Y+196550X0450Y1100     S0      
327P12V_SSD0                          A01X+082244Y+193411X0650Y0250     S0      
327P12V_SSD0                          A01X+082244Y+193911X0650Y0250     S0      
327P12V_SSD0                          A01X+082244Y+194411X0650Y0250     S0      
327P12V_SSD0                          A01X+082244Y+194911X0650Y0250     S0      
327P12V_SSD0                          A01X+081534Y+196701X0550Y0450     S0      
317P12V_SSD0                    D0340PA01X+084650Y+196170               S0      
317P12V_SSD0                    D0240PA01X+086250Y+195510               S0      
327P12V_SSD0                          A01X+089360Y+194597X0810Y0260     S0      
327P12V_SSD0                          A01X+089360Y+195097X0810Y0260     S0      
317P12V_SSD0        VIA        MD0280PA01X+083500Y+194100               S0      
317P12V_SSD0        VIA        MD0280PA01X+083580Y+194850               S0      
317P12V_SSD0        VIA        MD0100PA00X+086200Y+196050               S0      
317P12V_SSD0        VIA        MD0100PA00X+086200Y+196990               S0      
317P12V_SSD0        VIA        MD0100PA00X+087950Y+197000               S0      
317P12V_SSD0        VIA        MD0100PA00X+088000Y+195550               S0      
327PE_TX2_DR0_N                       A01X+000886Y+167221X0980Y0200     S0      
327PE_TX2_DR0_N                       A01X+088268Y+188736X0790Y0200     S0      
317PE_TX2_DR0_N     VIA        MD0100PA00X+002753Y+167238               S0      
317PE_TX2_DR0_N     VIA        MD0100PA00X+086744Y+188734               S0      
327PE_TX2_DR0_P                       A01X+000886Y+167536X0980Y0200     S0      
327PE_TX2_DR0_P                       A01X+088268Y+189051X0790Y0200     S0      
317PE_TX2_DR0_P     VIA        MD0100PA00X+002753Y+167558               S0      
317PE_TX2_DR0_P     VIA        MD0100PA00X+086744Y+189054               S0      
327PE_RX2_DR0_N                       A08X+000886Y+166591X0980Y0200     S0      
327PE_RX2_DR0_N                       A01X+088268Y+189681X0790Y0200     S0      
317PE_RX2_DR0_N     VIA        MD0100PA00X+002000Y+166589               S0      
317PE_RX2_DR0_N     VIA        MD0100PA00X+087294Y+189619               S0      
327PE_RX2_DR0_P                       A08X+000886Y+166906X0980Y0200     S0      
327PE_RX2_DR0_P                       A01X+088268Y+189996X0790Y0200     S0      
317PE_RX2_DR0_P     VIA        MD0100PA00X+002000Y+166909               S0      
317PE_RX2_DR0_P     VIA        MD0100PA00X+087294Y+190059               S0      
327PE_TX3_DR0_N                       A01X+000886Y+168481X0980Y0200     S0      
327PE_TX3_DR0_N                       A01X+088268Y+190626X0790Y0200     S0      
317PE_TX3_DR0_N     VIA        MD0100PA00X+002753Y+168498               S0      
317PE_TX3_DR0_N     VIA        MD0100PA00X+086744Y+190624               S0      
327PE_TX3_DR0_P                       A01X+000886Y+168796X0980Y0200     S0      
327PE_TX3_DR0_P                       A01X+088268Y+190941X0790Y0200     S0      
317PE_TX3_DR0_P     VIA        MD0100PA00X+002753Y+168818               S0      
317PE_TX3_DR0_P     VIA        MD0100PA00X+086744Y+190944               S0      
327PE_RX3_DR0_N                       A08X+000886Y+167851X0980Y0200     S0      
327PE_RX3_DR0_N                       A01X+088268Y+191571X0790Y0200     S0      
317PE_RX3_DR0_N     VIA        MD0100PA00X+002000Y+167849               S0      
317PE_RX3_DR0_N     VIA        MD0100PA00X+087294Y+191508               S0      
327PE_RX3_DR0_P                       A08X+000886Y+168166X0980Y0200     S0      
327PE_RX3_DR0_P                       A01X+088268Y+191886X0790Y0200     S0      
317PE_RX3_DR0_P     VIA        MD0100PA00X+002000Y+168169               S0      
317PE_RX3_DR0_P     VIA        MD0100PA00X+087294Y+191948               S0      
317NNAME00143                   D0220PA01X+035950Y+123720               S0      
327NNAME00143                         A01X+007721Y+134807X0790Y0200     S0      
317NNAME00143       VIA        MD0100PA00X+012950Y+134802               S0      
317NNAME00143       VIA        MD0100PA00X+006800Y+134809               S0      
317NNAME00144                   D0220PA01X+035550Y+123720               S0      
327NNAME00144                         A01X+007721Y+134492X0790Y0200     S0      
317NNAME00144       VIA        MD0100PA00X+012950Y+134482               S0      
317NNAME00144       VIA        MD0100PA00X+006800Y+134490               S0      
327SSD11_PERST_N                      A08X+000886Y+109426X0980Y0200     S0      
327SSD11_PERST_N                      A01X+007721Y+133862X0790Y0200     S0      
327SSD11_PERST_N                      A01X+007721Y+133547X0790Y0200     S0      
317SSD11_PERST_N    VIA        MD0280PA01X+004229Y+110429               S0      
317SSD11_PERST_N    VIA        MD0100PA00X+003370Y+130178               S0      
317SSD11_PERST_N    VIA        MD0100PA00X+004229Y+108950               S0      
317SSD11_PERST_N    VIA        MD0100PA00X+007100Y+133549               S0      
317NNAME00145                   D0220PA01X+034450Y+123720               S0      
327NNAME00145                         A01X+008976Y+138114X0790Y0200     S0      
317NNAME00146                   D0220PA01X+034050Y+123720               S0      
327NNAME00146                         A01X+008976Y+137799X0790Y0200     S0      
327PE_TX1_DR11_N                      A01X+000886Y+131473X0980Y0200     S0      
327PE_TX1_DR11_N                      A01X+008976Y+137169X0790Y0200     S0      
317PE_TX1_DR11_N    VIA        MD0100PA00X+010500Y+137172               S0      
317PE_TX1_DR11_N    VIA        MD0100PA00X+002753Y+131491               S0      
327PE_TX1_DR11_P                      A01X+000886Y+131788X0980Y0200     S0      
327PE_TX1_DR11_P                      A01X+008976Y+136854X0790Y0200     S0      
317PE_TX1_DR11_P    VIA        MD0100PA00X+010500Y+136852               S0      
317PE_TX1_DR11_P    VIA        MD0100PA00X+002753Y+131811               S0      
327PE_RX1_DR11_N                      A08X+000886Y+132103X0980Y0200     S0      
327PE_RX1_DR11_N                      A01X+008976Y+136224X0790Y0200     S0      
317PE_RX1_DR11_N    VIA        MD0100PA00X+002000Y+132101               S0      
317PE_RX1_DR11_N    VIA        MD0100PA00X+009950Y+136287               S0      
327PE_RX1_DR11_P                      A08X+000886Y+132418X0980Y0200     S0      
327PE_RX1_DR11_P                      A01X+008976Y+135910X0790Y0200     S0      
317PE_RX1_DR11_P    VIA        MD0100PA00X+002000Y+132421               S0      
317PE_RX1_DR11_P    VIA        MD0100PA00X+009950Y+135847               S0      
327PE_TX4_DR11_N                      A01X+000886Y+135253X0980Y0200     S0      
327PE_TX4_DR11_N                      A01X+008976Y+128350X0790Y0200     S0      
317PE_TX4_DR11_N    VIA        MD0100PA00X+010500Y+128353               S0      
317PE_TX4_DR11_N    VIA        MD0100PA00X+002753Y+135270               S0      
327PE_TX4_DR11_P                      A01X+000886Y+135568X0980Y0200     S0      
327PE_TX4_DR11_P                      A01X+008976Y+128035X0790Y0200     S0      
317PE_TX4_DR11_P    VIA        MD0100PA00X+010500Y+128033               S0      
317PE_TX4_DR11_P    VIA        MD0100PA00X+002753Y+135590               S0      
327PE_RX4_DR11_N                      A08X+000886Y+135883X0980Y0200     S0      
327PE_RX4_DR11_N                      A01X+008976Y+127405X0790Y0200     S0      
317PE_RX4_DR11_N    VIA        MD0100PA00X+002000Y+135880               S0      
317PE_RX4_DR11_N    VIA        MD0100PA00X+009950Y+127468               S0      
327PE_RX4_DR11_P                      A08X+000886Y+136198X0980Y0200     S0      
327PE_RX4_DR11_P                      A01X+008976Y+127091X0790Y0200     S0      
317PE_RX4_DR11_P    VIA        MD0100PA00X+002000Y+136200               S0      
317PE_RX4_DR11_P    VIA        MD0100PA00X+009950Y+127028               S0      
317SCL_DR11_R                   D0220PA01X+011580Y+126550               S0      
327SCL_DR11_R                         A01X+008976Y+126461X0790Y0200     S0      
317SCL_DR11_R       VIA        MD0280PA01X+010800Y+126704               S0      
317SDA_DR11_R                   D0220PA01X+011580Y+126050               S0      
327SDA_DR11_R                         A01X+008976Y+126146X0790Y0200     S0      
317SDA_DR11_R       VIA        MD0280PA01X+010800Y+125954               S0      
317DUALPORTEN#11                D0220PA01X+012150Y+125550               S0      
317DUALPORTEN#11                D0220PA01X+012600Y+125550               S0      
327DUALPORTEN#11                      A01X+008976Y+125831X0790Y0200     S0      
317DUALPORTEN#11    VIA        MD0280PA01X+011630Y+125550               S0      
317NNAME00147                   D0220PA01X+034700Y+125620               S0      
317NNAME00147                   D0220PA01X+034720Y+126050               S0      
327NNAME00147                         A01X+007884Y+131270X0810Y0260     S0      
317NNAME00147       VIA        MD0280PA01X+034725Y+126550               S0      
317NNAME00148                   D0220PA01X+035500Y+125620               S0      
317NNAME00148                   D0220PA01X+035520Y+126050               S0      
327NNAME00148                         A01X+007884Y+128270X0810Y0260     S0      
317NNAME00148       VIA        MD0280PA01X+035503Y+126540               S0      
317SSD_ACT_DR11                 D0220PA01X+007675Y+145515               S0      
317SSD_ACT_DR11                 D0220PA01X+007675Y+145081               S0      
327SSD_ACT_DR11                       A01X+007884Y+127770X0810Y0260     S0      
317SSD_ACT_DR11     VIA        MD0280PA08X+007939Y+132708               S0      
317SSD_ACT_DR11     VIA        MD0100PA00X+007250Y+127770               S0      
317SSD_ACT_DR11     VIA        MD0100PA00X+007300Y+145510               S0      
327NNAME00149                         A01X+006815Y+121870X0450Y1100     S0      
327NNAME00149                         A01X+007884Y+126770X0810Y0260     S0      
317NNAME00149       VIA        MD0280PA01X+006815Y+120820               S0      
327P12V_SSD11                         A01X+010640Y+124132X0830Y0570     S0      
327P12V_SSD11                         A01X+010640Y+123288X0830Y0570     S0      
327P12V_SSD11                         A01X+008665Y+121870X0450Y1100     S0      
327P12V_SSD11                         A01X+011720Y+124410X0650Y0250     S0      
327P12V_SSD11                         A01X+011720Y+123910X0650Y0250     S0      
327P12V_SSD11                         A01X+011720Y+123410X0650Y0250     S0      
327P12V_SSD11                         A01X+011720Y+122910X0650Y0250     S0      
327P12V_SSD11                         A01X+009750Y+121180X0450Y0550     S0      
317P12V_SSD11                   D0340PA01X+009760Y+122920               S0      
317P12V_SSD11                   D0240PA01X+009840Y+124660               S0      
327P12V_SSD11                         A01X+007884Y+126270X0810Y0260     S0      
327P12V_SSD11                         A01X+007884Y+125770X0810Y0260     S0      
317P12V_SSD11       VIA        MD0280PA01X+008300Y+120860               S0      
317P12V_SSD11       VIA        MD0280PA01X+009080Y+120860               S0      
327PE_TX2_DR11_N                      A01X+000886Y+132733X0980Y0200     S0      
327PE_TX2_DR11_N                      A01X+008976Y+132130X0790Y0200     S0      
317PE_TX2_DR11_N    VIA        MD0100PA00X+010500Y+132132               S0      
317PE_TX2_DR11_N    VIA        MD0100PA00X+002753Y+132751               S0      
327PE_TX2_DR11_P                      A01X+000886Y+133048X0980Y0200     S0      
327PE_TX2_DR11_P                      A01X+008976Y+131815X0790Y0200     S0      
317PE_TX2_DR11_P    VIA        MD0100PA00X+010500Y+131812               S0      
317PE_TX2_DR11_P    VIA        MD0100PA00X+002753Y+133071               S0      
327PE_RX2_DR11_N                      A08X+000886Y+133363X0980Y0200     S0      
327PE_RX2_DR11_N                      A01X+008976Y+131185X0790Y0200     S0      
317PE_RX2_DR11_N    VIA        MD0100PA00X+002000Y+133360               S0      
317PE_RX2_DR11_N    VIA        MD0100PA00X+009950Y+131248               S0      
327PE_RX2_DR11_P                      A08X+000886Y+133678X0980Y0200     S0      
327PE_RX2_DR11_P                      A01X+008976Y+130870X0790Y0200     S0      
317PE_RX2_DR11_P    VIA        MD0100PA00X+002000Y+133680               S0      
317PE_RX2_DR11_P    VIA        MD0100PA00X+009950Y+130808               S0      
327PE_TX3_DR11_N                      A01X+000886Y+133993X0980Y0200     S0      
327PE_TX3_DR11_N                      A01X+008976Y+130240X0790Y0200     S0      
317PE_TX3_DR11_N    VIA        MD0100PA00X+010500Y+130243               S0      
317PE_TX3_DR11_N    VIA        MD0100PA00X+002753Y+134011               S0      
327PE_TX3_DR11_P                      A01X+000886Y+134308X0980Y0200     S0      
327PE_TX3_DR11_P                      A01X+008976Y+129925X0790Y0200     S0      
317PE_TX3_DR11_P    VIA        MD0100PA00X+010500Y+129923               S0      
317PE_TX3_DR11_P    VIA        MD0100PA00X+002753Y+134331               S0      
327PE_RX3_DR11_N                      A08X+000886Y+134623X0980Y0200     S0      
327PE_RX3_DR11_N                      A01X+008976Y+129295X0790Y0200     S0      
317PE_RX3_DR11_N    VIA        MD0100PA00X+002000Y+134620               S0      
317PE_RX3_DR11_N    VIA        MD0100PA00X+009950Y+129358               S0      
327PE_RX3_DR11_P                      A08X+000886Y+134938X0980Y0200     S0      
327PE_RX3_DR11_P                      A01X+008976Y+128980X0790Y0200     S0      
317PE_RX3_DR11_P    VIA        MD0100PA00X+002000Y+134940               S0      
317PE_RX3_DR11_P    VIA        MD0100PA00X+009950Y+128918               S0      
317NNAME00150                   D0220PA01X+035950Y+086570               S0      
327NNAME00150                         A01X+007721Y+094256X0790Y0200     S0      
317NNAME00150       VIA        MD0100PA00X+016700Y+094251               S0      
317NNAME00150       VIA        MD0100PA00X+006800Y+094258               S0      
317NNAME00151                   D0220PA01X+035550Y+086570               S0      
327NNAME00151                         A01X+007721Y+093941X0790Y0200     S0      
317NNAME00151       VIA        MD0100PA00X+016700Y+093931               S0      
317NNAME00151       VIA        MD0100PA00X+006800Y+093938               S0      
327SSD12_PERST_N                      A08X+000886Y+112576X0980Y0200     S0      
327SSD12_PERST_N                      A01X+007721Y+093311X0790Y0200     S0      
327SSD12_PERST_N                      A01X+007721Y+092996X0790Y0200     S0      
317SSD12_PERST_N    VIA        MD0280PA01X+004184Y+111555               S0      
317SSD12_PERST_N    VIA        MD0100PA00X+003233Y+112200               S0      
317SSD12_PERST_N    VIA        MD0100PA00X+004229Y+108550               S0      
317SSD12_PERST_N    VIA        MD0100PA00X+007100Y+092550               S0      
317NNAME00152                   D0220PA01X+034450Y+086570               S0      
327NNAME00152                         A01X+008976Y+097563X0790Y0200     S0      
317NNAME00153                   D0220PA01X+034050Y+086570               S0      
327NNAME00153                         A01X+008976Y+097248X0790Y0200     S0      
327PE_TX1_DR12_N                      A01X+000886Y+084387X0980Y0200     S0      
327PE_TX1_DR12_N                      A01X+008976Y+096618X0790Y0200     S0      
317PE_TX1_DR12_N    VIA        MD0100PA00X+010500Y+096621               S0      
317PE_TX1_DR12_N    VIA        MD0100PA00X+002753Y+084364               S0      
327PE_TX1_DR12_P                      A01X+000886Y+084702X0980Y0200     S0      
327PE_TX1_DR12_P                      A01X+008976Y+096303X0790Y0200     S0      
317PE_TX1_DR12_P    VIA        MD0100PA00X+010500Y+096301               S0      
317PE_TX1_DR12_P    VIA        MD0100PA00X+002753Y+084684               S0      
327PE_RX1_DR12_N                      A08X+000886Y+083757X0980Y0200     S0      
327PE_RX1_DR12_N                      A01X+008976Y+095673X0790Y0200     S0      
317PE_RX1_DR12_N    VIA        MD0100PA00X+002000Y+083754               S0      
317PE_RX1_DR12_N    VIA        MD0100PA00X+009950Y+095736               S0      
327PE_RX1_DR12_P                      A08X+000886Y+084072X0980Y0200     S0      
327PE_RX1_DR12_P                      A01X+008976Y+095358X0790Y0200     S0      
317PE_RX1_DR12_P    VIA        MD0100PA00X+002000Y+084074               S0      
317PE_RX1_DR12_P    VIA        MD0100PA00X+009950Y+095296               S0      
327PE_TX4_DR12_N                      A01X+000886Y+088166X0980Y0200     S0      
327PE_TX4_DR12_N                      A01X+008976Y+087799X0790Y0200     S0      
317PE_TX4_DR12_N    VIA        MD0100PA00X+010500Y+087802               S0      
317PE_TX4_DR12_N    VIA        MD0100PA00X+002753Y+088149               S0      
327PE_TX4_DR12_P                      A01X+000886Y+088481X0980Y0200     S0      
327PE_TX4_DR12_P                      A01X+008976Y+087484X0790Y0200     S0      
317PE_TX4_DR12_P    VIA        MD0100PA00X+010500Y+087482               S0      
317PE_TX4_DR12_P    VIA        MD0100PA00X+002753Y+088469               S0      
327PE_RX4_DR12_N                      A08X+000886Y+087536X0980Y0200     S0      
327PE_RX4_DR12_N                      A01X+008976Y+086854X0790Y0200     S0      
317PE_RX4_DR12_N    VIA        MD0100PA00X+002000Y+087534               S0      
317PE_RX4_DR12_N    VIA        MD0100PA00X+009950Y+086917               S0      
327PE_RX4_DR12_P                      A08X+000886Y+087851X0980Y0200     S0      
327PE_RX4_DR12_P                      A01X+008976Y+086539X0790Y0200     S0      
317PE_RX4_DR12_P    VIA        MD0100PA00X+002000Y+087854               S0      
317PE_RX4_DR12_P    VIA        MD0100PA00X+009950Y+086477               S0      
317SCL_DR12_R                   D0220PA01X+011580Y+086000               S0      
327SCL_DR12_R                         A01X+008976Y+085909X0790Y0200     S0      
317SCL_DR12_R       VIA        MD0280PA01X+010800Y+086152               S0      
317SDA_DR12_R                   D0220PA01X+011580Y+085500               S0      
327SDA_DR12_R                         A01X+008976Y+085595X0790Y0200     S0      
317SDA_DR12_R       VIA        MD0280PA01X+010800Y+085402               S0      
317DUALPORTEN#12                D0220PA01X+012225Y+084895               S0      
317DUALPORTEN#12                D0220PA01X+012680Y+084900               S0      
327DUALPORTEN#12                      A01X+008976Y+085279X0790Y0200     S0      
317DUALPORTEN#12    VIA        MD0280PA01X+011700Y+084940               S0      
317NNAME00154                   D0220PA01X+034700Y+088470               S0      
317NNAME00154                   D0220PA01X+034720Y+088900               S0      
327NNAME00154                         A01X+007884Y+090719X0810Y0260     S0      
317NNAME00154       VIA        MD0280PA01X+034725Y+089400               S0      
317NNAME00155                   D0220PA01X+035500Y+088470               S0      
317NNAME00155                   D0220PA01X+035520Y+088900               S0      
327NNAME00155                         A01X+007884Y+087719X0810Y0260     S0      
317NNAME00155       VIA        MD0280PA01X+035525Y+089390               S0      
317SSD_ACT_DR12                 D0220PA01X+007775Y+104944               S0      
317SSD_ACT_DR12                 D0220PA01X+007775Y+104430               S0      
327SSD_ACT_DR12                       A01X+007884Y+087219X0810Y0260     S0      
317SSD_ACT_DR12     VIA        MD0280PA08X+005600Y+096700               S0      
317SSD_ACT_DR12     VIA        MD0100PA00X+006550Y+092750               S0      
317SSD_ACT_DR12     VIA        MD0100PA00X+007250Y+087219               S0      
317SSD_ACT_DR12     VIA        MD0100PA00X+007400Y+104750               S0      
327NNAME00156                         A01X+007015Y+081320X0450Y1100     S0      
327NNAME00156                         A01X+007884Y+086219X0810Y0260     S0      
317NNAME00156       VIA        MD0280PA01X+007015Y+080315               S0      
327P12V_SSD12                         A01X+010630Y+083562X0830Y0570     S0      
327P12V_SSD12                         A01X+010020Y+082718X0830Y0570     S0      
327P12V_SSD12                         A01X+008865Y+081320X0450Y1100     S0      
327P12V_SSD12                         A01X+011690Y+083860X0650Y0250     S0      
327P12V_SSD12                         A01X+011690Y+083360X0650Y0250     S0      
327P12V_SSD12                         A01X+011690Y+082860X0650Y0250     S0      
327P12V_SSD12                         A01X+011690Y+082360X0650Y0250     S0      
327P12V_SSD12                         A01X+009760Y+080570X0450Y0550     S0      
317P12V_SSD12                   D0340PA01X+010870Y+082310               S0      
317P12V_SSD12                   D0240PA01X+009840Y+084110               S0      
327P12V_SSD12                         A01X+007884Y+085719X0810Y0260     S0      
327P12V_SSD12                         A01X+007884Y+085219X0810Y0260     S0      
317P12V_SSD12       VIA        MD0280PA01X+008130Y+080360               S0      
317P12V_SSD12       VIA        MD0280PA01X+008980Y+080350               S0      
327PE_TX2_DR12_N                      A01X+000886Y+085647X0980Y0200     S0      
327PE_TX2_DR12_N                      A01X+008976Y+091579X0790Y0200     S0      
317PE_TX2_DR12_N    VIA        MD0100PA00X+010500Y+091581               S0      
317PE_TX2_DR12_N    VIA        MD0100PA00X+002753Y+085624               S0      
327PE_TX2_DR12_P                      A01X+000886Y+085962X0980Y0200     S0      
327PE_TX2_DR12_P                      A01X+008976Y+091264X0790Y0200     S0      
317PE_TX2_DR12_P    VIA        MD0100PA00X+010500Y+091261               S0      
317PE_TX2_DR12_P    VIA        MD0100PA00X+002753Y+085944               S0      
327PE_RX2_DR12_N                      A08X+000886Y+085017X0980Y0200     S0      
327PE_RX2_DR12_N                      A01X+008976Y+090634X0790Y0200     S0      
317PE_RX2_DR12_N    VIA        MD0100PA00X+002000Y+085014               S0      
317PE_RX2_DR12_N    VIA        MD0100PA00X+009950Y+090696               S0      
327PE_RX2_DR12_P                      A08X+000886Y+085332X0980Y0200     S0      
327PE_RX2_DR12_P                      A01X+008976Y+090319X0790Y0200     S0      
317PE_RX2_DR12_P    VIA        MD0100PA00X+002000Y+085334               S0      
317PE_RX2_DR12_P    VIA        MD0100PA00X+009950Y+090256               S0      
327PE_TX3_DR12_N                      A01X+000886Y+086906X0980Y0200     S0      
327PE_TX3_DR12_N                      A01X+008976Y+089689X0790Y0200     S0      
317PE_TX3_DR12_N    VIA        MD0100PA00X+010500Y+089691               S0      
317PE_TX3_DR12_N    VIA        MD0100PA00X+002753Y+086884               S0      
327PE_TX3_DR12_P                      A01X+000886Y+087221X0980Y0200     S0      
327PE_TX3_DR12_P                      A01X+008976Y+089374X0790Y0200     S0      
317PE_TX3_DR12_P    VIA        MD0100PA00X+010500Y+089372               S0      
317PE_TX3_DR12_P    VIA        MD0100PA00X+002753Y+087204               S0      
327PE_RX3_DR12_N                      A08X+000886Y+086276X0980Y0200     S0      
327PE_RX3_DR12_N                      A01X+008976Y+088744X0790Y0200     S0      
317PE_RX3_DR12_N    VIA        MD0100PA00X+002000Y+086274               S0      
317PE_RX3_DR12_N    VIA        MD0100PA00X+009950Y+088807               S0      
327PE_RX3_DR12_P                      A08X+000886Y+086591X0980Y0200     S0      
327PE_RX3_DR12_P                      A01X+008976Y+088429X0790Y0200     S0      
317PE_RX3_DR12_P    VIA        MD0100PA00X+002000Y+086594               S0      
317PE_RX3_DR12_P    VIA        MD0100PA00X+009950Y+088367               S0      
317NNAME00157                   D0220PA01X+035950Y+043570               S0      
327NNAME00157                         A01X+007721Y+053705X0790Y0200     S0      
317NNAME00157       VIA        MD0100PA00X+012400Y+053707               S0      
317NNAME00157       VIA        MD0100PA00X+006800Y+053707               S0      
317NNAME00158                   D0220PA01X+035550Y+043570               S0      
327NNAME00158                         A01X+007721Y+053390X0790Y0200     S0      
317NNAME00158       VIA        MD0100PA00X+012400Y+053387               S0      
317NNAME00158       VIA        MD0100PA00X+006800Y+053387               S0      
327SSD13_PERST_N                      A01X+000886Y+075253X0980Y0200     S0      
327SSD13_PERST_N                      A01X+007721Y+052760X0790Y0200     S0      
327SSD13_PERST_N                      A01X+007721Y+052445X0790Y0200     S0      
317SSD13_PERST_N    VIA        MD0280PA01X+004190Y+071696               S0      
317SSD13_PERST_N    VIA        MD0100PA00X+004800Y+064950               S0      
317SSD13_PERST_N    VIA        MD0100PA00X+007100Y+052446               S0      
317NNAME00159                   D0220PA01X+034450Y+043570               S0      
327NNAME00159                         A01X+008976Y+057012X0790Y0200     S0      
317NNAME00160                   D0220PA01X+034050Y+043570               S0      
327NNAME00160                         A01X+008976Y+056697X0790Y0200     S0      
327PE_TX1_DR13_N                      A01X+000886Y+066434X0980Y0200     S0      
327PE_TX1_DR13_N                      A01X+008976Y+056067X0790Y0200     S0      
317PE_TX1_DR13_N    VIA        MD0100PA00X+010500Y+056069               S0      
317PE_TX1_DR13_N    VIA        MD0100PA00X+002753Y+066452               S0      
327PE_TX1_DR13_P                      A01X+000886Y+066749X0980Y0200     S0      
327PE_TX1_DR13_P                      A01X+008976Y+055752X0790Y0200     S0      
317PE_TX1_DR13_P    VIA        MD0100PA00X+010500Y+055749               S0      
317PE_TX1_DR13_P    VIA        MD0100PA00X+002753Y+066772               S0      
327PE_RX1_DR13_N                      A08X+000886Y+065804X0980Y0200     S0      
327PE_RX1_DR13_N                      A01X+008976Y+055122X0790Y0200     S0      
317PE_RX1_DR13_N    VIA        MD0100PA00X+002000Y+065801               S0      
317PE_RX1_DR13_N    VIA        MD0100PA00X+009950Y+055184               S0      
327PE_RX1_DR13_P                      A08X+000886Y+066119X0980Y0200     S0      
327PE_RX1_DR13_P                      A01X+008976Y+054807X0790Y0200     S0      
317PE_RX1_DR13_P    VIA        MD0100PA00X+002000Y+066121               S0      
317PE_RX1_DR13_P    VIA        MD0100PA00X+009950Y+054745               S0      
327PE_TX4_DR13_N                      A01X+000886Y+070213X0980Y0200     S0      
327PE_TX4_DR13_N                      A01X+008976Y+047248X0790Y0200     S0      
317PE_TX4_DR13_N    VIA        MD0100PA00X+010500Y+047251               S0      
317PE_TX4_DR13_N    VIA        MD0100PA00X+002753Y+070231               S0      
327PE_TX4_DR13_P                      A01X+000886Y+070528X0980Y0200     S0      
327PE_TX4_DR13_P                      A01X+008976Y+046933X0790Y0200     S0      
317PE_TX4_DR13_P    VIA        MD0100PA00X+010500Y+046930               S0      
317PE_TX4_DR13_P    VIA        MD0100PA00X+002753Y+070551               S0      
327PE_RX4_DR13_N                      A08X+000886Y+069584X0980Y0200     S0      
327PE_RX4_DR13_N                      A01X+008976Y+046303X0790Y0200     S0      
317PE_RX4_DR13_N    VIA        MD0100PA00X+002000Y+069581               S0      
317PE_RX4_DR13_N    VIA        MD0100PA00X+009950Y+046366               S0      
327PE_RX4_DR13_P                      A08X+000886Y+069899X0980Y0200     S0      
327PE_RX4_DR13_P                      A01X+008976Y+045988X0790Y0200     S0      
317PE_RX4_DR13_P    VIA        MD0100PA00X+002000Y+069901               S0      
317PE_RX4_DR13_P    VIA        MD0100PA00X+009950Y+045926               S0      
317SCL_DR13_R                   D0220PA01X+011580Y+045450               S0      
327SCL_DR13_R                         A01X+008976Y+045358X0790Y0200     S0      
317SCL_DR13_R       VIA        MD0280PA01X+010800Y+045601               S0      
317SDA_DR13_R                   D0220PA01X+011580Y+044950               S0      
327SDA_DR13_R                         A01X+008976Y+045043X0790Y0200     S0      
317SDA_DR13_R       VIA        MD0280PA01X+010800Y+044851               S0      
317DUALPORTEN#13                D0220PA01X+012080Y+044450               S0      
317DUALPORTEN#13                D0220PA01X+012530Y+044450               S0      
327DUALPORTEN#13                      A01X+008976Y+044728X0790Y0200     S0      
317DUALPORTEN#13    VIA        MD0280PA01X+011580Y+044460               S0      
317NNAME00161                   D0220PA01X+034700Y+045470               S0      
317NNAME00161                   D0220PA01X+034720Y+045900               S0      
327NNAME00161                         A01X+007884Y+050167X0810Y0260     S0      
317NNAME00161       VIA        MD0280PA01X+034725Y+046400               S0      
317NNAME00162                   D0220PA01X+035500Y+045470               S0      
317NNAME00162                   D0220PA01X+035520Y+045900               S0      
327NNAME00162                         A01X+007884Y+047167X0810Y0260     S0      
317NNAME00162       VIA        MD0280PA01X+035525Y+046390               S0      
317SSD_ACT_DR13                 D0220PA01X+007855Y+064523               S0      
317SSD_ACT_DR13                 D0220PA01X+007675Y+063978               S0      
327SSD_ACT_DR13                       A01X+007884Y+046667X0810Y0260     S0      
317SSD_ACT_DR13     VIA        MD0280PA01X+007471Y+065190               S0      
317SSD_ACT_DR13     VIA        MD0100PA00X+007050Y+064850               S0      
317SSD_ACT_DR13     VIA        MD0100PA00X+007250Y+046667               S0      
327NNAME00163                         A01X+006755Y+040720X0450Y1100     S0      
327NNAME00163                         A01X+007884Y+045667X0810Y0260     S0      
317NNAME00163       VIA        MD0280PA01X+006530Y+039680               S0      
327P12V_SSD13                         A01X+010630Y+043052X0830Y0570     S0      
327P12V_SSD13                         A01X+009960Y+042198X0830Y0570     S0      
327P12V_SSD13                         A01X+008605Y+040720X0450Y1100     S0      
327P12V_SSD13                         A01X+011690Y+043310X0650Y0250     S0      
327P12V_SSD13                         A01X+011690Y+042810X0650Y0250     S0      
327P12V_SSD13                         A01X+011690Y+042310X0650Y0250     S0      
327P12V_SSD13                         A01X+011690Y+041810X0650Y0250     S0      
327P12V_SSD13                         A01X+009743Y+040103X0450Y0550     S0      
317P12V_SSD13                   D0340PA01X+010840Y+041760               S0      
317P12V_SSD13                   D0240PA01X+009840Y+043560               S0      
327P12V_SSD13                         A01X+007884Y+045167X0810Y0260     S0      
327P12V_SSD13                         A01X+007884Y+044667X0810Y0260     S0      
317P12V_SSD13       VIA        MD0280PA01X+008030Y+039770               S0      
317P12V_SSD13       VIA        MD0280PA01X+009080Y+039770               S0      
327PE_TX2_DR13_N                      A01X+000886Y+067694X0980Y0200     S0      
327PE_TX2_DR13_N                      A01X+008976Y+051028X0790Y0200     S0      
317PE_TX2_DR13_N    VIA        MD0100PA00X+010500Y+051030               S0      
317PE_TX2_DR13_N    VIA        MD0100PA00X+002753Y+067711               S0      
327PE_TX2_DR13_P                      A01X+000886Y+068009X0980Y0200     S0      
327PE_TX2_DR13_P                      A01X+008976Y+050713X0790Y0200     S0      
317PE_TX2_DR13_P    VIA        MD0100PA00X+010500Y+050710               S0      
317PE_TX2_DR13_P    VIA        MD0100PA00X+002753Y+068031               S0      
327PE_RX2_DR13_N                      A08X+000886Y+067064X0980Y0200     S0      
327PE_RX2_DR13_N                      A01X+008976Y+050083X0790Y0200     S0      
317PE_RX2_DR13_N    VIA        MD0100PA00X+002000Y+067061               S0      
317PE_RX2_DR13_N    VIA        MD0100PA00X+009950Y+050145               S0      
327PE_RX2_DR13_P                      A08X+000886Y+067379X0980Y0200     S0      
327PE_RX2_DR13_P                      A01X+008976Y+049768X0790Y0200     S0      
317PE_RX2_DR13_P    VIA        MD0100PA00X+002000Y+067381               S0      
317PE_RX2_DR13_P    VIA        MD0100PA00X+009950Y+049705               S0      
327PE_TX3_DR13_N                      A01X+000886Y+068954X0980Y0200     S0      
327PE_TX3_DR13_N                      A01X+008976Y+049138X0790Y0200     S0      
317PE_TX3_DR13_N    VIA        MD0100PA00X+010500Y+049140               S0      
317PE_TX3_DR13_N    VIA        MD0100PA00X+002753Y+068971               S0      
327PE_TX3_DR13_P                      A01X+000886Y+069269X0980Y0200     S0      
327PE_TX3_DR13_P                      A01X+008976Y+048823X0790Y0200     S0      
317PE_TX3_DR13_P    VIA        MD0100PA00X+010500Y+048820               S0      
317PE_TX3_DR13_P    VIA        MD0100PA00X+002753Y+069291               S0      
327PE_RX3_DR13_N                      A08X+000886Y+068324X0980Y0200     S0      
327PE_RX3_DR13_N                      A01X+008976Y+048193X0790Y0200     S0      
317PE_RX3_DR13_N    VIA        MD0100PA00X+002000Y+068321               S0      
317PE_RX3_DR13_N    VIA        MD0100PA00X+009950Y+048255               S0      
327PE_RX3_DR13_P                      A08X+000886Y+068639X0980Y0200     S0      
327PE_RX3_DR13_P                      A01X+008976Y+047878X0790Y0200     S0      
317PE_RX3_DR13_P    VIA        MD0100PA00X+002000Y+068641               S0      
317PE_RX3_DR13_P    VIA        MD0100PA00X+009950Y+047815               S0      
317NNAME00164                   D0220PA01X+037600Y+036430               S0      
327NNAME00164                         A01X+007721Y+013154X0790Y0200     S0      
317NNAME00164       VIA        MD0100PA00X+012400Y+013156               S0      
317NNAME00164       VIA        MD0100PA00X+006800Y+013156               S0      
317NNAME00165                   D0220PA01X+038000Y+036430               S0      
327NNAME00165                         A01X+007721Y+012839X0790Y0200     S0      
317NNAME00165       VIA        MD0100PA00X+012400Y+012836               S0      
317NNAME00165       VIA        MD0100PA00X+006800Y+012836               S0      
327SSD14_PERST_N                      A08X+000886Y+073048X0980Y0200     S0      
327SSD14_PERST_N                      A01X+007721Y+012209X0790Y0200     S0      
327SSD14_PERST_N                      A01X+007721Y+011894X0790Y0200     S0      
317SSD14_PERST_N    VIA        MD0280PA01X+011883Y+015256               S0      
317SSD14_PERST_N    VIA        MD0100PA00X+011458Y+013778               S0      
317NNAME00166                   D0220PA01X+039100Y+036430               S0      
327NNAME00166                         A01X+008976Y+016461X0790Y0200     S0      
317NNAME00167                   D0220PA01X+039500Y+036430               S0      
327NNAME00167                         A01X+008976Y+016146X0790Y0200     S0      
327PE_TX1_DR14_N                      A01X+000886Y+060135X0980Y0200     S0      
327PE_TX1_DR14_N                      A01X+008976Y+015516X0790Y0200     S0      
317PE_TX1_DR14_N    VIA        MD0100PA00X+010500Y+015518               S0      
317PE_TX1_DR14_N    VIA        MD0100PA00X+002753Y+060152               S0      
327PE_TX1_DR14_P                      A01X+000886Y+060450X0980Y0200     S0      
327PE_TX1_DR14_P                      A01X+008976Y+015201X0790Y0200     S0      
317PE_TX1_DR14_P    VIA        MD0100PA00X+010500Y+015198               S0      
317PE_TX1_DR14_P    VIA        MD0100PA00X+002753Y+060472               S0      
327PE_RX1_DR14_N                      A08X+000886Y+060765X0980Y0200     S0      
327PE_RX1_DR14_N                      A01X+008976Y+014571X0790Y0200     S0      
317PE_RX1_DR14_N    VIA        MD0100PA00X+002000Y+060762               S0      
317PE_RX1_DR14_N    VIA        MD0100PA00X+009950Y+014633               S0      
327PE_RX1_DR14_P                      A08X+000886Y+061080X0980Y0200     S0      
327PE_RX1_DR14_P                      A01X+008976Y+014256X0790Y0200     S0      
317PE_RX1_DR14_P    VIA        MD0100PA00X+002000Y+061082               S0      
317PE_RX1_DR14_P    VIA        MD0100PA00X+009950Y+014193               S0      
327PE_TX4_DR14_N                      A01X+000886Y+063914X0980Y0200     S0      
327PE_TX4_DR14_N                      A01X+008976Y+006697X0790Y0200     S0      
317PE_TX4_DR14_N    VIA        MD0100PA00X+010500Y+006699               S0      
317PE_TX4_DR14_N    VIA        MD0100PA00X+002753Y+063932               S0      
327PE_TX4_DR14_P                      A01X+000886Y+064229X0980Y0200     S0      
327PE_TX4_DR14_P                      A01X+008976Y+006382X0790Y0200     S0      
317PE_TX4_DR14_P    VIA        MD0100PA00X+010500Y+006379               S0      
317PE_TX4_DR14_P    VIA        MD0100PA00X+002753Y+064252               S0      
327PE_RX4_DR14_N                      A08X+000886Y+064544X0980Y0200     S0      
327PE_RX4_DR14_N                      A01X+008976Y+005752X0790Y0200     S0      
317PE_RX4_DR14_N    VIA        MD0100PA00X+002000Y+064542               S0      
317PE_RX4_DR14_N    VIA        MD0100PA00X+009950Y+005824               S0      
327PE_RX4_DR14_P                      A08X+000886Y+064859X0980Y0200     S0      
327PE_RX4_DR14_P                      A01X+008976Y+005437X0790Y0200     S0      
317PE_RX4_DR14_P    VIA        MD0100PA00X+002000Y+064862               S0      
317PE_RX4_DR14_P    VIA        MD0100PA00X+009950Y+005384               S0      
317SCL_DR14_R                   D0220PA01X+011430Y+006580               S0      
327SCL_DR14_R                         A01X+008976Y+004807X0790Y0200     S0      
317SCL_DR14_R       VIA        MD0280PA01X+011320Y+005995               S0      
317SDA_DR14_R                   D0220PA01X+011930Y+006580               S0      
327SDA_DR14_R                         A01X+008976Y+004492X0790Y0200     S0      
317SDA_DR14_R       VIA        MD0280PA01X+012070Y+005995               S0      
317DUALPORTEN#14                D0220PA01X+012160Y+004790               S0      
317DUALPORTEN#14                D0220PA01X+012570Y+004790               S0      
327DUALPORTEN#14                      A01X+008976Y+004177X0790Y0200     S0      
317DUALPORTEN#14    VIA        MD0280PA01X+011280Y+004920               S0      
317NNAME00168                   D0220PA01X+038850Y+034530               S0      
317NNAME00168                   D0220PA01X+038830Y+034100               S0      
327NNAME00168                         A01X+007884Y+009616X0810Y0260     S0      
317NNAME00168       VIA        MD0280PA01X+038825Y+033600               S0      
317NNAME00169                   D0220PA01X+038050Y+034530               S0      
317NNAME00169                   D0220PA01X+038030Y+034100               S0      
327NNAME00169                         A01X+007884Y+006616X0810Y0260     S0      
317NNAME00169       VIA        MD0280PA01X+038025Y+033610               S0      
317SSD_ACT_DR14                 D0220PA01X+007855Y+023972               S0      
317SSD_ACT_DR14                 D0220PA01X+007675Y+023427               S0      
327SSD_ACT_DR14                       A01X+007884Y+006116X0810Y0260     S0      
317SSD_ACT_DR14     VIA        MD0280PA01X+007471Y+024639               S0      
317SSD_ACT_DR14     VIA        MD0100PA00X+007050Y+024299               S0      
317SSD_ACT_DR14     VIA        MD0100PA00X+007250Y+006116               S0      
327NNAME00170                         A01X+010540Y+002385X1100Y0450     S0      
327NNAME00170                         A01X+007884Y+005116X0810Y0260     S0      
317NNAME00170       VIA        MD0280PA01X+009804Y+001414               S0      
327P12V_SSD14                         A01X+015210Y+004832X0830Y0570     S0      
327P12V_SSD14                         A01X+013960Y+004832X0830Y0570     S0      
327P12V_SSD14                         A01X+010540Y+004235X1100Y0450     S0      
327P12V_SSD14                         A01X+016550Y+005900X0650Y0250     S0      
327P12V_SSD14                         A01X+016550Y+005400X0650Y0250     S0      
327P12V_SSD14                         A01X+016550Y+004900X0650Y0250     S0      
327P12V_SSD14                         A01X+016550Y+004400X0650Y0250     S0      
327P12V_SSD14                         A01X+015280Y+003660X0450Y0550     S0      
317P12V_SSD14                   D0220PA01X+038220Y+008470               S0      
317P12V_SSD14                   D0340PA01X+013100Y+005100               S0      
317P12V_SSD14                   D0240PA01X+011570Y+004000               S0      
327P12V_SSD14                         A01X+007884Y+004616X0810Y0260     S0      
327P12V_SSD14                         A01X+007884Y+004116X0810Y0260     S0      
317P12V_SSD14       VIA        MD0280PA01X+013050Y+004540               S0      
317P12V_SSD14       VIA        MD0280PA01X+014600Y+004190               S0      
317P12V_SSD14       VIA        MD0100PA00X+015240Y+004150               S0      
317P12V_SSD14       VIA        MD0100PA00X+038220Y+008150               S0      
317P12V_SSD14       VIA        MD0160PA00X+013610Y+004120               S0      
317P12V_SSD14       VIA        MD0160PA00X+007120Y+003690               S0      
327PE_TX2_DR14_N                      A01X+000886Y+061395X0980Y0200     S0      
327PE_TX2_DR14_N                      A01X+008976Y+010476X0790Y0200     S0      
317PE_TX2_DR14_N    VIA        MD0100PA00X+010500Y+010479               S0      
317PE_TX2_DR14_N    VIA        MD0100PA00X+002753Y+061407               S0      
327PE_TX2_DR14_P                      A01X+000886Y+061709X0980Y0200     S0      
327PE_TX2_DR14_P                      A01X+008976Y+010161X0790Y0200     S0      
317PE_TX2_DR14_P    VIA        MD0100PA00X+010500Y+010159               S0      
317PE_TX2_DR14_P    VIA        MD0100PA00X+002753Y+061727               S0      
327PE_RX2_DR14_N                      A08X+000886Y+062025X0980Y0200     S0      
327PE_RX2_DR14_N                      A01X+008976Y+009532X0790Y0200     S0      
317PE_RX2_DR14_N    VIA        MD0100PA00X+002000Y+062022               S0      
317PE_RX2_DR14_N    VIA        MD0100PA00X+009950Y+009594               S0      
327PE_RX2_DR14_P                      A08X+000886Y+062339X0980Y0200     S0      
327PE_RX2_DR14_P                      A01X+008976Y+009217X0790Y0200     S0      
317PE_RX2_DR14_P    VIA        MD0100PA00X+002000Y+062342               S0      
317PE_RX2_DR14_P    VIA        MD0100PA00X+009950Y+009154               S0      
327PE_TX3_DR14_N                      A01X+000886Y+062654X0980Y0200     S0      
327PE_TX3_DR14_N                      A01X+008976Y+008587X0790Y0200     S0      
317PE_TX3_DR14_N    VIA        MD0100PA00X+010500Y+008589               S0      
317PE_TX3_DR14_N    VIA        MD0100PA00X+002753Y+062672               S0      
327PE_TX3_DR14_P                      A01X+000886Y+062969X0980Y0200     S0      
327PE_TX3_DR14_P                      A01X+008976Y+008272X0790Y0200     S0      
317PE_TX3_DR14_P    VIA        MD0100PA00X+010500Y+008269               S0      
317PE_TX3_DR14_P    VIA        MD0100PA00X+002753Y+062992               S0      
327PE_RX3_DR14_N                      A08X+000886Y+063284X0980Y0200     S0      
327PE_RX3_DR14_N                      A01X+008976Y+007642X0790Y0200     S0      
317PE_RX3_DR14_N    VIA        MD0100PA00X+002000Y+063282               S0      
317PE_RX3_DR14_N    VIA        MD0100PA00X+009950Y+007704               S0      
327PE_RX3_DR14_P                      A08X+000886Y+063599X0980Y0200     S0      
327PE_RX3_DR14_P                      A01X+008976Y+007327X0790Y0200     S0      
317PE_RX3_DR14_P    VIA        MD0100PA00X+002000Y+063602               S0      
317PE_RX3_DR14_P    VIA        MD0100PA00X+009950Y+007264               S0      
327ATTN_LED_DR1_N                     A01X+000886Y+157457X0980Y0200     S0      
327ATTN_LED_DR1_N                     A01X+089125Y+135399X0480Y0160     S0      
317ATTN_LED_DR1_N               D0220PA01X+088739Y+136970               S0      
317ATTN_LED_DR1_N               D0220PA01X+088739Y+136520               S0      
317ATTN_LED_DR1_N   VIA        MD0280PA01X+004286Y+155490               S0      
317ATTN_LED_DR1_N   VIA        MD0100PA00X+004300Y+152600               S0      
317ATTN_LED_DR1_N   VIA        MD0100PA00X+088744Y+137337               S0      
327SSD1_PWREN                         A01X+000886Y+157772X0980Y0200     S0      
317SSD1_PWREN                   D0220PA01X+082100Y+158920               S0      
317SSD1_PWREN                   D0220PA01X+081650Y+158920               S0      
317SSD1_PWREN                   D0220PA01X+081198Y+159428               S0      
317SSD1_PWREN                   D0300PA01X+082788Y+157925               S0      
317SSD1_PWREN       VIA        MD0120PA00X+080776Y+159428               S0      
317SSD1_PWREN       VIA        MD0100PA00X+004264Y+152196               S0      
327PCIE_MATED#_A                      A01X+000886Y+166591X0980Y0200     S0      
327PCIE_MATED#_A                      A01X+004110Y+163365X1100Y0450     S0      
327SSD0_PWREN                         A01X+000886Y+170686X0980Y0200     S0      
317SSD0_PWREN                   D0220PA01X+076924Y+196321               S0      
317SSD0_PWREN                   D0220PA01X+076474Y+196321               S0      
317SSD0_PWREN                   D0220PA01X+076021Y+196828               S0      
317SSD0_PWREN                   D0300PA01X+079271Y+195326               S0      
317SSD0_PWREN       VIA        MD0280PA08X+012200Y+172750               S0      
317SSD0_PWREN       VIA        MD0100PA00X+013700Y+172750               S0      
317SSD0_PWREN       VIA        MD0100PA00X+003590Y+170600               S0      
317SSD0_PWREN       VIA        MD0100PA00X+075600Y+196828               S0      
327ATTN_LED_DR0_N                     A01X+000886Y+171001X0980Y0200     S0      
327ATTN_LED_DR0_N                     A01X+089125Y+175950X0480Y0160     S0      
317ATTN_LED_DR0_N               D0220PA01X+088795Y+177725               S0      
317ATTN_LED_DR0_N               D0220PA01X+088795Y+177325               S0      
317ATTN_LED_DR0_N   VIA        MD0280PA08X+004540Y+171231               S0      
317ATTN_LED_DR0_N   VIA        MD0100PA00X+014083Y+172983               S0      
317ATTN_LED_DR0_N   VIA        MD0100PA00X+003422Y+170900               S0      
317ATTN_LED_DR0_N   VIA        MD0100PA00X+088872Y+178105               S0      
327PE_TX1_DR5_P                       A01X+000886Y+171946X0980Y0200     S0      
327PE_TX1_DR5_P                       A01X+015433Y+183697X0790Y0200     S0      
317PE_TX1_DR5_P     VIA        MD0100PA00X+013909Y+183694               S0      
317PE_TX1_DR5_P     VIA        MD0100PA00X+002753Y+171962               S0      
327PE_TX1_DR5_N                       A01X+000886Y+172261X0980Y0200     S0      
327PE_TX1_DR5_N                       A01X+015433Y+184012X0790Y0200     S0      
317PE_TX1_DR5_N     VIA        MD0100PA00X+013909Y+184014               S0      
317PE_TX1_DR5_N     VIA        MD0100PA00X+002753Y+172282               S0      
327PE_TX2_DR5_P                       A01X+000886Y+173206X0980Y0200     S0      
327PE_TX2_DR5_P                       A01X+015433Y+188736X0790Y0200     S0      
317PE_TX2_DR5_P     VIA        MD0100PA00X+013909Y+188734               S0      
317PE_TX2_DR5_P     VIA        MD0100PA00X+002753Y+173222               S0      
327PE_TX2_DR5_N                       A01X+000886Y+173520X0980Y0200     S0      
327PE_TX2_DR5_N                       A01X+015433Y+189051X0790Y0200     S0      
317PE_TX2_DR5_N     VIA        MD0100PA00X+013909Y+189054               S0      
317PE_TX2_DR5_N     VIA        MD0100PA00X+002753Y+173542               S0      
327PE_TX3_DR5_P                       A01X+000886Y+174465X0980Y0200     S0      
327PE_TX3_DR5_P                       A01X+015433Y+190626X0790Y0200     S0      
317PE_TX3_DR5_P     VIA        MD0100PA00X+013909Y+190624               S0      
317PE_TX3_DR5_P     VIA        MD0100PA00X+002753Y+174482               S0      
327PE_TX3_DR5_N                       A01X+000886Y+174780X0980Y0200     S0      
327PE_TX3_DR5_N                       A01X+015433Y+190941X0790Y0200     S0      
317PE_TX3_DR5_N     VIA        MD0100PA00X+013909Y+190944               S0      
317PE_TX3_DR5_N     VIA        MD0100PA00X+002753Y+174802               S0      
327PE_TX4_DR5_P                       A01X+000886Y+175725X0980Y0200     S0      
327PE_TX4_DR5_P                       A01X+015433Y+192516X0790Y0200     S0      
317PE_TX4_DR5_P     VIA        MD0100PA00X+013909Y+192513               S0      
317PE_TX4_DR5_P     VIA        MD0100PA00X+002753Y+175742               S0      
327PE_TX4_DR5_N                       A01X+000886Y+176040X0980Y0200     S0      
327PE_TX4_DR5_N                       A01X+015433Y+192831X0790Y0200     S0      
317PE_TX4_DR5_N     VIA        MD0100PA00X+013909Y+192833               S0      
317PE_TX4_DR5_N     VIA        MD0100PA00X+002753Y+176062               S0      
327NNAME00171                         A01X+000886Y+177615X0980Y0200     S0      
317NNAME00171                   D0220PA01X+027650Y+171430               S0      
317NNAME00171       VIA        MD0280PA01X+027650Y+170940               S0      
327NNAME00172                         A01X+000886Y+177930X0980Y0200     S0      
317NNAME00172                   D0220PA01X+027250Y+171430               S0      
317NNAME00172       VIA        MD0280PA01X+026900Y+170952               S0      
327NNAME00173                         A01X+000886Y+178560X0980Y0200     S0      
317NNAME00173                   D0220PA01X+028700Y+139580               S0      
317NNAME00173                   D0220PA01X+033080Y+118250               S0      
317NNAME00173                   D0220PA01X+033080Y+168100               S0      
317NNAME00173                   D0220PA01X+028490Y+139020               S0      
317NNAME00173       VIA        MD0120PA00X+031716Y+119344               S0      
317NNAME00173       VIA        MD0100PA00X+024850Y+171301               S0      
317NNAME00173       VIA        MD0100PA00X+028717Y+138000               S0      
317NNAME00173       VIA        MD0100PA00X+031816Y+169244               S0      
327NNAME00174                         A01X+000886Y+178875X0980Y0200     S0      
317NNAME00174                   D0220PA01X+029100Y+139580               S0      
317NNAME00174                   D0220PA01X+033080Y+118650               S0      
317NNAME00174                   D0220PA01X+033080Y+168500               S0      
317NNAME00174                   D0220PA01X+029310Y+139020               S0      
317NNAME00174       VIA        MD0120PA00X+032466Y+119344               S0      
317NNAME00174       VIA        MD0100PA00X+024850Y+171681               S0      
317NNAME00174       VIA        MD0100PA00X+029097Y+138000               S0      
317NNAME00174       VIA        MD0100PA00X+032566Y+169244               S0      
327NNAME00175                         A01X+000886Y+179505X0980Y0200     S0      
317NNAME00175                   D0220PA01X+095130Y+166850               S0      
317NNAME00175       VIA        MD0120PA00X+043866Y+166900               S0      
317NNAME00175       VIA        MD0100PA00X+025550Y+173857               S0      
327NNAME00176                         A01X+000886Y+179820X0980Y0200     S0      
317NNAME00176                   D0220PA01X+095130Y+166350               S0      
317NNAME00176       VIA        MD0120PA00X+043116Y+166900               S0      
317NNAME00176       VIA        MD0100PA00X+025169Y+173857               S0      
327SSD10_PWREN                        A08X+000886Y+157772X0980Y0200     S0      
317SSD10_PWREN                  D0220PA01X+015853Y+161423               S0      
317SSD10_PWREN                  D0220PA01X+014950Y+161930               S0      
317SSD10_PWREN                  D0220PA01X+015400Y+161930               S0      
317SSD10_PWREN                  D0300PA01X+014603Y+162935               S0      
317SSD10_PWREN      VIA        MD0280PA08X+005574Y+157859               S0      
317SSD10_PWREN      VIA        MD0100PA00X+006453Y+159102               S0      
327NNAME00177                         A08X+000886Y+158087X0980Y0200     S0      
327NNAME00177                         A01X+008820Y+184715X0160Y0480     S0      
317NNAME00177                   D0220PA01X+008780Y+183630               S0      
317NNAME00177                   D0220PA01X+008780Y+184060               S0      
317NNAME00177       VIA        MD0280PA08X+005878Y+158583               S0      
317NNAME00177       VIA        MD0100PA00X+006640Y+170690               S0      
317NNAME00177       VIA        MD0100PA00X+007410Y+179620               S0      
317NNAME00177       VIA        MD0100PA00X+008500Y+181710               S0      
327ATTN_LED_DR5_N                     A08X+000886Y+170371X0980Y0200     S0      
327ATTN_LED_DR5_N                     A01X+020760Y+177200X0480Y0160     S0      
317ATTN_LED_DR5_N               D0220PA01X+021600Y+177620               S0      
317ATTN_LED_DR5_N               D0220PA01X+021600Y+177210               S0      
317ATTN_LED_DR5_N   VIA        MD0280PA08X+015790Y+177050               S0      
317ATTN_LED_DR5_N   VIA        MD0100PA00X+015790Y+178015               S0      
327SSD5_PWREN                         A08X+000886Y+170686X0980Y0200     S0      
317SSD5_PWREN                   D0220PA01X+003338Y+197028               S0      
317SSD5_PWREN                   D0220PA01X+004180Y+196400               S0      
317SSD5_PWREN                   D0220PA01X+003730Y+196400               S0      
317SSD5_PWREN                   D0300PA01X+006938Y+195425               S0      
317SSD5_PWREN       VIA        MD0280PA08X+014720Y+175660               S0      
317SSD5_PWREN       VIA        MD0100PA00X+015145Y+181000               S0      
317SSD5_PWREN       VIA        MD0100PA00X+003020Y+197030               S0      
327PE_RX1_DR5_P                       A08X+000886Y+171316X0980Y0200     S0      
327PE_RX1_DR5_P                       A01X+015433Y+184642X0790Y0200     S0      
317PE_RX1_DR5_P     VIA        MD0100PA00X+014460Y+184579               S0      
317PE_RX1_DR5_P     VIA        MD0100PA00X+002000Y+171313               S0      
327PE_RX1_DR5_N                       A08X+000886Y+171631X0980Y0200     S0      
327PE_RX1_DR5_N                       A01X+015433Y+184957X0790Y0200     S0      
317PE_RX1_DR5_N     VIA        MD0100PA00X+014460Y+185019               S0      
317PE_RX1_DR5_N     VIA        MD0100PA00X+002000Y+171633               S0      
327PE_RX2_DR5_P                       A08X+000886Y+172576X0980Y0200     S0      
327PE_RX2_DR5_P                       A01X+015433Y+189681X0790Y0200     S0      
317PE_RX2_DR5_P     VIA        MD0100PA00X+014460Y+189619               S0      
317PE_RX2_DR5_P     VIA        MD0100PA00X+002000Y+172573               S0      
327PE_RX2_DR5_N                       A08X+000886Y+172891X0980Y0200     S0      
327PE_RX2_DR5_N                       A01X+015433Y+189996X0790Y0200     S0      
317PE_RX2_DR5_N     VIA        MD0100PA00X+014460Y+190059               S0      
317PE_RX2_DR5_N     VIA        MD0100PA00X+002000Y+172893               S0      
327PE_RX3_DR5_P                       A08X+000886Y+173835X0980Y0200     S0      
327PE_RX3_DR5_P                       A01X+015433Y+191571X0790Y0200     S0      
317PE_RX3_DR5_P     VIA        MD0100PA00X+014460Y+191508               S0      
317PE_RX3_DR5_P     VIA        MD0100PA00X+002000Y+173833               S0      
327PE_RX3_DR5_N                       A08X+000886Y+174150X0980Y0200     S0      
327PE_RX3_DR5_N                       A01X+015433Y+191886X0790Y0200     S0      
317PE_RX3_DR5_N     VIA        MD0100PA00X+014460Y+191948               S0      
317PE_RX3_DR5_N     VIA        MD0100PA00X+002000Y+174153               S0      
327PE_RX4_DR5_P                       A08X+000886Y+175095X0980Y0200     S0      
327PE_RX4_DR5_P                       A01X+015433Y+193461X0790Y0200     S0      
317PE_RX4_DR5_P     VIA        MD0100PA00X+014460Y+193398               S0      
317PE_RX4_DR5_P     VIA        MD0100PA00X+002000Y+175093               S0      
327PE_RX4_DR5_N                       A08X+000886Y+175410X0980Y0200     S0      
327PE_RX4_DR5_N                       A01X+015433Y+193776X0790Y0200     S0      
317PE_RX4_DR5_N     VIA        MD0100PA00X+014460Y+193838               S0      
317PE_RX4_DR5_N     VIA        MD0100PA00X+002000Y+175413               S0      
327NNAME00178                         A08X+000886Y+176985X0980Y0200     S0      
317NNAME00178                   D0220PA01X+032370Y+057250               S0      
317NNAME00178                   D0220PA01X+033080Y+038100               S0      
317NNAME00178                   D0220PA01X+033080Y+081100               S0      
317NNAME00178                   D0220PA01X+032930Y+057058               S0      
317NNAME00178       VIA        MD0280PA08X+032070Y+039610               S0      
317NNAME00178       VIA        MD0100PA00X+031866Y+039144               S0      
317NNAME00178       VIA        MD0100PA00X+032617Y+081110               S0      
317NNAME00178       VIA        MD0100PA00X+033950Y+057267               S0      
327NNAME00179                         A08X+000886Y+177300X0980Y0200     S0      
317NNAME00179                   D0220PA01X+032370Y+057650               S0      
317NNAME00179                   D0220PA01X+033080Y+038500               S0      
317NNAME00179                   D0220PA01X+033080Y+081500               S0      
317NNAME00179                   D0220PA01X+032930Y+057860               S0      
317NNAME00179       VIA        MD0280PA08X+031870Y+046980               S0      
317NNAME00179       VIA        MD0100PA00X+032616Y+039144               S0      
317NNAME00179       VIA        MD0100PA00X+032617Y+081490               S0      
317NNAME00179       VIA        MD0100PA00X+033950Y+057647               S0      
327SSD5_PERST_N                       A08X+000886Y+177930X0980Y0200     S0      
327SSD5_PERST_N                       A01X+016689Y+187004X0790Y0200     S0      
327SSD5_PERST_N                       A01X+016689Y+187319X0790Y0200     S0      
317SSD5_PERST_N     VIA        MD0280PA01X+008391Y+188651               S0      
317SSD5_PERST_N     VIA        MD0100PA00X+011350Y+187597               S0      
317SSD5_PERST_N     VIA        MD0100PA00X+017350Y+187170               S0      
317SSD5_PERST_N     VIA        MD0100PA00X+006090Y+188585               S0      
327NNAME00180                         A08X+000886Y+179190X0980Y0200     S0      
317NNAME00180                   D0220PA01X+005200Y+188080               S0      
317NNAME00180                   D0220PA01X+005600Y+188080               S0      
317NNAME00180       VIA        MD0280PA08X+005320Y+186580               S0      
317NNAME00180       VIA        MD0100PA00X+005200Y+187750               S0      
327NNAME00181                         A08X+000886Y+179505X0980Y0200     S0      
317NNAME00181                   D0220PA01X+004800Y+188080               S0      
317NNAME00181       VIA        MD0280PA08X+005010Y+187280               S0      
317NNAME00181       VIA        MD0100PA00X+004800Y+187750               S0      
327PE_TX3_DR4_N                       A01X+000886Y+109741X0980Y0200     S0      
327PE_TX3_DR4_N                       A01X+088268Y+028421X0790Y0200     S0      
317PE_TX3_DR4_N     VIA        MD0100PA00X+002753Y+109759               S0      
317PE_TX3_DR4_N     VIA        MD0100PA00X+086744Y+028419               S0      
327PE_TX3_DR4_P                       A01X+000886Y+110056X0980Y0200     S0      
327PE_TX3_DR4_P                       A01X+088268Y+028736X0790Y0200     S0      
317PE_TX3_DR4_P     VIA        MD0100PA00X+002753Y+110079               S0      
317PE_TX3_DR4_P     VIA        MD0100PA00X+086744Y+028739               S0      
327PE_TX4_DR4_N                       A01X+000886Y+111001X0980Y0200     S0      
327PE_TX4_DR4_N                       A01X+088268Y+030311X0790Y0200     S0      
317PE_TX4_DR4_N     VIA        MD0100PA00X+002753Y+111018               S0      
317PE_TX4_DR4_N     VIA        MD0100PA00X+086744Y+030309               S0      
327PE_TX4_DR4_P                       A01X+000886Y+111316X0980Y0200     S0      
327PE_TX4_DR4_P                       A01X+088268Y+030626X0790Y0200     S0      
317PE_TX4_DR4_P     VIA        MD0100PA00X+002753Y+111338               S0      
317PE_TX4_DR4_P     VIA        MD0100PA00X+086744Y+030629               S0      
327SSD3_PERST_N                       A01X+000886Y+111946X0980Y0200     S0      
327SSD3_PERST_N                       A01X+089524Y+065350X0790Y0200     S0      
327SSD3_PERST_N                       A01X+089524Y+065665X0790Y0200     S0      
317SSD3_PERST_N     VIA        MD0280PA01X+003766Y+112507               S0      
317SSD3_PERST_N     VIA        MD0100PA00X+015720Y+095080               S0      
317SSD3_PERST_N     VIA        MD0100PA00X+004161Y+112507               S0      
317SSD3_PERST_N     VIA        MD0100PA00X+090120Y+065510               S0      
327SSD3_PWREN                         A01X+000886Y+112261X0980Y0200     S0      
317SSD3_PWREN                   D0220PA01X+082100Y+077820               S0      
317SSD3_PWREN                   D0220PA01X+081650Y+077820               S0      
317SSD3_PWREN                   D0220PA01X+081198Y+078328               S0      
317SSD3_PWREN                   D0300PA01X+082788Y+076825               S0      
317SSD3_PWREN       VIA        MD0120PA00X+080826Y+078328               S0      
317SSD3_PWREN       VIA        MD0100PA00X+015590Y+095420               S0      
317SSD3_PWREN       VIA        MD0100PA00X+003996Y+112831               S0      
327ATTN_LED_DR3_N                     A01X+000886Y+112576X0980Y0200     S0      
327ATTN_LED_DR3_N                     A01X+089125Y+054297X0480Y0160     S0      
317ATTN_LED_DR3_N               D0220PA01X+088795Y+056072               S0      
317ATTN_LED_DR3_N               D0220PA01X+088795Y+055672               S0      
317ATTN_LED_DR3_N   VIA        MD0280PA08X+014800Y+096650               S0      
317ATTN_LED_DR3_N   VIA        MD0100PA00X+015700Y+095750               S0      
317ATTN_LED_DR3_N   VIA        MD0100PA00X+003740Y+113091               S0      
317ATTN_LED_DR3_N   VIA        MD0100PA00X+088872Y+056452               S0      
327PE_TX1_DR3_N                       A01X+000886Y+113521X0980Y0200     S0      
327PE_TX1_DR3_N                       A01X+088268Y+062043X0790Y0200     S0      
317PE_TX1_DR3_N     VIA        MD0100PA00X+002753Y+113518               S0      
317PE_TX1_DR3_N     VIA        MD0100PA00X+086744Y+062041               S0      
327PE_TX1_DR3_P                       A01X+000886Y+113836X0980Y0200     S0      
327PE_TX1_DR3_P                       A01X+088268Y+062358X0790Y0200     S0      
317PE_TX1_DR3_P     VIA        MD0100PA00X+002753Y+113838               S0      
317PE_TX1_DR3_P     VIA        MD0100PA00X+086744Y+062361               S0      
327PE_TX2_DR3_N                       A01X+000886Y+114780X0980Y0200     S0      
327PE_TX2_DR3_N                       A01X+088268Y+067083X0790Y0200     S0      
317PE_TX2_DR3_N     VIA        MD0100PA00X+002753Y+114778               S0      
317PE_TX2_DR3_N     VIA        MD0100PA00X+086744Y+067080               S0      
327PE_TX2_DR3_P                       A01X+000886Y+115095X0980Y0200     S0      
327PE_TX2_DR3_P                       A01X+088268Y+067398X0790Y0200     S0      
317PE_TX2_DR3_P     VIA        MD0100PA00X+002753Y+115098               S0      
317PE_TX2_DR3_P     VIA        MD0100PA00X+086744Y+067400               S0      
327PE_TX3_DR3_N                       A01X+000886Y+116040X0980Y0200     S0      
327PE_TX3_DR3_N                       A01X+088268Y+068972X0790Y0200     S0      
317PE_TX3_DR3_N     VIA        MD0100PA00X+002753Y+116038               S0      
317PE_TX3_DR3_N     VIA        MD0100PA00X+086744Y+068970               S0      
327PE_TX3_DR3_P                       A01X+000886Y+116355X0980Y0200     S0      
327PE_TX3_DR3_P                       A01X+088268Y+069287X0790Y0200     S0      
317PE_TX3_DR3_P     VIA        MD0100PA00X+002753Y+116358               S0      
317PE_TX3_DR3_P     VIA        MD0100PA00X+086744Y+069290               S0      
327PE_TX4_DR3_N                       A01X+000886Y+117300X0980Y0200     S0      
327PE_TX4_DR3_N                       A01X+088268Y+070862X0790Y0200     S0      
317PE_TX4_DR3_N     VIA        MD0100PA00X+002753Y+117298               S0      
317PE_TX4_DR3_N     VIA        MD0100PA00X+086744Y+070860               S0      
327PE_TX4_DR3_P                       A01X+000886Y+117615X0980Y0200     S0      
327PE_TX4_DR3_P                       A01X+088268Y+071177X0790Y0200     S0      
317PE_TX4_DR3_P     VIA        MD0100PA00X+002753Y+117618               S0      
317PE_TX4_DR3_P     VIA        MD0100PA00X+086744Y+071180               S0      
327PE_TX1_DR7_N                       A01X+000886Y+118560X0980Y0200     S0      
327PE_TX1_DR7_N                       A01X+015433Y+102595X0790Y0200     S0      
317PE_TX1_DR7_N     VIA        MD0100PA00X+013909Y+102592               S0      
317PE_TX1_DR7_N     VIA        MD0100PA00X+002753Y+118557               S0      
327PE_TX1_DR7_P                       A01X+000886Y+118875X0980Y0200     S0      
327PE_TX1_DR7_P                       A01X+015433Y+102910X0790Y0200     S0      
317PE_TX1_DR7_P     VIA        MD0100PA00X+013909Y+102912               S0      
317PE_TX1_DR7_P     VIA        MD0100PA00X+002753Y+118877               S0      
327PE_TX2_DR7_N                       A01X+000886Y+119820X0980Y0200     S0      
327PE_TX2_DR7_N                       A01X+015433Y+107634X0790Y0200     S0      
317PE_TX2_DR7_N     VIA        MD0100PA00X+013909Y+107631               S0      
317PE_TX2_DR7_N     VIA        MD0100PA00X+002753Y+119817               S0      
327PE_TX2_DR7_P                       A01X+000886Y+120135X0980Y0200     S0      
327PE_TX2_DR7_P                       A01X+015433Y+107949X0790Y0200     S0      
317PE_TX2_DR7_P     VIA        MD0100PA00X+013909Y+107951               S0      
317PE_TX2_DR7_P     VIA        MD0100PA00X+002753Y+120137               S0      
327PE_TX3_DR7_N                       A01X+000886Y+121080X0980Y0200     S0      
327PE_TX3_DR7_N                       A01X+015433Y+109524X0790Y0200     S0      
317PE_TX3_DR7_N     VIA        MD0100PA00X+013909Y+109521               S0      
317PE_TX3_DR7_N     VIA        MD0100PA00X+002753Y+121077               S0      
327PE_TX3_DR7_P                       A01X+000886Y+121395X0980Y0200     S0      
327PE_TX3_DR7_P                       A01X+015433Y+109839X0790Y0200     S0      
317PE_TX3_DR7_P     VIA        MD0100PA00X+013909Y+109841               S0      
317PE_TX3_DR7_P     VIA        MD0100PA00X+002753Y+121397               S0      
327PE_TX4_DR7_N                       A01X+000886Y+122339X0980Y0200     S0      
327PE_TX4_DR7_N                       A01X+015433Y+111413X0790Y0200     S0      
317PE_TX4_DR7_N     VIA        MD0100PA00X+013909Y+111411               S0      
317PE_TX4_DR7_N     VIA        MD0100PA00X+002753Y+122337               S0      
327PE_TX4_DR7_P                       A01X+000886Y+122654X0980Y0200     S0      
327PE_TX4_DR7_P                       A01X+015433Y+111728X0790Y0200     S0      
317PE_TX4_DR7_P     VIA        MD0100PA00X+013909Y+111731               S0      
317PE_TX4_DR7_P     VIA        MD0100PA00X+002753Y+122657               S0      
327ATTN_LED_DR7_N                     A01X+000886Y+124544X0980Y0200     S0      
327ATTN_LED_DR7_N                     A01X+019000Y+094975X0160Y0480     S0      
317ATTN_LED_DR7_N               D0220PA01X+020390Y+096548               S0      
317ATTN_LED_DR7_N               D0220PA01X+020390Y+096098               S0      
317ATTN_LED_DR7_N   VIA        MD0280PA08X+013200Y+104200               S0      
317ATTN_LED_DR7_N   VIA        MD0100PA00X+019890Y+096548               S0      
317ATTN_LED_DR7_N   VIA        MD0100PA00X+003296Y+123448               S0      
327PE_TX1_DR2_N                       A01X+000886Y+125489X0980Y0200     S0      
327PE_TX1_DR2_N                       A01X+088268Y+102595X0790Y0200     S0      
317PE_TX1_DR2_N     VIA        MD0100PA00X+002753Y+125487               S0      
317PE_TX1_DR2_N     VIA        MD0100PA00X+086744Y+102592               S0      
327PE_TX1_DR2_P                       A01X+000886Y+125804X0980Y0200     S0      
327PE_TX1_DR2_P                       A01X+088268Y+102910X0790Y0200     S0      
317PE_TX1_DR2_P     VIA        MD0100PA00X+002753Y+125807               S0      
317PE_TX1_DR2_P     VIA        MD0100PA00X+086744Y+102912               S0      
327PE_TX2_DR2_N                       A01X+000886Y+126749X0980Y0200     S0      
327PE_TX2_DR2_N                       A01X+088268Y+107634X0790Y0200     S0      
317PE_TX2_DR2_N     VIA        MD0100PA00X+002753Y+126746               S0      
317PE_TX2_DR2_N     VIA        MD0100PA00X+086744Y+107631               S0      
327PE_TX2_DR2_P                       A01X+000886Y+127064X0980Y0200     S0      
327PE_TX2_DR2_P                       A01X+088268Y+107949X0790Y0200     S0      
317PE_TX2_DR2_P     VIA        MD0100PA00X+002753Y+127066               S0      
317PE_TX2_DR2_P     VIA        MD0100PA00X+086744Y+107951               S0      
327PE_TX3_DR2_N                       A01X+000886Y+128009X0980Y0200     S0      
327PE_TX3_DR2_N                       A01X+088268Y+109524X0790Y0200     S0      
317PE_TX3_DR2_N     VIA        MD0100PA00X+002753Y+128006               S0      
317PE_TX3_DR2_N     VIA        MD0100PA00X+086744Y+109521               S0      
327PE_TX3_DR2_P                       A01X+000886Y+128324X0980Y0200     S0      
327PE_TX3_DR2_P                       A01X+088268Y+109839X0790Y0200     S0      
317PE_TX3_DR2_P     VIA        MD0100PA00X+002753Y+128326               S0      
317PE_TX3_DR2_P     VIA        MD0100PA00X+086744Y+109841               S0      
327PE_TX4_DR2_N                       A01X+000886Y+129269X0980Y0200     S0      
327PE_TX4_DR2_N                       A01X+088268Y+111413X0790Y0200     S0      
317PE_TX4_DR2_N     VIA        MD0100PA00X+002753Y+129266               S0      
317PE_TX4_DR2_N     VIA        MD0100PA00X+086744Y+111411               S0      
327PE_TX4_DR2_P                       A01X+000886Y+129584X0980Y0200     S0      
327PE_TX4_DR2_P                       A01X+088268Y+111728X0790Y0200     S0      
317PE_TX4_DR2_P     VIA        MD0100PA00X+002753Y+129586               S0      
317PE_TX4_DR2_P     VIA        MD0100PA00X+086744Y+111731               S0      
327SSD2_PWREN                         A01X+000886Y+130213X0980Y0200     S0      
317SSD2_PWREN                   D0220PA01X+082100Y+118370               S0      
317SSD2_PWREN                   D0220PA01X+081650Y+118370               S0      
317SSD2_PWREN                   D0220PA01X+081198Y+118877               S0      
317SSD2_PWREN                   D0300PA01X+082788Y+117375               S0      
317SSD2_PWREN       VIA        MD0120PA00X+080776Y+118877               S0      
317SSD2_PWREN       VIA        MD0100PA00X+003394Y+131100               S0      
327ATTN_LED_DR2_N                     A01X+000886Y+130528X0980Y0200     S0      
327ATTN_LED_DR2_N                     A01X+089125Y+094848X0480Y0160     S0      
317ATTN_LED_DR2_N               D0220PA01X+088795Y+096623               S0      
317ATTN_LED_DR2_N               D0220PA01X+088795Y+096223               S0      
317ATTN_LED_DR2_N   VIA        MD0280PA01X+089055Y+095745               S0      
317ATTN_LED_DR2_N   VIA        MD0100PA00X+003000Y+130500               S0      
317ATTN_LED_DR2_N   VIA        MD0100PA00X+088872Y+097003               S0      
327PE_TX1_DR6_N                       A01X+000886Y+136513X0980Y0200     S0      
327PE_TX1_DR6_N                       A01X+015433Y+143146X0790Y0200     S0      
317PE_TX1_DR6_N     VIA        MD0100PA00X+013909Y+143143               S0      
317PE_TX1_DR6_N     VIA        MD0100PA00X+002753Y+136510               S0      
327PE_TX1_DR6_P                       A01X+000886Y+136828X0980Y0200     S0      
327PE_TX1_DR6_P                       A01X+015433Y+143461X0790Y0200     S0      
317PE_TX1_DR6_P     VIA        MD0100PA00X+013909Y+143463               S0      
317PE_TX1_DR6_P     VIA        MD0100PA00X+002753Y+136830               S0      
327PE_TX2_DR6_N                       A01X+000886Y+137773X0980Y0200     S0      
327PE_TX2_DR6_N                       A01X+015433Y+148185X0790Y0200     S0      
317PE_TX2_DR6_N     VIA        MD0100PA00X+013909Y+148183               S0      
317PE_TX2_DR6_N     VIA        MD0100PA00X+002753Y+137770               S0      
327PE_TX2_DR6_P                       A01X+000886Y+138087X0980Y0200     S0      
327PE_TX2_DR6_P                       A01X+015433Y+148500X0790Y0200     S0      
317PE_TX2_DR6_P     VIA        MD0100PA00X+013909Y+148503               S0      
317PE_TX2_DR6_P     VIA        MD0100PA00X+002753Y+138090               S0      
327PE_TX3_DR6_N                       A01X+000886Y+139032X0980Y0200     S0      
327PE_TX3_DR6_N                       A01X+015433Y+150075X0790Y0200     S0      
317PE_TX3_DR6_N     VIA        MD0100PA00X+013909Y+150072               S0      
317PE_TX3_DR6_N     VIA        MD0100PA00X+002753Y+139030               S0      
327PE_TX3_DR6_P                       A01X+000886Y+139347X0980Y0200     S0      
327PE_TX3_DR6_P                       A01X+015433Y+150390X0790Y0200     S0      
317PE_TX3_DR6_P     VIA        MD0100PA00X+013909Y+150392               S0      
317PE_TX3_DR6_P     VIA        MD0100PA00X+002753Y+139350               S0      
327PE_TX4_DR6_N                       A01X+000886Y+140292X0980Y0200     S0      
327PE_TX4_DR6_N                       A01X+015433Y+151965X0790Y0200     S0      
317PE_TX4_DR6_N     VIA        MD0100PA00X+013909Y+151962               S0      
317PE_TX4_DR6_N     VIA        MD0100PA00X+002753Y+140290               S0      
327PE_TX4_DR6_P                       A01X+000886Y+140607X0980Y0200     S0      
327PE_TX4_DR6_P                       A01X+015433Y+152280X0790Y0200     S0      
317PE_TX4_DR6_P     VIA        MD0100PA00X+013909Y+152282               S0      
317PE_TX4_DR6_P     VIA        MD0100PA00X+002753Y+140610               S0      
327ATTN_LED_DR6_N                     A01X+000886Y+141552X0980Y0200     S0      
327ATTN_LED_DR6_N                     A01X+016290Y+135399X0480Y0160     S0      
317ATTN_LED_DR6_N               D0220PA01X+015466Y+134780               S0      
317ATTN_LED_DR6_N               D0220PA01X+015466Y+135230               S0      
317ATTN_LED_DR6_N   VIA        MD0280PA08X+016250Y+138050               S0      
317ATTN_LED_DR6_N   VIA        MD0100PA00X+015471Y+134451               S0      
317ATTN_LED_DR6_N   VIA        MD0100PA00X+002700Y+141750               S0      
327SSD6_PWREN                         A01X+000886Y+141867X0980Y0200     S0      
317SSD6_PWREN                   D0220PA01X+007526Y+158368               S0      
317SSD6_PWREN                   D0220PA01X+008388Y+158358               S0      
317SSD6_PWREN                   D0220PA01X+007938Y+158358               S0      
317SSD6_PWREN                   D0300PA01X+009888Y+157025               S0      
317SSD6_PWREN       VIA        MD0120PA00X+007761Y+156539               S0      
317SSD6_PWREN       VIA        MD0100PA00X+002800Y+144400               S0      
327SSD2_PERST_N                       A08X+000886Y+109741X0980Y0200     S0      
327SSD2_PERST_N                       A01X+089524Y+105902X0790Y0200     S0      
327SSD2_PERST_N                       A01X+089524Y+106217X0790Y0200     S0      
317SSD2_PERST_N     VIA        MD0280PA01X+009781Y+106642               S0      
317SSD2_PERST_N     VIA        MD0100PA00X+013750Y+101450               S0      
317SSD2_PERST_N     VIA        MD0100PA00X+006709Y+107036               S0      
317SSD2_PERST_N     VIA        MD0100PA00X+090130Y+106070               S0      
327PE_RX3_DR4_N                       A08X+000886Y+110371X0980Y0200     S0      
327PE_RX3_DR4_N                       A01X+088268Y+029366X0790Y0200     S0      
317PE_RX3_DR4_N     VIA        MD0100PA00X+002000Y+110368               S0      
317PE_RX3_DR4_N     VIA        MD0100PA00X+087294Y+029304               S0      
327PE_RX3_DR4_P                       A08X+000886Y+110686X0980Y0200     S0      
327PE_RX3_DR4_P                       A01X+088268Y+029681X0790Y0200     S0      
317PE_RX3_DR4_P     VIA        MD0100PA00X+002000Y+110688               S0      
317PE_RX3_DR4_P     VIA        MD0100PA00X+087294Y+029744               S0      
327PE_RX4_DR4_N                       A08X+000886Y+111631X0980Y0200     S0      
327PE_RX4_DR4_N                       A01X+088268Y+031256X0790Y0200     S0      
317PE_RX4_DR4_N     VIA        MD0100PA00X+002000Y+111628               S0      
317PE_RX4_DR4_N     VIA        MD0100PA00X+087294Y+031193               S0      
327PE_RX4_DR4_P                       A08X+000886Y+111946X0980Y0200     S0      
327PE_RX4_DR4_P                       A01X+088268Y+031571X0790Y0200     S0      
317PE_RX4_DR4_P     VIA        MD0100PA00X+002000Y+111948               S0      
317PE_RX4_DR4_P     VIA        MD0100PA00X+087294Y+031633               S0      
327SSD12_PWREN                        A08X+000886Y+112891X0980Y0200     S0      
317SSD12_PWREN                  D0220PA01X+015850Y+080770               S0      
317SSD12_PWREN                  D0220PA01X+014950Y+080830               S0      
317SSD12_PWREN                  D0220PA01X+015400Y+080830               S0      
317SSD12_PWREN                  D0300PA01X+014453Y+081835               S0      
317SSD12_PWREN      VIA        MD0280PA08X+008010Y+080550               S0      
317SSD12_PWREN      VIA        MD0100PA00X+014380Y+080740               S0      
327NNAME00182                         A08X+000886Y+113206X0980Y0200     S0      
327NNAME00182                         A01X+009773Y+105545X0480Y0160     S0      
317NNAME00182                   D0220PA01X+008400Y+104620               S0      
317NNAME00182                   D0220PA01X+008800Y+104620               S0      
317NNAME00182       VIA        MD0280PA08X+008118Y+106640               S0      
317NNAME00182       VIA        MD0100PA00X+008169Y+104940               S0      
327PE_RX1_DR3_N                       A08X+000886Y+114150X0980Y0200     S0      
327PE_RX1_DR3_N                       A01X+088268Y+062988X0790Y0200     S0      
317PE_RX1_DR3_N     VIA        MD0100PA00X+002000Y+114148               S0      
317PE_RX1_DR3_N     VIA        MD0100PA00X+087294Y+062926               S0      
327PE_RX1_DR3_P                       A08X+000886Y+114465X0980Y0200     S0      
327PE_RX1_DR3_P                       A01X+088268Y+063303X0790Y0200     S0      
317PE_RX1_DR3_P     VIA        MD0100PA00X+002000Y+114468               S0      
317PE_RX1_DR3_P     VIA        MD0100PA00X+087294Y+063366               S0      
327PE_RX2_DR3_N                       A08X+000886Y+115410X0980Y0200     S0      
327PE_RX2_DR3_N                       A01X+088268Y+068028X0790Y0200     S0      
317PE_RX2_DR3_N     VIA        MD0100PA00X+002000Y+115408               S0      
317PE_RX2_DR3_N     VIA        MD0100PA00X+087294Y+067965               S0      
327PE_RX2_DR3_P                       A08X+000886Y+115725X0980Y0200     S0      
327PE_RX2_DR3_P                       A01X+088268Y+068343X0790Y0200     S0      
317PE_RX2_DR3_P     VIA        MD0100PA00X+002000Y+115728               S0      
317PE_RX2_DR3_P     VIA        MD0100PA00X+087294Y+068405               S0      
327PE_RX3_DR3_N                       A08X+000886Y+116670X0980Y0200     S0      
327PE_RX3_DR3_N                       A01X+088268Y+069917X0790Y0200     S0      
317PE_RX3_DR3_N     VIA        MD0100PA00X+002000Y+116667               S0      
317PE_RX3_DR3_N     VIA        MD0100PA00X+087294Y+069855               S0      
327PE_RX3_DR3_P                       A08X+000886Y+116985X0980Y0200     S0      
327PE_RX3_DR3_P                       A01X+088268Y+070232X0790Y0200     S0      
317PE_RX3_DR3_P     VIA        MD0100PA00X+002000Y+116988               S0      
317PE_RX3_DR3_P     VIA        MD0100PA00X+087294Y+070295               S0      
327PE_RX4_DR3_N                       A08X+000886Y+117930X0980Y0200     S0      
327PE_RX4_DR3_N                       A01X+088268Y+071807X0790Y0200     S0      
317PE_RX4_DR3_N     VIA        MD0100PA00X+002000Y+117927               S0      
317PE_RX4_DR3_N     VIA        MD0100PA00X+087294Y+071745               S0      
327PE_RX4_DR3_P                       A08X+000886Y+118245X0980Y0200     S0      
327PE_RX4_DR3_P                       A01X+088268Y+072122X0790Y0200     S0      
317PE_RX4_DR3_P     VIA        MD0100PA00X+002000Y+118247               S0      
317PE_RX4_DR3_P     VIA        MD0100PA00X+087294Y+072185               S0      
327PE_RX1_DR7_N                       A08X+000886Y+119190X0980Y0200     S0      
327PE_RX1_DR7_N                       A01X+015433Y+103539X0790Y0200     S0      
317PE_RX1_DR7_N     VIA        MD0100PA00X+014460Y+103477               S0      
317PE_RX1_DR7_N     VIA        MD0100PA00X+002000Y+119187               S0      
327PE_RX1_DR7_P                       A08X+000886Y+119505X0980Y0200     S0      
327PE_RX1_DR7_P                       A01X+015433Y+103854X0790Y0200     S0      
317PE_RX1_DR7_P     VIA        MD0100PA00X+014460Y+103917               S0      
317PE_RX1_DR7_P     VIA        MD0100PA00X+002000Y+119507               S0      
327PE_RX2_DR7_N                       A08X+000886Y+120450X0980Y0200     S0      
327PE_RX2_DR7_N                       A01X+015433Y+108579X0790Y0200     S0      
317PE_RX2_DR7_N     VIA        MD0100PA00X+014460Y+108516               S0      
317PE_RX2_DR7_N     VIA        MD0100PA00X+002000Y+120447               S0      
327PE_RX2_DR7_P                       A08X+000886Y+120765X0980Y0200     S0      
327PE_RX2_DR7_P                       A01X+015433Y+108894X0790Y0200     S0      
317PE_RX2_DR7_P     VIA        MD0100PA00X+014460Y+108956               S0      
317PE_RX2_DR7_P     VIA        MD0100PA00X+002000Y+120767               S0      
327PE_RX3_DR7_N                       A08X+000886Y+121710X0980Y0200     S0      
327PE_RX3_DR7_N                       A01X+015433Y+110468X0790Y0200     S0      
317PE_RX3_DR7_N     VIA        MD0100PA00X+014460Y+110406               S0      
317PE_RX3_DR7_N     VIA        MD0100PA00X+002000Y+121707               S0      
327PE_RX3_DR7_P                       A08X+000886Y+122025X0980Y0200     S0      
327PE_RX3_DR7_P                       A01X+015433Y+110783X0790Y0200     S0      
317PE_RX3_DR7_P     VIA        MD0100PA00X+014460Y+110846               S0      
317PE_RX3_DR7_P     VIA        MD0100PA00X+002000Y+122027               S0      
327SSD7_PERST_N                       A08X+000886Y+122654X0980Y0200     S0      
327SSD7_PERST_N                       A01X+016689Y+105902X0790Y0200     S0      
327SSD7_PERST_N                       A01X+016689Y+106217X0790Y0200     S0      
317SSD7_PERST_N     VIA        MD0280PA01X+004010Y+115499               S0      
317SSD7_PERST_N     VIA        MD0100PA00X+017300Y+106040               S0      
317SSD7_PERST_N     VIA        MD0100PA00X+003320Y+123067               S0      
317SSD7_PERST_N     VIA        MD0100PA00X+004010Y+114251               S0      
327SSD7_PWREN                         A08X+000886Y+122969X0980Y0200     S0      
317SSD7_PWREN                   D0220PA01X+008548Y+118877               S0      
317SSD7_PWREN                   D0220PA01X+009450Y+118370               S0      
317SSD7_PWREN                   D0220PA01X+009000Y+118370               S0      
317SSD7_PWREN                   D0300PA01X+009958Y+117415               S0      
317SSD7_PWREN       VIA        MD0280PA08X+005194Y+123251               S0      
317SSD7_PWREN       VIA        MD0100PA00X+008530Y+118200               S0      
327PE_RX4_DR7_N                       A08X+000886Y+124859X0980Y0200     S0      
327PE_RX4_DR7_N                       A01X+015433Y+112358X0790Y0200     S0      
317PE_RX4_DR7_N     VIA        MD0100PA00X+014460Y+112296               S0      
317PE_RX4_DR7_N     VIA        MD0100PA00X+002000Y+124857               S0      
327PE_RX4_DR7_P                       A08X+000886Y+125174X0980Y0200     S0      
327PE_RX4_DR7_P                       A01X+015433Y+112673X0790Y0200     S0      
317PE_RX4_DR7_P     VIA        MD0100PA00X+014460Y+112736               S0      
317PE_RX4_DR7_P     VIA        MD0100PA00X+002000Y+125177               S0      
327PE_RX1_DR2_N                       A08X+000886Y+126119X0980Y0200     S0      
327PE_RX1_DR2_N                       A01X+088268Y+103539X0790Y0200     S0      
317PE_RX1_DR2_N     VIA        MD0100PA00X+002000Y+126116               S0      
317PE_RX1_DR2_N     VIA        MD0100PA00X+087294Y+103477               S0      
327PE_RX1_DR2_P                       A08X+000886Y+126434X0980Y0200     S0      
327PE_RX1_DR2_P                       A01X+088268Y+103854X0790Y0200     S0      
317PE_RX1_DR2_P     VIA        MD0100PA00X+002000Y+126436               S0      
317PE_RX1_DR2_P     VIA        MD0100PA00X+087294Y+103917               S0      
327PE_RX2_DR2_N                       A08X+000886Y+127379X0980Y0200     S0      
327PE_RX2_DR2_N                       A01X+088268Y+108579X0790Y0200     S0      
317PE_RX2_DR2_N     VIA        MD0100PA00X+002000Y+127376               S0      
317PE_RX2_DR2_N     VIA        MD0100PA00X+087294Y+108516               S0      
327PE_RX2_DR2_P                       A08X+000886Y+127694X0980Y0200     S0      
327PE_RX2_DR2_P                       A01X+088268Y+108894X0790Y0200     S0      
317PE_RX2_DR2_P     VIA        MD0100PA00X+002000Y+127696               S0      
317PE_RX2_DR2_P     VIA        MD0100PA00X+087294Y+108956               S0      
327PE_RX3_DR2_N                       A08X+000886Y+128639X0980Y0200     S0      
327PE_RX3_DR2_N                       A01X+088268Y+110468X0790Y0200     S0      
317PE_RX3_DR2_N     VIA        MD0100PA00X+002000Y+128636               S0      
317PE_RX3_DR2_N     VIA        MD0100PA00X+087294Y+110406               S0      
327PE_RX3_DR2_P                       A08X+000886Y+128954X0980Y0200     S0      
327PE_RX3_DR2_P                       A01X+088268Y+110783X0790Y0200     S0      
317PE_RX3_DR2_P     VIA        MD0100PA00X+002000Y+128956               S0      
317PE_RX3_DR2_P     VIA        MD0100PA00X+087294Y+110846               S0      
327PE_RX4_DR2_N                       A08X+000886Y+129898X0980Y0200     S0      
327PE_RX4_DR2_N                       A01X+088268Y+112358X0790Y0200     S0      
317PE_RX4_DR2_N     VIA        MD0100PA00X+002000Y+129896               S0      
317PE_RX4_DR2_N     VIA        MD0100PA00X+087294Y+112296               S0      
327PE_RX4_DR2_P                       A08X+000886Y+130213X0980Y0200     S0      
327PE_RX4_DR2_P                       A01X+088268Y+112673X0790Y0200     S0      
317PE_RX4_DR2_P     VIA        MD0100PA00X+002000Y+130216               S0      
317PE_RX4_DR2_P     VIA        MD0100PA00X+087294Y+112736               S0      
327SSD11_PWREN                        A08X+000886Y+130843X0980Y0200     S0      
317SSD11_PWREN                  D0220PA01X+015853Y+120873               S0      
317SSD11_PWREN                  D0220PA01X+014950Y+121380               S0      
317SSD11_PWREN                  D0220PA01X+015400Y+121380               S0      
317SSD11_PWREN                  D0300PA01X+014483Y+122385               S0      
317SSD11_PWREN      VIA        MD0120PA00X+016317Y+121100               S0      
317SSD11_PWREN      VIA        MD0100PA00X+002650Y+130512               S0      
327NNAME00183                         A08X+000886Y+131158X0980Y0200     S0      
327NNAME00183                         A01X+009773Y+146096X0480Y0160     S0      
317NNAME00183                   D0220PA01X+008359Y+145095               S0      
317NNAME00183                   D0220PA01X+008759Y+145095               S0      
317NNAME00183       VIA        MD0280PA08X+006500Y+133600               S0      
317NNAME00183       VIA        MD0100PA00X+008030Y+145100               S0      
327PE_RX1_DR6_N                       A08X+000886Y+137143X0980Y0200     S0      
327PE_RX1_DR6_N                       A01X+015433Y+144091X0790Y0200     S0      
317PE_RX1_DR6_N     VIA        MD0100PA00X+014460Y+144028               S0      
317PE_RX1_DR6_N     VIA        MD0100PA00X+002000Y+137140               S0      
327PE_RX1_DR6_P                       A08X+000886Y+137458X0980Y0200     S0      
327PE_RX1_DR6_P                       A01X+015433Y+144406X0790Y0200     S0      
317PE_RX1_DR6_P     VIA        MD0100PA00X+014460Y+144468               S0      
317PE_RX1_DR6_P     VIA        MD0100PA00X+002000Y+137460               S0      
327PE_RX2_DR6_N                       A08X+000886Y+138402X0980Y0200     S0      
327PE_RX2_DR6_N                       A01X+015433Y+149130X0790Y0200     S0      
317PE_RX2_DR6_N     VIA        MD0100PA00X+014460Y+149067               S0      
317PE_RX2_DR6_N     VIA        MD0100PA00X+002000Y+138400               S0      
327PE_RX2_DR6_P                       A08X+000886Y+138717X0980Y0200     S0      
327PE_RX2_DR6_P                       A01X+015433Y+149445X0790Y0200     S0      
317PE_RX2_DR6_P     VIA        MD0100PA00X+014460Y+149507               S0      
317PE_RX2_DR6_P     VIA        MD0100PA00X+002000Y+138720               S0      
327PE_RX3_DR6_N                       A08X+000886Y+139662X0980Y0200     S0      
327PE_RX3_DR6_N                       A01X+015433Y+151020X0790Y0200     S0      
317PE_RX3_DR6_N     VIA        MD0100PA00X+014460Y+150957               S0      
317PE_RX3_DR6_N     VIA        MD0100PA00X+002000Y+139660               S0      
327PE_RX3_DR6_P                       A08X+000886Y+139977X0980Y0200     S0      
327PE_RX3_DR6_P                       A01X+015433Y+151335X0790Y0200     S0      
317PE_RX3_DR6_P     VIA        MD0100PA00X+014460Y+151397               S0      
317PE_RX3_DR6_P     VIA        MD0100PA00X+002000Y+139980               S0      
327PE_RX4_DR6_N                       A08X+000886Y+140922X0980Y0200     S0      
327PE_RX4_DR6_N                       A01X+015433Y+152910X0790Y0200     S0      
317PE_RX4_DR6_N     VIA        MD0100PA00X+014460Y+152847               S0      
317PE_RX4_DR6_N     VIA        MD0100PA00X+002000Y+140920               S0      
327PE_RX4_DR6_P                       A08X+000886Y+141237X0980Y0200     S0      
327PE_RX4_DR6_P                       A01X+015433Y+153224X0790Y0200     S0      
317PE_RX4_DR6_P     VIA        MD0100PA00X+014460Y+153287               S0      
317PE_RX4_DR6_P     VIA        MD0100PA00X+002000Y+141240               S0      
327SSD6_PERST_N                       A08X+000886Y+141867X0980Y0200     S0      
327SSD6_PERST_N                       A01X+016689Y+146453X0790Y0200     S0      
327SSD6_PERST_N                       A01X+016689Y+146768X0790Y0200     S0      
317SSD6_PERST_N     VIA        MD0280PA01X+008214Y+147650               S0      
317SSD6_PERST_N     VIA        MD0100PA00X+014810Y+146875               S0      
317SSD6_PERST_N     VIA        MD0100PA00X+017310Y+146630               S0      
317SSD6_PERST_N     VIA        MD0100PA00X+006937Y+147472               S0      
327SSD9_PWREN                         A01X+000886Y+065174X0980Y0200     S0      
317SSD9_PWREN                   D0220PA01X+008548Y+037778               S0      
317SSD9_PWREN                   D0220PA01X+009450Y+037270               S0      
317SSD9_PWREN                   D0220PA01X+009000Y+037270               S0      
317SSD9_PWREN                   D0300PA01X+009958Y+036275               S0      
317SSD9_PWREN       VIA        MD0120PA00X+007868Y+038070               S0      
317SSD9_PWREN       VIA        MD0100PA00X+005207Y+037065               S0      
327ATTN_LED_DR9_N                     A01X+000886Y+065489X0980Y0200     S0      
327ATTN_LED_DR9_N                     A01X+016290Y+013845X0480Y0160     S0      
317ATTN_LED_DR9_N               D0220PA01X+015056Y+013630               S0      
317ATTN_LED_DR9_N               D0220PA01X+014640Y+013630               S0      
317ATTN_LED_DR9_N   VIA        MD0280PA01X+005650Y+021661               S0      
327PE_TX1_DR9_N                       A01X+000886Y+071473X0980Y0200     S0      
327PE_TX1_DR9_N                       A01X+015433Y+021492X0790Y0200     S0      
317PE_TX1_DR9_N     VIA        MD0100PA00X+013909Y+021490               S0      
317PE_TX1_DR9_N     VIA        MD0100PA00X+002753Y+071471               S0      
327PE_TX1_DR9_P                       A01X+000886Y+071788X0980Y0200     S0      
327PE_TX1_DR9_P                       A01X+015433Y+021807X0790Y0200     S0      
317PE_TX1_DR9_P     VIA        MD0100PA00X+013909Y+021810               S0      
317PE_TX1_DR9_P     VIA        MD0100PA00X+002753Y+071791               S0      
327PE_TX2_DR9_N                       A01X+000886Y+072733X0980Y0200     S0      
327PE_TX2_DR9_N                       A01X+015433Y+026532X0790Y0200     S0      
317PE_TX2_DR9_N     VIA        MD0100PA00X+013909Y+026529               S0      
317PE_TX2_DR9_N     VIA        MD0100PA00X+002753Y+072731               S0      
327PE_TX2_DR9_P                       A01X+000886Y+073048X0980Y0200     S0      
327PE_TX2_DR9_P                       A01X+015433Y+026846X0790Y0200     S0      
317PE_TX2_DR9_P     VIA        MD0100PA00X+013909Y+026849               S0      
317PE_TX2_DR9_P     VIA        MD0100PA00X+002753Y+073051               S0      
327SSD9_PERST_N                       A01X+000886Y+074938X0980Y0200     S0      
327SSD9_PERST_N                       A01X+016689Y+024799X0790Y0200     S0      
327SSD9_PERST_N                       A01X+016689Y+025114X0790Y0200     S0      
317SSD9_PERST_N     VIA        MD0280PA01X+010678Y+026879               S0      
317SSD9_PERST_N     VIA        MD0100PA00X+014360Y+025210               S0      
317SSD9_PERST_N     VIA        MD0100PA00X+017290Y+024940               S0      
327PE_TX3_DR9_N                       A01X+000886Y+075883X0980Y0200     S0      
327PE_TX3_DR9_N                       A01X+015433Y+028421X0790Y0200     S0      
317PE_TX3_DR9_N     VIA        MD0100PA00X+013909Y+028419               S0      
317PE_TX3_DR9_N     VIA        MD0100PA00X+002753Y+075880               S0      
327PE_TX3_DR9_P                       A01X+000886Y+076198X0980Y0200     S0      
327PE_TX3_DR9_P                       A01X+015433Y+028736X0790Y0200     S0      
317PE_TX3_DR9_P     VIA        MD0100PA00X+013909Y+028739               S0      
317PE_TX3_DR9_P     VIA        MD0100PA00X+002753Y+076200               S0      
327PE_TX4_DR9_N                       A01X+000886Y+077143X0980Y0200     S0      
327PE_TX4_DR9_N                       A01X+015433Y+030311X0790Y0200     S0      
317PE_TX4_DR9_N     VIA        MD0100PA00X+013909Y+030309               S0      
317PE_TX4_DR9_N     VIA        MD0100PA00X+002753Y+077140               S0      
327PE_TX4_DR9_P                       A01X+000886Y+077458X0980Y0200     S0      
327PE_TX4_DR9_P                       A01X+015433Y+030626X0790Y0200     S0      
317PE_TX4_DR9_P     VIA        MD0100PA00X+013909Y+030629               S0      
317PE_TX4_DR9_P     VIA        MD0100PA00X+002753Y+077460               S0      
327SSD13_PWREN                        A01X+000886Y+078087X0980Y0200     S0      
317SSD13_PWREN                  D0220PA01X+015815Y+039735               S0      
317SSD13_PWREN                  D0220PA01X+014913Y+040242               S0      
317SSD13_PWREN                  D0220PA01X+015362Y+040242               S0      
317SSD13_PWREN                  D0300PA01X+014453Y+041285               S0      
317SSD13_PWREN      VIA        MD0280PA01X+004458Y+072436               S0      
317SSD13_PWREN      VIA        MD0100PA00X+015850Y+040800               S0      
317SSD13_PWREN      VIA        MD0100PA00X+004650Y+065350               S0      
327NNAME00184                         A01X+000886Y+078402X0980Y0200     S0      
327NNAME00184                         A01X+009773Y+064994X0480Y0160     S0      
317NNAME00184                   D0220PA01X+008359Y+063993               S0      
317NNAME00184                   D0220PA01X+008759Y+063993               S0      
317NNAME00184       VIA        MD0120PA00X+004750Y+066050               S0      
317NNAME00184       VIA        MD0100PA00X+008030Y+063998               S0      
327PE_TX1_DR8_N                       A01X+000886Y+079347X0980Y0200     S0      
327PE_TX1_DR8_N                       A01X+015433Y+062043X0790Y0200     S0      
317PE_TX1_DR8_N     VIA        MD0100PA00X+013909Y+062041               S0      
317PE_TX1_DR8_N     VIA        MD0100PA00X+002753Y+079345               S0      
327PE_TX1_DR8_P                       A01X+000886Y+079662X0980Y0200     S0      
327PE_TX1_DR8_P                       A01X+015433Y+062358X0790Y0200     S0      
317PE_TX1_DR8_P     VIA        MD0100PA00X+013909Y+062361               S0      
317PE_TX1_DR8_P     VIA        MD0100PA00X+002753Y+079665               S0      
327PE_TX2_DR8_N                       A01X+000886Y+080607X0980Y0200     S0      
327PE_TX2_DR8_N                       A01X+015433Y+067083X0790Y0200     S0      
317PE_TX2_DR8_N     VIA        MD0100PA00X+013909Y+067080               S0      
317PE_TX2_DR8_N     VIA        MD0100PA00X+002753Y+080605               S0      
327PE_TX2_DR8_P                       A01X+000886Y+080922X0980Y0200     S0      
327PE_TX2_DR8_P                       A01X+015433Y+067398X0790Y0200     S0      
317PE_TX2_DR8_P     VIA        MD0100PA00X+013909Y+067400               S0      
317PE_TX2_DR8_P     VIA        MD0100PA00X+002753Y+080925               S0      
327PE_TX3_DR8_N                       A01X+000886Y+081867X0980Y0200     S0      
327PE_TX3_DR8_N                       A01X+015433Y+068972X0790Y0200     S0      
317PE_TX3_DR8_N     VIA        MD0100PA00X+013909Y+068970               S0      
317PE_TX3_DR8_N     VIA        MD0100PA00X+002753Y+081864               S0      
327PE_TX3_DR8_P                       A01X+000886Y+082182X0980Y0200     S0      
327PE_TX3_DR8_P                       A01X+015433Y+069287X0790Y0200     S0      
317PE_TX3_DR8_P     VIA        MD0100PA00X+013909Y+069290               S0      
317PE_TX3_DR8_P     VIA        MD0100PA00X+002753Y+082185               S0      
327PE_TX4_DR8_N                       A01X+000886Y+083127X0980Y0200     S0      
327PE_TX4_DR8_N                       A01X+015433Y+070862X0790Y0200     S0      
317PE_TX4_DR8_N     VIA        MD0100PA00X+013909Y+070860               S0      
317PE_TX4_DR8_N     VIA        MD0100PA00X+002753Y+083124               S0      
327PE_TX4_DR8_P                       A01X+000886Y+083442X0980Y0200     S0      
327PE_TX4_DR8_P                       A01X+015433Y+071177X0790Y0200     S0      
317PE_TX4_DR8_P     VIA        MD0100PA00X+013909Y+071180               S0      
317PE_TX4_DR8_P     VIA        MD0100PA00X+002753Y+083444               S0      
327PE_TX1_DR4_N                       A01X+000886Y+089426X0980Y0200     S0      
327PE_TX1_DR4_N                       A01X+088268Y+021492X0790Y0200     S0      
317PE_TX1_DR4_N     VIA        MD0100PA00X+002753Y+089424               S0      
317PE_TX1_DR4_N     VIA        MD0100PA00X+086744Y+021490               S0      
327PE_TX1_DR4_P                       A01X+000886Y+089741X0980Y0200     S0      
327PE_TX1_DR4_P                       A01X+088268Y+021807X0790Y0200     S0      
317PE_TX1_DR4_P     VIA        MD0100PA00X+002753Y+089744               S0      
317PE_TX1_DR4_P     VIA        MD0100PA00X+086744Y+021810               S0      
327PE_TX2_DR4_N                       A01X+000886Y+090686X0980Y0200     S0      
327PE_TX2_DR4_N                       A01X+088268Y+026532X0790Y0200     S0      
317PE_TX2_DR4_N     VIA        MD0100PA00X+002753Y+090683               S0      
317PE_TX2_DR4_N     VIA        MD0100PA00X+086744Y+026529               S0      
327PE_TX2_DR4_P                       A01X+000886Y+091001X0980Y0200     S0      
327PE_TX2_DR4_P                       A01X+088268Y+026846X0790Y0200     S0      
317PE_TX2_DR4_P     VIA        MD0100PA00X+002753Y+091003               S0      
317PE_TX2_DR4_P     VIA        MD0100PA00X+086744Y+026849               S0      
327TRAY_ID_R                          A01X+000886Y+091631X0980Y0200     S0      
317TRAY_ID_R                    D0220PA01X+004500Y+106080               S0      
317TRAY_ID_R        VIA        MD0120PA00X+004500Y+105700               S0      
317TRAY_ID_R        VIA        MD0100PA00X+003000Y+099100               S0      
327NNAME00185                         A01X+000886Y+091946X0980Y0200     S0      
317NNAME00185                   D0220PA01X+004100Y+106080               S0      
317NNAME00185       VIA        MD0120PA00X+002783Y+099500               S0      
317NNAME00185       VIA        MD0100PA00X+004100Y+105750               S0      
327PCIE_MATED#_B                      A01X+000886Y+092261X0980Y0200     S0      
327PCIE_MATED#_B                      A01X+003171Y+106279X1100Y0450     S0      
317PCIE_MATED#_B    VIA        MD0120PA00X+002500Y+098800               S0      
317PCIE_MATED#_B    VIA        MD0100PA00X+002329Y+106279               S0      
327NNAME00186                         A08X+000886Y+059820X0980Y0200     S0      
327NNAME00186                         A01X+009773Y+024442X0480Y0160     S0      
317NNAME00186                   D0220PA01X+008359Y+023442               S0      
317NNAME00186                   D0220PA01X+008759Y+023442               S0      
317NNAME00186       VIA        MD0280PA08X+007390Y+026950               S0      
317NNAME00186       VIA        MD0100PA00X+008030Y+023447               S0      
327SSD14_PWREN                        A08X+000886Y+060135X0980Y0200     S0      
317SSD14_PWREN                  D0220PA01X+020902Y+002373               S0      
317SSD14_PWREN                  D0220PA01X+020000Y+002880               S0      
317SSD14_PWREN                  D0220PA01X+020450Y+002880               S0      
317SSD14_PWREN                  D0300PA01X+019313Y+003875               S0      
317SSD14_PWREN      VIA        MD0120PA00X+021324Y+002373               S0      
327PE_RX1_DR9_N                       A08X+000886Y+070843X0980Y0200     S0      
327PE_RX1_DR9_N                       A01X+015433Y+022437X0790Y0200     S0      
317PE_RX1_DR9_N     VIA        MD0100PA00X+014460Y+022375               S0      
317PE_RX1_DR9_N     VIA        MD0100PA00X+002000Y+070841               S0      
327PE_RX1_DR9_P                       A08X+000886Y+071158X0980Y0200     S0      
327PE_RX1_DR9_P                       A01X+015433Y+022752X0790Y0200     S0      
317PE_RX1_DR9_P     VIA        MD0100PA00X+014460Y+022815               S0      
317PE_RX1_DR9_P     VIA        MD0100PA00X+002000Y+071161               S0      
327PE_RX2_DR9_N                       A08X+000886Y+072103X0980Y0200     S0      
327PE_RX2_DR9_N                       A01X+015433Y+027476X0790Y0200     S0      
317PE_RX2_DR9_N     VIA        MD0100PA00X+014460Y+027414               S0      
317PE_RX2_DR9_N     VIA        MD0100PA00X+002000Y+072101               S0      
327PE_RX2_DR9_P                       A08X+000886Y+072418X0980Y0200     S0      
327PE_RX2_DR9_P                       A01X+015433Y+027791X0790Y0200     S0      
317PE_RX2_DR9_P     VIA        MD0100PA00X+014460Y+027854               S0      
317PE_RX2_DR9_P     VIA        MD0100PA00X+002000Y+072421               S0      
327SSD4_PERST_N                       A08X+000886Y+073363X0980Y0200     S0      
327SSD4_PERST_N                       A01X+089524Y+024799X0790Y0200     S0      
327SSD4_PERST_N                       A01X+089524Y+025114X0790Y0200     S0      
317SSD4_PERST_N     VIA        MD0280PA01X+003909Y+065061               S0      
317SSD4_PERST_N     VIA        MD0100PA00X+002770Y+073754               S0      
317SSD4_PERST_N     VIA        MD0100PA00X+006661Y+029596               S0      
317SSD4_PERST_N     VIA        MD0100PA00X+090160Y+024980               S0      
327PE_RX3_DR9_N                       A08X+000886Y+075253X0980Y0200     S0      
327PE_RX3_DR9_N                       A01X+015433Y+029366X0790Y0200     S0      
317PE_RX3_DR9_N     VIA        MD0100PA00X+014460Y+029304               S0      
317PE_RX3_DR9_N     VIA        MD0100PA00X+002000Y+075250               S0      
327PE_RX3_DR9_P                       A08X+000886Y+075568X0980Y0200     S0      
327PE_RX3_DR9_P                       A01X+015433Y+029681X0790Y0200     S0      
317PE_RX3_DR9_P     VIA        MD0100PA00X+014460Y+029744               S0      
317PE_RX3_DR9_P     VIA        MD0100PA00X+002000Y+075570               S0      
327PE_RX4_DR9_N                       A08X+000886Y+076513X0980Y0200     S0      
327PE_RX4_DR9_N                       A01X+015433Y+031256X0790Y0200     S0      
317PE_RX4_DR9_N     VIA        MD0100PA00X+014460Y+031193               S0      
317PE_RX4_DR9_N     VIA        MD0100PA00X+002000Y+076510               S0      
327PE_RX4_DR9_P                       A08X+000886Y+076828X0980Y0200     S0      
327PE_RX4_DR9_P                       A01X+015433Y+031571X0790Y0200     S0      
317PE_RX4_DR9_P     VIA        MD0100PA00X+014460Y+031633               S0      
317PE_RX4_DR9_P     VIA        MD0100PA00X+002000Y+076830               S0      
327ATTN_LED_DR4_N                     A08X+000886Y+077773X0980Y0200     S0      
327ATTN_LED_DR4_N                     A01X+089225Y+013745X0480Y0160     S0      
317ATTN_LED_DR4_N               D0220PA01X+088970Y+016100               S0      
317ATTN_LED_DR4_N               D0220PA01X+088970Y+015700               S0      
317ATTN_LED_DR4_N   VIA        MD0280PA08X+003700Y+076200               S0      
317ATTN_LED_DR4_N   VIA        MD0100PA00X+089047Y+016480               S0      
327SSD4_PWREN                         A08X+000886Y+078087X0980Y0200     S0      
317SSD4_PWREN                   D0220PA01X+082100Y+037270               S0      
317SSD4_PWREN                   D0220PA01X+081650Y+037270               S0      
317SSD4_PWREN                   D0220PA01X+081198Y+037778               S0      
317SSD4_PWREN                   D0300PA01X+082788Y+036275               S0      
317SSD4_PWREN       VIA        MD0120PA00X+080776Y+037778               S0      
327PE_RX1_DR8_N                       A08X+000886Y+078717X0980Y0200     S0      
327PE_RX1_DR8_N                       A01X+015433Y+062988X0790Y0200     S0      
317PE_RX1_DR8_N     VIA        MD0100PA00X+014460Y+062926               S0      
317PE_RX1_DR8_N     VIA        MD0100PA00X+002000Y+078715               S0      
327PE_RX1_DR8_P                       A08X+000886Y+079032X0980Y0200     S0      
327PE_RX1_DR8_P                       A01X+015433Y+063303X0790Y0200     S0      
317PE_RX1_DR8_P     VIA        MD0100PA00X+014460Y+063366               S0      
317PE_RX1_DR8_P     VIA        MD0100PA00X+002000Y+079035               S0      
327PE_RX2_DR8_N                       A08X+000886Y+079977X0980Y0200     S0      
327PE_RX2_DR8_N                       A01X+015433Y+068028X0790Y0200     S0      
317PE_RX2_DR8_N     VIA        MD0100PA00X+014460Y+067965               S0      
317PE_RX2_DR8_N     VIA        MD0100PA00X+002000Y+079975               S0      
327PE_RX2_DR8_P                       A08X+000886Y+080292X0980Y0200     S0      
327PE_RX2_DR8_P                       A01X+015433Y+068343X0790Y0200     S0      
317PE_RX2_DR8_P     VIA        MD0100PA00X+014460Y+068405               S0      
317PE_RX2_DR8_P     VIA        MD0100PA00X+002000Y+080295               S0      
327PE_RX3_DR8_N                       A08X+000886Y+081237X0980Y0200     S0      
327PE_RX3_DR8_N                       A01X+015433Y+069917X0790Y0200     S0      
317PE_RX3_DR8_N     VIA        MD0100PA00X+014460Y+069855               S0      
317PE_RX3_DR8_N     VIA        MD0100PA00X+002000Y+081234               S0      
327PE_RX3_DR8_P                       A08X+000886Y+081552X0980Y0200     S0      
327PE_RX3_DR8_P                       A01X+015433Y+070232X0790Y0200     S0      
317PE_RX3_DR8_P     VIA        MD0100PA00X+014460Y+070295               S0      
317PE_RX3_DR8_P     VIA        MD0100PA00X+002000Y+081554               S0      
327PE_RX4_DR8_N                       A08X+000886Y+082497X0980Y0200     S0      
327PE_RX4_DR8_N                       A01X+015433Y+071807X0790Y0200     S0      
317PE_RX4_DR8_N     VIA        MD0100PA00X+014460Y+071745               S0      
317PE_RX4_DR8_N     VIA        MD0100PA00X+002000Y+082494               S0      
327PE_RX4_DR8_P                       A08X+000886Y+082812X0980Y0200     S0      
327PE_RX4_DR8_P                       A01X+015433Y+072122X0790Y0200     S0      
317PE_RX4_DR8_P     VIA        MD0100PA00X+014460Y+072185               S0      
317PE_RX4_DR8_P     VIA        MD0100PA00X+002000Y+082814               S0      
327ATTN_LED_DR8_N                     A08X+000886Y+088796X0980Y0200     S0      
327ATTN_LED_DR8_N                     A01X+015350Y+055675X0160Y0480     S0      
317ATTN_LED_DR8_N               D0220PA01X+015450Y+054470               S0      
317ATTN_LED_DR8_N               D0220PA01X+015000Y+054470               S0      
317ATTN_LED_DR8_N   VIA        MD0280PA08X+004339Y+080350               S0      
317ATTN_LED_DR8_N   VIA        MD0100PA00X+015775Y+054475               S0      
327SSD8_PWREN                         A08X+000886Y+089111X0980Y0200     S0      
317SSD8_PWREN                   D0220PA01X+008548Y+078328               S0      
317SSD8_PWREN                   D0220PA01X+009450Y+077820               S0      
317SSD8_PWREN                   D0220PA01X+009000Y+077820               S0      
317SSD8_PWREN                   D0300PA01X+009958Y+076825               S0      
317SSD8_PWREN       VIA        MD0280PA08X+008022Y+078790               S0      
317SSD8_PWREN       VIA        MD0100PA00X+008022Y+077714               S0      
327SSD8_PERST_N                       A08X+000886Y+089426X0980Y0200     S0      
327SSD8_PERST_N                       A01X+016689Y+065350X0790Y0200     S0      
327SSD8_PERST_N                       A01X+016689Y+065665X0790Y0200     S0      
317SSD8_PERST_N     VIA        MD0280PA01X+004356Y+077694               S0      
317SSD8_PERST_N     VIA        MD0100PA00X+017300Y+065520               S0      
317SSD8_PERST_N     VIA        MD0100PA00X+003487Y+089091               S0      
317SSD8_PERST_N     VIA        MD0100PA00X+004950Y+077100               S0      
327PE_RX1_DR4_N                       A08X+000886Y+090056X0980Y0200     S0      
327PE_RX1_DR4_N                       A01X+088268Y+022437X0790Y0200     S0      
317PE_RX1_DR4_N     VIA        MD0100PA00X+002000Y+090053               S0      
317PE_RX1_DR4_N     VIA        MD0100PA00X+087294Y+022375               S0      
327PE_RX1_DR4_P                       A08X+000886Y+090371X0980Y0200     S0      
327PE_RX1_DR4_P                       A01X+088268Y+022752X0790Y0200     S0      
317PE_RX1_DR4_P     VIA        MD0100PA00X+002000Y+090373               S0      
317PE_RX1_DR4_P     VIA        MD0100PA00X+087294Y+022815               S0      
327PE_RX2_DR4_N                       A08X+000886Y+091316X0980Y0200     S0      
327PE_RX2_DR4_N                       A01X+088268Y+027476X0790Y0200     S0      
317PE_RX2_DR4_N     VIA        MD0100PA00X+002000Y+091313               S0      
317PE_RX2_DR4_N     VIA        MD0100PA00X+087294Y+027414               S0      
327PE_RX2_DR4_P                       A08X+000886Y+091631X0980Y0200     S0      
327PE_RX2_DR4_P                       A01X+088268Y+027791X0790Y0200     S0      
317PE_RX2_DR4_P     VIA        MD0100PA00X+002000Y+091633               S0      
317PE_RX2_DR4_P     VIA        MD0100PA00X+087294Y+027854               S0      
327NNAME00187                         A08X+000886Y+092261X0980Y0200     S0      
317NNAME00187                   D0220PA01X+032580Y+060900               S0      
317NNAME00187       VIA        MD0280PA08X+004100Y+090800               S0      
317NNAME00187       VIA        MD0100PA00X+004750Y+090150               S0      
317NNAME00188                   D0220PA01X+037600Y+116580               S0      
327NNAME00188                         A01X+089524Y+104957X0790Y0200     S0      
317NNAME00188       VIA        MD0100PA00X+090515Y+104642               S0      
317NNAME00188       VIA        MD0100PA00X+091885Y+105273               S0      
317NNAME00189                   D0220PA01X+038000Y+116580               S0      
327NNAME00189                         A01X+089524Y+105272X0790Y0200     S0      
317NNAME00189       VIA        MD0100PA00X+090835Y+104642               S0      
317NNAME00189       VIA        MD0100PA00X+091885Y+104953               S0      
317NNAME00190                   D0220PA01X+039100Y+116580               S0      
327NNAME00190                         A01X+088268Y+101650X0790Y0200     S0      
317NNAME00191                   D0220PA01X+039500Y+116580               S0      
327NNAME00191                         A01X+088268Y+101965X0790Y0200     S0      
317SCL_DR2_R                    D0220PA01X+085620Y+113200               S0      
327SCL_DR2_R                          A01X+088268Y+113303X0790Y0200     S0      
317SCL_DR2_R        VIA        MD0280PA01X+086424Y+113060               S0      
317SDA_DR2_R                    D0220PA01X+085620Y+113700               S0      
327SDA_DR2_R                          A01X+088268Y+113618X0790Y0200     S0      
317SDA_DR2_R        VIA        MD0280PA01X+086424Y+113810               S0      
317DUALPORTEN#2                 D0220PA01X+085450Y+114220               S0      
317DUALPORTEN#2                 D0220PA01X+084460Y+114220               S0      
327DUALPORTEN#2                       A01X+088268Y+113933X0790Y0200     S0      
317DUALPORTEN#2     VIA        MD0280PA01X+084955Y+114215               S0      
317SSD2_CLK0_OE_N               D0220PA01X+038850Y+114680               S0      
317SSD2_CLK0_OE_N               D0220PA01X+038830Y+114250               S0      
327SSD2_CLK0_OE_N                     A01X+089360Y+108494X0810Y0260     S0      
317SSD2_CLK0_OE_N   VIA        MD0280PA01X+038825Y+113750               S0      
317SSD_PRSNT_NET2               D0220PA01X+038050Y+114680               S0      
317SSD_PRSNT_NET2               D0220PA01X+038030Y+114250               S0      
327SSD_PRSNT_NET2                     A01X+089360Y+111494X0810Y0260     S0      
317SSD_PRSNT_NET2   VIA        MD0280PA01X+038025Y+113760               S0      
317SSD_ACT_DR2                  D0220PA01X+089865Y+096168               S0      
317SSD_ACT_DR2                  D0220PA01X+090630Y+095748               S0      
327SSD_ACT_DR2                        A01X+089360Y+111994X0810Y0260     S0      
317SSD_ACT_DR2      VIA        MD0280PA01X+090373Y+096221               S0      
317SSD_ACT_DR2      VIA        MD0100PA00X+089555Y+096183               S0      
317SSD_ACT_DR2      VIA        MD0100PA00X+089994Y+111994               S0      
32712V_PRECH_SSD2                     A01X+091205Y+118060X0450Y1100     S0      
32712V_PRECH_SSD2                     A01X+089360Y+112994X0810Y0260     S0      
31712V_PRECH_SSD2   VIA        MD0280PA01X+091910Y+118060               S0      
327P12V_SSD2                          A01X+086620Y+115698X0830Y0570     S0      
327P12V_SSD2                          A01X+086600Y+116552X0830Y0570     S0      
327P12V_SSD2                          A01X+089355Y+118060X0450Y1100     S0      
327P12V_SSD2                          A01X+085550Y+115350X0650Y0250     S0      
327P12V_SSD2                          A01X+085550Y+115850X0650Y0250     S0      
327P12V_SSD2                          A01X+085550Y+116350X0650Y0250     S0      
327P12V_SSD2                          A01X+085550Y+116850X0650Y0250     S0      
327P12V_SSD2                          A01X+087390Y+118740X0450Y0550     S0      
317P12V_SSD2                    D0340PA01X+087450Y+116920               S0      
317P12V_SSD2                    D0240PA01X+087410Y+115130               S0      
327P12V_SSD2                          A01X+089360Y+113494X0810Y0260     S0      
327P12V_SSD2                          A01X+089360Y+113994X0810Y0260     S0      
317P12V_SSD2        VIA        MD0280PA01X+088050Y+117850               S0      
317P12V_SSD2        VIA        MD0280PA01X+088640Y+118500               S0      
317NNAME00192                   D0220PA01X+040570Y+080500               S0      
327NNAME00192                         A01X+089524Y+064406X0790Y0200     S0      
317NNAME00192       VIA        MD0100PA00X+090515Y+064091               S0      
317NNAME00192       VIA        MD0100PA00X+091885Y+064721               S0      
317NNAME00193                   D0220PA01X+040570Y+080900               S0      
327NNAME00193                         A01X+089524Y+064721X0790Y0200     S0      
317NNAME00193       VIA        MD0100PA00X+090835Y+064091               S0      
317NNAME00193       VIA        MD0100PA00X+091885Y+064401               S0      
317NNAME00194                   D0220PA01X+040570Y+082000               S0      
327NNAME00194                         A01X+088268Y+061098X0790Y0200     S0      
317NNAME00195                   D0220PA01X+040570Y+082400               S0      
327NNAME00195                         A01X+088268Y+061413X0790Y0200     S0      
317SCL_DR3_R                    D0220PA01X+085620Y+072650               S0      
327SCL_DR3_R                          A01X+088268Y+072752X0790Y0200     S0      
317SCL_DR3_R        VIA        MD0280PA01X+086384Y+072509               S0      
317SDA_DR3_R                    D0220PA01X+085620Y+073150               S0      
327SDA_DR3_R                          A01X+088268Y+073067X0790Y0200     S0      
317SDA_DR3_R        VIA        MD0280PA01X+086384Y+073259               S0      
317DUALPORTEN#3                 D0220PA01X+085610Y+073680               S0      
317DUALPORTEN#3                 D0220PA01X+084620Y+073680               S0      
327DUALPORTEN#3                       A01X+088268Y+073382X0790Y0200     S0      
317DUALPORTEN#3     VIA        MD0280PA01X+085115Y+073675               S0      
317SSD3_CLK0_OE_N               D0220PA01X+042470Y+081750               S0      
317SSD3_CLK0_OE_N               D0220PA01X+042900Y+081730               S0      
327SSD3_CLK0_OE_N                     A01X+089360Y+067943X0810Y0260     S0      
317SSD3_CLK0_OE_N   VIA        MD0280PA01X+043400Y+081725               S0      
317SSD_PRSNT_NET3               D0220PA01X+042470Y+080950               S0      
317SSD_PRSNT_NET3               D0220PA01X+042900Y+080930               S0      
327SSD_PRSNT_NET3                     A01X+089360Y+070943X0810Y0260     S0      
317SSD_PRSNT_NET3   VIA        MD0280PA01X+043390Y+080925               S0      
317SSD_ACT_DR3                  D0220PA01X+089875Y+055617               S0      
317SSD_ACT_DR3                  D0220PA01X+090630Y+055197               S0      
327SSD_ACT_DR3                        A01X+089360Y+071443X0810Y0260     S0      
317SSD_ACT_DR3      VIA        MD0280PA01X+090373Y+055669               S0      
317SSD_ACT_DR3      VIA        MD0100PA00X+089555Y+055632               S0      
317SSD_ACT_DR3      VIA        MD0100PA00X+089994Y+071443               S0      
32712V_PRECH_SSD3                     A01X+090795Y+077460X0450Y1100     S0      
32712V_PRECH_SSD3                     A01X+089360Y+072443X0810Y0260     S0      
31712V_PRECH_SSD3   VIA        MD0280PA01X+091580Y+077460               S0      
327P12V_SSD3                          A01X+086610Y+075128X0830Y0570     S0      
327P12V_SSD3                          A01X+087400Y+076002X0830Y0570     S0      
327P12V_SSD3                          A01X+088945Y+077460X0450Y1100     S0      
327P12V_SSD3                          A01X+085550Y+074800X0650Y0250     S0      
327P12V_SSD3                          A01X+085550Y+075300X0650Y0250     S0      
327P12V_SSD3                          A01X+085550Y+075800X0650Y0250     S0      
327P12V_SSD3                          A01X+085550Y+076300X0650Y0250     S0      
327P12V_SSD3                          A01X+087390Y+078190X0450Y0550     S0      
317P12V_SSD3                    D0340PA01X+086500Y+076310               S0      
317P12V_SSD3                    D0240PA01X+087410Y+074680               S0      
327P12V_SSD3                          A01X+089360Y+072943X0810Y0260     S0      
327P12V_SSD3                          A01X+089360Y+073443X0810Y0260     S0      
317P12V_SSD3        VIA        MD0280PA01X+088200Y+077300               S0      
317P12V_SSD3        VIA        MD0280PA01X+089480Y+078390               S0      
317NNAME00196                   D0220PA01X+036950Y+079430               S0      
327NNAME00196                         A01X+089524Y+023854X0790Y0200     S0      
317NNAME00196       VIA        MD0100PA00X+090515Y+023539               S0      
317NNAME00196       VIA        MD0100PA00X+091885Y+024170               S0      
317NNAME00197                   D0220PA01X+037350Y+079430               S0      
327NNAME00197                         A01X+089524Y+024169X0790Y0200     S0      
317NNAME00197       VIA        MD0100PA00X+090835Y+023539               S0      
317NNAME00197       VIA        MD0100PA00X+091885Y+023850               S0      
317NNAME00198                   D0220PA01X+038450Y+079430               S0      
327NNAME00198                         A01X+088268Y+020547X0790Y0200     S0      
317NNAME00199                   D0220PA01X+038850Y+079430               S0      
327NNAME00199                         A01X+088268Y+020862X0790Y0200     S0      
317SCL_DR4_R                    D0220PA01X+085620Y+032100               S0      
327SCL_DR4_R                          A01X+088268Y+032201X0790Y0200     S0      
317SCL_DR4_R        VIA        MD0280PA01X+086394Y+031958               S0      
317SDA_DR4_R                    D0220PA01X+085620Y+032600               S0      
327SDA_DR4_R                          A01X+088268Y+032516X0790Y0200     S0      
317SDA_DR4_R        VIA        MD0280PA01X+086394Y+032708               S0      
317DUALPORTEN#4                 D0220PA01X+085620Y+033080               S0      
317DUALPORTEN#4                 D0220PA01X+084405Y+033080               S0      
327DUALPORTEN#4                       A01X+088268Y+032831X0790Y0200     S0      
317DUALPORTEN#4     VIA        MD0280PA01X+085012Y+033075               S0      
317SSD4_CLK0_OE_N               D0220PA01X+038200Y+077530               S0      
317SSD4_CLK0_OE_N               D0220PA01X+038180Y+077100               S0      
327SSD4_CLK0_OE_N                     A01X+089360Y+027392X0810Y0260     S0      
317SSD4_CLK0_OE_N   VIA        MD0280PA01X+038175Y+076600               S0      
317SSD_PRSNT_NET4               D0220PA01X+037400Y+077530               S0      
317SSD_PRSNT_NET4               D0220PA01X+037380Y+077100               S0      
327SSD_PRSNT_NET4                     A01X+089360Y+030392X0810Y0260     S0      
317SSD_PRSNT_NET4   VIA        MD0280PA01X+037375Y+076610               S0      
317SSD_ACT_DR4                  D0220PA01X+089965Y+015065               S0      
317SSD_ACT_DR4                  D0220PA01X+090730Y+014645               S0      
327SSD_ACT_DR4                        A01X+089360Y+030892X0810Y0260     S0      
317SSD_ACT_DR4      VIA        MD0280PA01X+090473Y+015118               S0      
317SSD_ACT_DR4      VIA        MD0100PA00X+089655Y+015080               S0      
317SSD_ACT_DR4      VIA        MD0100PA00X+089994Y+030892               S0      
32712V_PRECH_SSD4                     A01X+090825Y+036860X0450Y1100     S0      
32712V_PRECH_SSD4                     A01X+089360Y+031892X0810Y0260     S0      
31712V_PRECH_SSD4   VIA        MD0280PA01X+091590Y+036860               S0      
327P12V_SSD4                          A01X+086630Y+034598X0830Y0570     S0      
327P12V_SSD4                          A01X+087400Y+035452X0830Y0570     S0      
327P12V_SSD4                          A01X+088975Y+036860X0450Y1100     S0      
327P12V_SSD4                          A01X+085550Y+034250X0650Y0250     S0      
327P12V_SSD4                          A01X+085550Y+034750X0650Y0250     S0      
327P12V_SSD4                          A01X+085550Y+035250X0650Y0250     S0      
327P12V_SSD4                          A01X+085550Y+035750X0650Y0250     S0      
327P12V_SSD4                          A01X+087440Y+037640X0450Y0550     S0      
317P12V_SSD4                    D0340PA01X+086550Y+035720               S0      
317P12V_SSD4                    D0240PA01X+087420Y+034030               S0      
327P12V_SSD4                          A01X+089360Y+032392X0810Y0260     S0      
327P12V_SSD4                          A01X+089360Y+032892X0810Y0260     S0      
317P12V_SSD4        VIA        MD0280PA01X+088250Y+036700               S0      
317P12V_SSD4        VIA        MD0280PA01X+089490Y+037730               S0      
317NNAME00200                   D0220PA01X+035950Y+173570               S0      
327NNAME00200                         A01X+016689Y+186059X0790Y0200     S0      
317NNAME00200       VIA        MD0100PA00X+017680Y+185744               S0      
317NNAME00200       VIA        MD0100PA00X+019050Y+186375               S0      
317NNAME00201                   D0220PA01X+035550Y+173570               S0      
327NNAME00201                         A01X+016689Y+186374X0790Y0200     S0      
317NNAME00201       VIA        MD0100PA00X+018000Y+185744               S0      
317NNAME00201       VIA        MD0100PA00X+019050Y+186055               S0      
317NNAME00202                   D0220PA01X+034450Y+173570               S0      
327NNAME00202                         A01X+015433Y+182752X0790Y0200     S0      
317NNAME00203                   D0220PA01X+034050Y+173570               S0      
327NNAME00203                         A01X+015433Y+183067X0790Y0200     S0      
317SCL_DR5_R                    D0220PA01X+012650Y+193410               S0      
327SCL_DR5_R                          A01X+015433Y+194406X0790Y0200     S0      
317SCL_DR5_R        VIA        MD0280PA01X+013180Y+193283               S0      
317SDA_DR5_R                    D0220PA01X+012650Y+193910               S0      
327SDA_DR5_R                          A01X+015433Y+194721X0790Y0200     S0      
317SDA_DR5_R        VIA        MD0280PA01X+013180Y+194033               S0      
317DUALPORTEN#5                 D0220PA01X+012650Y+194380               S0      
317DUALPORTEN#5                 D0220PA01X+012240Y+194390               S0      
327DUALPORTEN#5                       A01X+015433Y+195036X0790Y0200     S0      
317DUALPORTEN#5     VIA        MD0280PA01X+013810Y+194600               S0      
317SSD5_CLK0_OE_N               D0220PA01X+034700Y+175470               S0      
317SSD5_CLK0_OE_N               D0220PA01X+034720Y+175900               S0      
327SSD5_CLK0_OE_N                     A01X+016526Y+189597X0810Y0260     S0      
317SSD5_CLK0_OE_N   VIA        MD0280PA01X+034725Y+176400               S0      
317SSD_PRSNT_NET5               D0220PA01X+035500Y+175470               S0      
317SSD_PRSNT_NET5               D0220PA01X+035520Y+175900               S0      
327SSD_PRSNT_NET5                     A01X+016526Y+192597X0810Y0260     S0      
317SSD_PRSNT_NET5   VIA        MD0280PA01X+035525Y+176390               S0      
317SSD_ACT_DR5                  D0220PA01X+020020Y+175880               S0      
317SSD_ACT_DR5                  D0220PA01X+019475Y+175305               S0      
327SSD_ACT_DR5                        A01X+016526Y+193096X0810Y0260     S0      
317SSD_ACT_DR5      VIA        MD0280PA01X+020145Y+175150               S0      
317SSD_ACT_DR5      VIA        MD0100PA00X+017160Y+193096               S0      
317SSD_ACT_DR5      VIA        MD0100PA00X+020330Y+175975               S0      
32712V_PRECH_SSD5                     A01X+014345Y+196520X0450Y1100     S0      
32712V_PRECH_SSD5                     A01X+016526Y+194097X0810Y0260     S0      
31712V_PRECH_SSD5   VIA        MD0280PA01X+014345Y+197566               S0      
327P12V_SSD5                          A01X+009740Y+195722X0830Y0570     S0      
327P12V_SSD5                          A01X+010990Y+195722X0830Y0570     S0      
327P12V_SSD5                          A01X+012495Y+196520X0450Y1100     S0      
327P12V_SSD5                          A01X+009950Y+193400X0650Y0250     S0      
327P12V_SSD5                          A01X+009950Y+193900X0650Y0250     S0      
327P12V_SSD5                          A01X+009950Y+194400X0650Y0250     S0      
327P12V_SSD5                          A01X+009950Y+194900X0650Y0250     S0      
327P12V_SSD5                          A01X+008720Y+196800X0550Y0450     S0      
317P12V_SSD5                    D0340PA01X+011850Y+196180               S0      
317P12V_SSD5                    D0240PA01X+013320Y+195450               S0      
327P12V_SSD5                          A01X+016526Y+194597X0810Y0260     S0      
327P12V_SSD5                          A01X+016526Y+195097X0810Y0260     S0      
317P12V_SSD5        VIA        MD0280PA01X+010910Y+193630               S0      
317P12V_SSD5        VIA        MD0280PA01X+010950Y+194770               S0      
317P12V_SSD5        VIA        MD0100PA00X+013680Y+195990               S0      
317P12V_SSD5        VIA        MD0100PA00X+013730Y+196990               S0      
317P12V_SSD5        VIA        MD0100PA00X+015060Y+197030               S0      
317P12V_SSD5        VIA        MD0100PA00X+015080Y+195890               S0      
317NNAME00204                   D0220PA01X+039500Y+123720               S0      
327NNAME00204                         A01X+016689Y+145508X0790Y0200     S0      
317NNAME00204       VIA        MD0100PA00X+017680Y+145193               S0      
317NNAME00204       VIA        MD0100PA00X+019050Y+145824               S0      
317NNAME00205                   D0220PA01X+039100Y+123720               S0      
327NNAME00205                         A01X+016689Y+145823X0790Y0200     S0      
317NNAME00205       VIA        MD0100PA00X+018000Y+145193               S0      
317NNAME00205       VIA        MD0100PA00X+019050Y+145504               S0      
317NNAME00206                   D0220PA01X+038000Y+123720               S0      
327NNAME00206                         A01X+015433Y+142201X0790Y0200     S0      
317NNAME00207                   D0220PA01X+037600Y+123720               S0      
327NNAME00207                         A01X+015433Y+142516X0790Y0200     S0      
317SCL_DR6_R                    D0220PA01X+012820Y+153750               S0      
327SCL_DR6_R                          A01X+015433Y+153854X0790Y0200     S0      
317SCL_DR6_R        VIA        MD0280PA01X+013569Y+153611               S0      
317SDA_DR6_R                    D0220PA01X+012820Y+154250               S0      
327SDA_DR6_R                          A01X+015433Y+154169X0790Y0200     S0      
317SDA_DR6_R        VIA        MD0280PA01X+013569Y+154361               S0      
317DUALPORTEN#6                 D0220PA01X+011250Y+154820               S0      
317DUALPORTEN#6                 D0220PA01X+011250Y+154370               S0      
327DUALPORTEN#6                       A01X+015433Y+154484X0790Y0200     S0      
317DUALPORTEN#6     VIA        MD0280PA01X+012250Y+154740               S0      
317SSD6_CLK0_OE_N               D0220PA01X+038250Y+125620               S0      
317SSD6_CLK0_OE_N               D0220PA01X+038270Y+126050               S0      
327SSD6_CLK0_OE_N                     A01X+016526Y+149045X0810Y0260     S0      
317SSD6_CLK0_OE_N   VIA        MD0280PA01X+038275Y+126550               S0      
317SSD_PRSNT_NET6               D0220PA01X+039050Y+125620               S0      
317SSD_PRSNT_NET6               D0220PA01X+039070Y+126050               S0      
327SSD_PRSNT_NET6                     A01X+016526Y+152045X0810Y0260     S0      
317SSD_PRSNT_NET6   VIA        MD0280PA01X+039075Y+126540               S0      
317SSD_ACT_DR6                  D0220PA01X+017040Y+136669               S0      
317SSD_ACT_DR6                  D0220PA01X+017795Y+136249               S0      
327SSD_ACT_DR6                        A01X+016526Y+152545X0810Y0260     S0      
317SSD_ACT_DR6      VIA        MD0280PA01X+017555Y+136716               S0      
317SSD_ACT_DR6      VIA        MD0100PA00X+016730Y+136684               S0      
317SSD_ACT_DR6      VIA        MD0100PA00X+017160Y+152545               S0      
32712V_PRECH_SSD6                     A01X+017965Y+158570X0450Y1100     S0      
32712V_PRECH_SSD6                     A01X+016526Y+153545X0810Y0260     S0      
31712V_PRECH_SSD6   VIA        MD0280PA01X+018670Y+158570               S0      
327P12V_SSD6                          A01X+013760Y+156178X0830Y0570     S0      
327P12V_SSD6                          A01X+014550Y+157102X0830Y0570     S0      
327P12V_SSD6                          A01X+016115Y+158570X0450Y1100     S0      
327P12V_SSD6                          A01X+012670Y+155410X0650Y0250     S0      
327P12V_SSD6                          A01X+012670Y+155910X0650Y0250     S0      
327P12V_SSD6                          A01X+012670Y+156410X0650Y0250     S0      
327P12V_SSD6                          A01X+012670Y+156910X0650Y0250     S0      
327P12V_SSD6                          A01X+012973Y+158873X0550Y0450     S0      
317P12V_SSD6                    D0340PA01X+013670Y+157420               S0      
317P12V_SSD6                    D0240PA01X+014580Y+155410               S0      
327P12V_SSD6                          A01X+016526Y+154045X0810Y0260     S0      
327P12V_SSD6                          A01X+016526Y+154545X0810Y0260     S0      
317P12V_SSD6        VIA        MD0280PA01X+015490Y+159130               S0      
317P12V_SSD6        VIA        MD0280PA01X+015500Y+158380               S0      
317NNAME00208                   D0220PA01X+039500Y+086570               S0      
327NNAME00208                         A01X+016689Y+104957X0790Y0200     S0      
317NNAME00208       VIA        MD0100PA00X+017680Y+104642               S0      
317NNAME00208       VIA        MD0100PA00X+019050Y+105273               S0      
317NNAME00209                   D0220PA01X+039100Y+086570               S0      
327NNAME00209                         A01X+016689Y+105272X0790Y0200     S0      
317NNAME00209       VIA        MD0100PA00X+018000Y+104642               S0      
317NNAME00209       VIA        MD0100PA00X+019050Y+104953               S0      
317NNAME00210                   D0220PA01X+038000Y+086570               S0      
327NNAME00210                         A01X+015433Y+101650X0790Y0200     S0      
317NNAME00211                   D0220PA01X+037600Y+086570               S0      
327NNAME00211                         A01X+015433Y+101965X0790Y0200     S0      
317SCL_DR7_R                    D0220PA01X+012820Y+113200               S0      
327SCL_DR7_R                          A01X+015433Y+113303X0790Y0200     S0      
317SCL_DR7_R        VIA        MD0280PA01X+013590Y+113060               S0      
317SDA_DR7_R                    D0220PA01X+012820Y+113700               S0      
327SDA_DR7_R                          A01X+015433Y+113618X0790Y0200     S0      
317SDA_DR7_R        VIA        MD0280PA01X+013590Y+113810               S0      
317DUALPORTEN#7                 D0220PA01X+012240Y+114260               S0      
317DUALPORTEN#7                 D0220PA01X+011790Y+114260               S0      
327DUALPORTEN#7                       A01X+015433Y+113933X0790Y0200     S0      
317DUALPORTEN#7     VIA        MD0280PA01X+012750Y+114250               S0      
317SSD7_CLK0_OE_N               D0220PA01X+038250Y+088470               S0      
317SSD7_CLK0_OE_N               D0220PA01X+038270Y+088900               S0      
327SSD7_CLK0_OE_N                     A01X+016526Y+108494X0810Y0260     S0      
317SSD7_CLK0_OE_N   VIA        MD0280PA01X+038275Y+089400               S0      
317SSD_PRSNT_NET7               D0220PA01X+039050Y+088470               S0      
317SSD_PRSNT_NET7               D0220PA01X+039070Y+088900               S0      
327SSD_PRSNT_NET7                     A01X+016526Y+111494X0810Y0260     S0      
317SSD_PRSNT_NET7   VIA        MD0280PA01X+039075Y+089390               S0      
317SSD_ACT_DR7                  D0220PA01X+017800Y+095280               S0      
317SSD_ACT_DR7                  D0220PA01X+016962Y+096000               S0      
327SSD_ACT_DR7                        A01X+016526Y+111994X0810Y0260     S0      
317SSD_ACT_DR7      VIA        MD0280PA01X+017271Y+095275               S0      
317SSD_ACT_DR7      VIA        MD0100PA00X+017160Y+111994               S0      
317SSD_ACT_DR7      VIA        MD0100PA00X+017450Y+096000               S0      
32712V_PRECH_SSD7                     A01X+017855Y+117950X0450Y1100     S0      
32712V_PRECH_SSD7                     A01X+016526Y+112994X0810Y0260     S0      
31712V_PRECH_SSD7   VIA        MD0280PA01X+018800Y+117950               S0      
327P12V_SSD7                          A01X+013780Y+115608X0830Y0570     S0      
327P12V_SSD7                          A01X+014000Y+116452X0830Y0570     S0      
327P12V_SSD7                          A01X+016005Y+117950X0450Y1100     S0      
327P12V_SSD7                          A01X+012720Y+115390X0650Y0250     S0      
327P12V_SSD7                          A01X+012720Y+115890X0650Y0250     S0      
327P12V_SSD7                          A01X+012720Y+116390X0650Y0250     S0      
327P12V_SSD7                          A01X+012720Y+116890X0650Y0250     S0      
327P12V_SSD7                          A01X+014530Y+118590X0450Y0550     S0      
317P12V_SSD7                    D0340PA01X+014850Y+116870               S0      
317P12V_SSD7                    D0240PA01X+014580Y+115040               S0      
327P12V_SSD7                          A01X+016526Y+113494X0810Y0260     S0      
327P12V_SSD7                          A01X+016526Y+113994X0810Y0260     S0      
317P12V_SSD7        VIA        MD0280PA01X+015340Y+118970               S0      
317P12V_SSD7        VIA        MD0280PA01X+016610Y+118980               S0      
317NNAME00212                   D0220PA01X+039500Y+043570               S0      
327NNAME00212                         A01X+016689Y+064406X0790Y0200     S0      
317NNAME00212       VIA        MD0100PA00X+017680Y+064091               S0      
317NNAME00212       VIA        MD0100PA00X+019050Y+064721               S0      
317NNAME00213                   D0220PA01X+039100Y+043570               S0      
327NNAME00213                         A01X+016689Y+064721X0790Y0200     S0      
317NNAME00213       VIA        MD0100PA00X+018000Y+064091               S0      
317NNAME00213       VIA        MD0100PA00X+019050Y+064401               S0      
317NNAME00214                   D0220PA01X+038000Y+043570               S0      
327NNAME00214                         A01X+015433Y+061098X0790Y0200     S0      
317NNAME00215                   D0220PA01X+037600Y+043570               S0      
327NNAME00215                         A01X+015433Y+061413X0790Y0200     S0      
317SCL_DR8_R                    D0220PA01X+012820Y+072650               S0      
327SCL_DR8_R                          A01X+015433Y+072752X0790Y0200     S0      
317SCL_DR8_R        VIA        MD0280PA01X+013640Y+072509               S0      
317SDA_DR8_R                    D0220PA01X+012820Y+073150               S0      
327SDA_DR8_R                          A01X+015433Y+073067X0790Y0200     S0      
317SDA_DR8_R        VIA        MD0280PA01X+013640Y+073259               S0      
317DUALPORTEN#8                 D0220PA01X+012245Y+073722               S0      
317DUALPORTEN#8                 D0220PA01X+011794Y+073722               S0      
327DUALPORTEN#8                       A01X+015433Y+073382X0790Y0200     S0      
317DUALPORTEN#8     VIA        MD0280PA01X+012750Y+073710               S0      
317SSD8_CLK0_OE_N               D0220PA01X+038250Y+045470               S0      
317SSD8_CLK0_OE_N               D0220PA01X+038270Y+045900               S0      
327SSD8_CLK0_OE_N                     A01X+016526Y+067943X0810Y0260     S0      
317SSD8_CLK0_OE_N   VIA        MD0280PA01X+038275Y+046400               S0      
317SSD_PRSNT_NET8               D0220PA01X+039050Y+045470               S0      
317SSD_PRSNT_NET8               D0220PA01X+039070Y+045900               S0      
327SSD_PRSNT_NET8                     A01X+016526Y+070943X0810Y0260     S0      
317SSD_PRSNT_NET8   VIA        MD0280PA01X+039075Y+046390               S0      
317SSD_ACT_DR8                  D0220PA01X+020370Y+056900               S0      
317SSD_ACT_DR8                  D0220PA01X+020930Y+056900               S0      
327SSD_ACT_DR8                        A01X+016526Y+071443X0810Y0260     S0      
317SSD_ACT_DR8      VIA        MD0120PA00X+020670Y+057500               S0      
317SSD_ACT_DR8      VIA        MD0100PA00X+017160Y+071443               S0      
32712V_PRECH_SSD8                     A01X+017905Y+077540X0450Y1100     S0      
32712V_PRECH_SSD8                     A01X+016526Y+072443X0810Y0260     S0      
31712V_PRECH_SSD8   VIA        MD0280PA01X+018780Y+077540               S0      
327P12V_SSD8                          A01X+013780Y+075108X0830Y0570     S0      
327P12V_SSD8                          A01X+013790Y+075972X0830Y0570     S0      
327P12V_SSD8                          A01X+016055Y+077540X0450Y1100     S0      
327P12V_SSD8                          A01X+012720Y+074800X0650Y0250     S0      
327P12V_SSD8                          A01X+012720Y+075300X0650Y0250     S0      
327P12V_SSD8                          A01X+012720Y+075800X0650Y0250     S0      
327P12V_SSD8                          A01X+012720Y+076300X0650Y0250     S0      
327P12V_SSD8                          A01X+014670Y+078060X0450Y0550     S0      
317P12V_SSD8                    D0340PA01X+014650Y+076230               S0      
317P12V_SSD8                    D0240PA01X+014580Y+074590               S0      
327P12V_SSD8                          A01X+016526Y+072943X0810Y0260     S0      
327P12V_SSD8                          A01X+016526Y+073443X0810Y0260     S0      
317P12V_SSD8        VIA        MD0280PA01X+015250Y+077450               S0      
317P12V_SSD8        VIA        MD0280PA01X+015320Y+078360               S0      
317NNAME00216                   D0220PA01X+034050Y+036430               S0      
327NNAME00216                         A01X+016689Y+023854X0790Y0200     S0      
317NNAME00216       VIA        MD0100PA00X+017680Y+023539               S0      
317NNAME00216       VIA        MD0100PA00X+019050Y+024170               S0      
317NNAME00217                   D0220PA01X+034450Y+036430               S0      
327NNAME00217                         A01X+016689Y+024169X0790Y0200     S0      
317NNAME00217       VIA        MD0100PA00X+018000Y+023539               S0      
317NNAME00217       VIA        MD0100PA00X+019050Y+023850               S0      
317NNAME00218                   D0220PA01X+035550Y+036430               S0      
327NNAME00218                         A01X+015433Y+020547X0790Y0200     S0      
317NNAME00219                   D0220PA01X+035950Y+036430               S0      
327NNAME00219                         A01X+015433Y+020862X0790Y0200     S0      
317SCL_DR9_R                    D0220PA01X+012820Y+032100               S0      
327SCL_DR9_R                          A01X+015433Y+032201X0790Y0200     S0      
317SCL_DR9_R        VIA        MD0280PA01X+013680Y+031958               S0      
317SDA_DR9_R                    D0220PA01X+012820Y+032600               S0      
327SDA_DR9_R                          A01X+015433Y+032516X0790Y0200     S0      
317SDA_DR9_R        VIA        MD0280PA01X+013680Y+032708               S0      
317DUALPORTEN#9                 D0220PA01X+012645Y+033162               S0      
317DUALPORTEN#9                 D0220PA01X+011430Y+033162               S0      
327DUALPORTEN#9                       A01X+015433Y+032831X0790Y0200     S0      
317DUALPORTEN#9     VIA        MD0280PA01X+012037Y+033157               S0      
317SSD9_CLK0_OE_N               D0220PA01X+035300Y+034530               S0      
317SSD9_CLK0_OE_N               D0220PA01X+035280Y+034100               S0      
327SSD9_CLK0_OE_N                     A01X+016526Y+027392X0810Y0260     S0      
317SSD9_CLK0_OE_N   VIA        MD0280PA01X+035275Y+033600               S0      
317SSD_PRSNT_NET9               D0220PA01X+034500Y+034530               S0      
317SSD_PRSNT_NET9               D0220PA01X+034480Y+034100               S0      
327SSD_PRSNT_NET9                     A01X+016526Y+030392X0810Y0260     S0      
317SSD_PRSNT_NET9   VIA        MD0280PA01X+034475Y+033610               S0      
317SSD_ACT_DR9                  D0220PA01X+017040Y+015115               S0      
317SSD_ACT_DR9                  D0220PA01X+017795Y+014745               S0      
327SSD_ACT_DR9                        A01X+016526Y+030892X0810Y0260     S0      
317SSD_ACT_DR9      VIA        MD0280PA01X+017540Y+015200               S0      
317SSD_ACT_DR9      VIA        MD0100PA00X+016730Y+015120               S0      
317SSD_ACT_DR9      VIA        MD0100PA00X+017160Y+030892               S0      
32712V_PRECH_SSD9                     A01X+017885Y+036830X0450Y1100     S0      
32712V_PRECH_SSD9                     A01X+016526Y+031892X0810Y0260     S0      
31712V_PRECH_SSD9   VIA        MD0280PA01X+018640Y+036830               S0      
327P12V_SSD9                          A01X+013780Y+034538X0830Y0570     S0      
327P12V_SSD9                          A01X+013790Y+035412X0830Y0570     S0      
327P12V_SSD9                          A01X+016035Y+036830X0450Y1100     S0      
327P12V_SSD9                          A01X+012720Y+034250X0650Y0250     S0      
327P12V_SSD9                          A01X+012720Y+034750X0650Y0250     S0      
327P12V_SSD9                          A01X+012720Y+035250X0650Y0250     S0      
327P12V_SSD9                          A01X+012720Y+035750X0650Y0250     S0      
327P12V_SSD9                          A01X+014660Y+037530X0450Y0550     S0      
317P12V_SSD9                    D0340PA01X+014660Y+035750               S0      
317P12V_SSD9                    D0240PA01X+014570Y+034020               S0      
327P12V_SSD9                          A01X+016526Y+032392X0810Y0260     S0      
327P12V_SSD9                          A01X+016526Y+032892X0810Y0260     S0      
317P12V_SSD9        VIA        MD0280PA01X+015230Y+037040               S0      
317P12V_SSD9        VIA        MD0280PA01X+016430Y+037720               S0      
317NNAME00220                   D0220PA01X+089679Y+137135               S0      
317NNAME00220                   D0300PA01X+092050Y+135374               S0      
327NNAME00220                         A01X+089673Y+137675X0360Y0240     S0      
317NNAME00220       VIA        MD0280PA01X+091504Y+137004               S0      
317NNAME00221                   D0220PA01X+089021Y+137990               S0      
317NNAME00221                   D0300PA01X+087450Y+137424               S0      
327NNAME00221                         A01X+089673Y+137995X0360Y0240     S0      
317NNAME00221       VIA        MD0280PA01X+088010Y+138010               S0      
317DRV_ATTN_1                   D0220PA01X+091980Y+138099               S0      
327DRV_ATTN_1                         A01X+090248Y+137995X0360Y0240     S0      
317DRV_ATTN_1       VIA        MD0280PA01X+091483Y+138099               S0      
317DRV_ACT_1                    D0220PA01X+091980Y+137650               S0      
317DRV_ACT_1                    D0220PA01X+091980Y+137200               S0      
327DRV_ACT_1                          A01X+090248Y+137675X0360Y0240     S0      
317DRV_ACT_1        VIA        MD0280PA01X+090973Y+137549               S0      
317NNAME00222                   D0220PA01X+006828Y+182333               S0      
317NNAME00222                   D0300PA01X+010130Y+186065               S0      
327NNAME00222                         A01X+006996Y+182872X0360Y0240     S0      
317NNAME00222       VIA        MD0280PA01X+006290Y+182640               S0      
317NNAME00223                   D0220PA01X+007011Y+183727               S0      
317NNAME00223                   D0300PA01X+006760Y+184465               S0      
327NNAME00223                         A01X+006996Y+183192X0360Y0240     S0      
317NNAME00223       VIA        MD0280PA01X+006510Y+183810               S0      
317DRV_ATTN_10                  D0220PA01X+009380Y+183000               S0      
327DRV_ATTN_10                        A01X+007571Y+183192X0360Y0240     S0      
317DRV_ATTN_10      VIA        MD0280PA01X+008296Y+183140               S0      
317DRV_ACT_10                   D0220PA01X+009379Y+182592               S0      
317DRV_ACT_10                   D0220PA01X+009380Y+182150               S0      
327DRV_ACT_10                         A01X+007571Y+182872X0360Y0240     S0      
317DRV_ACT_10       VIA        MD0280PA01X+008810Y+182500               S0      
317NNAME00224                   D0220PA01X+089710Y+177690               S0      
317NNAME00224                   D0300PA01X+092050Y+175925               S0      
327NNAME00224                         A01X+089673Y+178226X0360Y0240     S0      
317NNAME00224       VIA        MD0280PA01X+091610Y+177380               S0      
317NNAME00225                   D0220PA01X+089549Y+179082               S0      
317NNAME00225                   D0300PA01X+087450Y+177975               S0      
327NNAME00225                         A01X+089673Y+178546X0360Y0240     S0      
317NNAME00225       VIA        MD0280PA01X+088684Y+178546               S0      
317DRV_ATTN_0                   D0220PA01X+091980Y+178650               S0      
327DRV_ATTN_0                         A01X+090248Y+178546X0360Y0240     S0      
317DRV_ATTN_0       VIA        MD0280PA01X+091483Y+178650               S0      
317DRV_ACT_0                    D0220PA01X+091980Y+178200               S0      
317DRV_ACT_0                    D0220PA01X+091980Y+177750               S0      
327DRV_ACT_0                          A01X+090248Y+178226X0360Y0240     S0      
317DRV_ACT_0        VIA        MD0280PA01X+090973Y+178100               S0      
317NNAME00226                   D0220PA01X+006754Y+141791               S0      
317NNAME00226                   D0300PA01X+006350Y+146175               S0      
327NNAME00226                         A01X+006996Y+142320X0360Y0240     S0      
317NNAME00226       VIA        MD0280PA01X+006200Y+144180               S0      
317NNAME00227                   D0220PA01X+006380Y+142919               S0      
317NNAME00227                   D0300PA01X+007321Y+143702               S0      
327NNAME00227                         A01X+006996Y+142640X0360Y0240     S0      
317NNAME00227       VIA        MD0280PA01X+006473Y+143418               S0      
317DRV_ATTN_11                  D0220PA01X+009280Y+142650               S0      
327DRV_ATTN_11                        A01X+007571Y+142640X0360Y0240     S0      
317DRV_ATTN_11      VIA        MD0280PA01X+008296Y+142766               S0      
317DRV_ACT_11                   D0220PA01X+009280Y+142200               S0      
317DRV_ACT_11                   D0220PA01X+009280Y+141750               S0      
327DRV_ACT_11                         A01X+007571Y+142320X0360Y0240     S0      
317DRV_ACT_11       VIA        MD0280PA01X+008750Y+142050               S0      
317NNAME00228                   D0220PA01X+006690Y+101244               S0      
317NNAME00228                   D0300PA01X+006700Y+105825               S0      
327NNAME00228                         A01X+006996Y+101769X0360Y0240     S0      
317NNAME00228       VIA        MD0280PA01X+006450Y+103750               S0      
317NNAME00229                   D0220PA01X+006404Y+102368               S0      
317NNAME00229                   D0300PA01X+007321Y+103151               S0      
327NNAME00229                         A01X+006996Y+102089X0360Y0240     S0      
317NNAME00229       VIA        MD0280PA01X+006473Y+102867               S0      
317DRV_ATTN_12                  D0220PA01X+009280Y+102100               S0      
327DRV_ATTN_12                        A01X+007571Y+102089X0360Y0240     S0      
317DRV_ATTN_12      VIA        MD0280PA01X+008296Y+102215               S0      
317DRV_ACT_12                   D0220PA01X+009280Y+101650               S0      
317DRV_ACT_12                   D0220PA01X+009300Y+101220               S0      
327DRV_ACT_12                         A01X+007571Y+101769X0360Y0240     S0      
317DRV_ACT_12       VIA        MD0280PA01X+008600Y+101420               S0      
317NNAME00230                   D0220PA01X+006362Y+061457               S0      
317NNAME00230                   D0300PA01X+006350Y+065073               S0      
327NNAME00230                         A01X+006996Y+061218X0360Y0240     S0      
317NNAME00230       VIA        MD0280PA01X+006152Y+063037               S0      
317NNAME00231                   D0220PA01X+006741Y+062826               S0      
317NNAME00231                   D0300PA01X+007321Y+062600               S0      
327NNAME00231                         A01X+006996Y+061538X0360Y0240     S0      
317NNAME00231       VIA        MD0280PA01X+006473Y+062316               S0      
317DRV_ATTN_13                  D0220PA01X+009280Y+061550               S0      
327DRV_ATTN_13                        A01X+007571Y+061538X0360Y0240     S0      
317DRV_ATTN_13      VIA        MD0280PA01X+008296Y+061664               S0      
317DRV_ACT_13                   D0220PA01X+009280Y+061100               S0      
317DRV_ACT_13                   D0220PA01X+009250Y+060670               S0      
327DRV_ACT_13                         A01X+007571Y+061218X0360Y0240     S0      
317DRV_ACT_13       VIA        MD0280PA01X+008650Y+060810               S0      
317NNAME00232                   D0220PA01X+005986Y+020497               S0      
317NNAME00232                   D0300PA01X+006350Y+024522               S0      
327NNAME00232                         A01X+006996Y+020667X0360Y0240     S0      
317NNAME00232       VIA        MD0280PA01X+005975Y+022347               S0      
317NNAME00233                   D0220PA01X+006390Y+021260               S0      
317NNAME00233                   D0300PA01X+007321Y+022048               S0      
327NNAME00233                         A01X+006996Y+020987X0360Y0240     S0      
317NNAME00233       VIA        MD0280PA01X+006473Y+021765               S0      
317DRV_ATTN_14                  D0220PA01X+009280Y+021000               S0      
327DRV_ATTN_14                        A01X+007571Y+020987X0360Y0240     S0      
317DRV_ATTN_14      VIA        MD0280PA01X+008760Y+020987               S0      
317DRV_ACT_14                   D0220PA01X+009280Y+020550               S0      
317DRV_ACT_14                   D0220PA01X+009280Y+020100               S0      
327DRV_ACT_14                         A01X+007571Y+020667X0360Y0240     S0      
317DRV_ACT_14       VIA        MD0280PA01X+008750Y+020200               S0      
317NNAME00234                   D0220PA01X+089717Y+096591               S0      
317NNAME00234                   D0300PA01X+092050Y+094823               S0      
327NNAME00234                         A01X+089673Y+097123X0360Y0240     S0      
317NNAME00234       VIA        MD0280PA01X+091465Y+096421               S0      
317NNAME00235                   D0220PA01X+088991Y+097731               S0      
317NNAME00235                   D0300PA01X+087450Y+096873               S0      
327NNAME00235                         A01X+089673Y+097444X0360Y0240     S0      
317NNAME00235       VIA        MD0280PA01X+087980Y+097580               S0      
317DRV_ATTN_2                   D0220PA01X+091980Y+097548               S0      
327DRV_ATTN_2                         A01X+090248Y+097444X0360Y0240     S0      
317DRV_ATTN_2       VIA        MD0280PA01X+091483Y+097548               S0      
317DRV_ACT_2                    D0220PA01X+091980Y+097100               S0      
317DRV_ACT_2                    D0220PA01X+091980Y+096650               S0      
327DRV_ACT_2                          A01X+090248Y+097123X0360Y0240     S0      
317DRV_ACT_2        VIA        MD0280PA01X+090973Y+096998               S0      
317NNAME00236                   D0220PA01X+089694Y+056041               S0      
317NNAME00236                   D0300PA01X+092050Y+054272               S0      
327NNAME00236                         A01X+089673Y+056572X0360Y0240     S0      
317NNAME00236       VIA        MD0280PA01X+091660Y+055660               S0      
317NNAME00237                   D0220PA01X+089598Y+057442               S0      
317NNAME00237                   D0300PA01X+087450Y+056322               S0      
327NNAME00237                         A01X+089673Y+056892X0360Y0240     S0      
317NNAME00237       VIA        MD0280PA01X+088684Y+056892               S0      
317DRV_ATTN_3                   D0220PA01X+091980Y+056997               S0      
327DRV_ATTN_3                         A01X+090248Y+056892X0360Y0240     S0      
317DRV_ATTN_3       VIA        MD0280PA01X+091483Y+056997               S0      
317DRV_ACT_3                    D0220PA01X+091980Y+056550               S0      
317DRV_ACT_3                    D0220PA01X+091980Y+056100               S0      
327DRV_ACT_3                          A01X+090248Y+056572X0360Y0240     S0      
317DRV_ACT_3        VIA        MD0280PA01X+090973Y+056447               S0      
317NNAME00238                   D0220PA01X+089868Y+015472               S0      
317NNAME00238                   D0300PA01X+092050Y+013720               S0      
327NNAME00238                         A01X+089673Y+016021X0360Y0240     S0      
317NNAME00238       VIA        MD0280PA01X+091504Y+015350               S0      
317NNAME00239                   D0220PA01X+089052Y+016835               S0      
317NNAME00239                   D0300PA01X+087616Y+016341               S0      
327NNAME00239                         A01X+089673Y+016341X0360Y0240     S0      
317NNAME00239       VIA        MD0280PA01X+087900Y+016950               S0      
317DRV_ATTN_4                   D0220PA01X+091980Y+016445               S0      
327DRV_ATTN_4                         A01X+090248Y+016341X0360Y0240     S0      
317DRV_ATTN_4       VIA        MD0280PA01X+091483Y+016445               S0      
317DRV_ACT_4                    D0220PA01X+091980Y+016000               S0      
317DRV_ACT_4                    D0220PA01X+091980Y+015550               S0      
327DRV_ACT_4                          A01X+090248Y+016021X0360Y0240     S0      
317DRV_ACT_4        VIA        MD0280PA01X+090973Y+015895               S0      
317NNAME00240                   D0220PA01X+017008Y+177353               S0      
317NNAME00240                   D0300PA01X+018060Y+176350               S0      
327NNAME00240                         A01X+016839Y+178226X0360Y0240     S0      
317NNAME00240       VIA        MD0280PA01X+016500Y+177400               S0      
317NNAME00241                   D0220PA01X+016749Y+179069               S0      
317NNAME00241                   D0300PA01X+023550Y+175625               S0      
327NNAME00241                         A01X+016839Y+178546X0360Y0240     S0      
317NNAME00241       VIA        MD0280PA01X+017151Y+176399               S0      
317DRV_ATTN_5                   D0220PA01X+019130Y+179050               S0      
327DRV_ATTN_5                         A01X+017414Y+178546X0360Y0240     S0      
317DRV_ATTN_5       VIA        MD0280PA01X+018640Y+178670               S0      
317DRV_ACT_5                    D0220PA01X+019130Y+178600               S0      
317DRV_ACT_5                    D0220PA01X+019130Y+178150               S0      
327DRV_ACT_5                          A01X+017414Y+178226X0360Y0240     S0      
317DRV_ACT_5        VIA        MD0280PA01X+018139Y+178100               S0      
317NNAME00242                   D0220PA01X+016407Y+137153               S0      
317NNAME00242                   D0300PA01X+019215Y+135374               S0      
327NNAME00242                         A01X+016839Y+137675X0360Y0240     S0      
317NNAME00242       VIA        MD0280PA01X+016910Y+137160               S0      
317NNAME00243                   D0220PA01X+016767Y+138532               S0      
317NNAME00243                   D0300PA01X+014050Y+137179               S0      
327NNAME00243                         A01X+016839Y+137995X0360Y0240     S0      
317NNAME00243       VIA        MD0280PA01X+015850Y+137995               S0      
317DRV_ATTN_6                   D0220PA01X+018680Y+138200               S0      
327DRV_ATTN_6                         A01X+017414Y+137995X0360Y0240     S0      
317DRV_ATTN_6       VIA        MD0280PA01X+018150Y+138240               S0      
317DRV_ACT_6                    D0220PA01X+018680Y+137750               S0      
317DRV_ACT_6                    D0220PA01X+018680Y+137300               S0      
327DRV_ACT_6                          A01X+017414Y+137675X0360Y0240     S0      
317DRV_ACT_6        VIA        MD0280PA01X+018130Y+137480               S0      
317NNAME00244                   D0220PA01X+015705Y+097700               S0      
317NNAME00244                   D0300PA01X+015150Y+097125               S0      
327NNAME00244                         A01X+016839Y+097123X0360Y0240     S0      
317NNAME00244       VIA        MD0280PA01X+016123Y+097125               S0      
317NNAME00245                   D0220PA01X+016823Y+097973               S0      
317NNAME00245                   D0300PA01X+021950Y+094523               S0      
327NNAME00245                         A01X+016839Y+097444X0360Y0240     S0      
317NNAME00245       VIA        MD0280PA01X+015000Y+095500               S0      
317DRV_ATTN_7                   D0220PA01X+019230Y+097850               S0      
327DRV_ATTN_7                         A01X+017414Y+097444X0360Y0240     S0      
317DRV_ATTN_7       VIA        MD0280PA01X+018649Y+097548               S0      
317DRV_ACT_7                    D0220PA01X+019230Y+097400               S0      
317DRV_ACT_7                    D0220PA01X+019230Y+096950               S0      
327DRV_ACT_7                          A01X+017414Y+097123X0360Y0240     S0      
317DRV_ACT_7        VIA        MD0280PA01X+018384Y+096828               S0      
317NNAME00246                   D0220PA01X+017070Y+056042               S0      
317NNAME00246                   D0300PA01X+020225Y+055900               S0      
327NNAME00246                         A01X+016839Y+056572X0360Y0240     S0      
317NNAME00246       VIA        MD0280PA01X+018750Y+055900               S0      
317NNAME00247                   D0220PA01X+016214Y+057524               S0      
317NNAME00247                   D0300PA01X+012550Y+056375               S0      
327NNAME00247                         A01X+016839Y+056892X0360Y0240     S0      
317NNAME00247       VIA        MD0280PA01X+013500Y+057000               S0      
317DRV_ATTN_8                   D0220PA01X+019180Y+057350               S0      
327DRV_ATTN_8                         A01X+017414Y+056892X0360Y0240     S0      
317DRV_ATTN_8       VIA        MD0280PA01X+018649Y+056997               S0      
317DRV_ACT_8                    D0220PA01X+019180Y+056900               S0      
317DRV_ACT_8                    D0220PA01X+019180Y+056450               S0      
327DRV_ACT_8                          A01X+017414Y+056572X0360Y0240     S0      
317DRV_ACT_8        VIA        MD0280PA01X+018139Y+056447               S0      
317NNAME00248                   D0220PA01X+016399Y+015474               S0      
317NNAME00248                   D0300PA01X+019150Y+014075               S0      
327NNAME00248                         A01X+016839Y+016021X0360Y0240     S0      
317NNAME00248       VIA        MD0280PA01X+018761Y+015475               S0      
317NNAME00249                   D0220PA01X+016766Y+016881               S0      
317NNAME00249                   D0300PA01X+013650Y+015625               S0      
327NNAME00249                         A01X+016839Y+016341X0360Y0240     S0      
317NNAME00249       VIA        MD0280PA01X+015850Y+016341               S0      
317DRV_ATTN_9                   D0220PA01X+019230Y+016700               S0      
327DRV_ATTN_9                         A01X+017414Y+016341X0360Y0240     S0      
317DRV_ATTN_9       VIA        MD0280PA01X+018649Y+016445               S0      
317DRV_ACT_9                    D0220PA01X+019230Y+016250               S0      
317DRV_ACT_9                    D0220PA01X+019230Y+015800               S0      
327DRV_ACT_9                          A01X+017414Y+016021X0360Y0240     S0      
317DRV_ACT_9        VIA        MD0280PA01X+018139Y+015895               S0      
327P3V3_VIN                           A01X+088983Y+168350X0570Y0830     S0      
327P3V3_VIN                           A01X+088983Y+167104X0570Y0830     S0      
327P3V3_VIN                           A01X+089055Y+170389X0120Y0360     S0      
327P3V3_VIN                           A01X+089252Y+170394X0120Y0370     S0      
327P3V3_VIN                           A01X+088985Y+166025X0500Y0650     S0      
317P3V3_VIN                     D0240PA01X+088930Y+169800               S0      
317P3V3_VIN         VIA        MD0280PA01X+088960Y+169190               S0      
327P3V3_VRG5                          A01X+089956Y+170902X0370Y0120     S0      
317P3V3_VRG5                    D0220PA01X+091580Y+171500               S0      
317P3V3_VRG5                    D0340PA01X+091050Y+170770               S0      
317P3V3_VRG5        VIA        MD0280PA01X+091620Y+170870               S0      
327P3V3_OUT                           A01X+082750Y+170780X0550Y0450     S0      
327P3V3_OUT                           A01X+082750Y+172720X0550Y0450     S0      
327P3V3_OUT                           A01X+083550Y+172720X0550Y0450     S0      
327P3V3_OUT                           A01X+083550Y+170780X0550Y0450     S0      
327P3V3_OUT                           A01X+084656Y+172000X1150Y1380     S0      
327P3V3_OUT                           A01X+082000Y+171450X0500Y0650     S0      
327P3V3_OUT                           A01X+082000Y+172350X0500Y0650     S0      
327P3V3_OUT                           A01X+082250Y+172975X0100Y0070     S0      
317P3V3_OUT                     D0340PA01X+085500Y+170230               S0      
317P3V3_OUT                     D0240PA01X+084150Y+170230               S0      
317P3V3_OUT         VIA        MD0280PA01X+082689Y+171400               S0      
317P3V3_OUT         VIA        MD0280PA01X+082989Y+172100               S0      
317P3V3_OUT         VIA        MD0280PA01X+083589Y+171650               S0      
317P3V3_VFB_R                   D0220PA01X+085950Y+169930               S0      
317P3V3_VFB_R                   D0340PA01X+085500Y+169670               S0      
317P3V3_VFB_R                   D0240PA01X+091530Y+169100               S0      
317P3V3_VFB_R       VIA        MD0100PA00X+085950Y+169600               S0      
317P3V3_VFB_R       VIA        MD0100PA00X+091525Y+168750               S0      
327P3V3_SW                            A01X+086844Y+172000X1150Y1380     S0      
327P3V3_SW                            A01X+088739Y+171295X0360Y0120     S0      
327P3V3_SW                            A01X+088744Y+171098X0370Y0120     S0      
327P3V3_SW                            A01X+088744Y+170902X0370Y0120     S0      
317P3V3_SW                      D0340PA01X+087800Y+172320               S0      
317P3V3_SW                      D0220PA01X+085950Y+170270               S0      
317P3V3_SW                      D0340PA01X+087700Y+170080               S0      
317P3V3_SW          VIA        MD0280PA01X+087910Y+171510               S0      
317P3V3_VBST_RR                 D0220PA01X+088150Y+169630               S0      
317P3V3_VBST_RR                 D0340PA01X+087700Y+169520               S0      
317P3V3_EN_R                    D0240PA01X+089450Y+172720               S0      
327P3V3_EN_R                          A01X+089448Y+171606X0120Y0370     S0      
317P3V3_EN_R                    D0220PA01X+089050Y+172730               S0      
317P3V3_EN_R                    D0220PA01X+089850Y+172730               S0      
317P3V3_EN_R        VIA        MD0280PA01X+089448Y+172220               S0      
317AGND_P3V3                    D0240PA01X+089450Y+173080               S0      
327AGND_P3V3                          A01X+089961Y+171295X0360Y0120     S0      
317AGND_P3V3                    D0163PA01X+091650Y+172325               S0      
317AGND_P3V3                    D0220PA01X+089050Y+173070               S0      
317AGND_P3V3                    D0220PA01X+091520Y+170300               S0      
317AGND_P3V3                    D0340PA01X+089650Y+168520               S0      
317AGND_P3V3                    D0240PA01X+091830Y+171900               S0      
317AGND_P3V3        VIA        MD0100PA00X+089650Y+168100               S0      
317AGND_P3V3        VIA        MD0100PA00X+092190Y+172240               S0      
327P3V3_SS                            A01X+089956Y+171098X0370Y0120     S0      
317P3V3_SS                      D0240PA01X+091470Y+171900               S0      
317P3V3_SS          VIA        MD0280PA01X+090970Y+171900               S0      
327P3V3_VCC                           A01X+089448Y+170394X0120Y0370     S0      
317P3V3_VCC                     D0340PA01X+090150Y+169080               S0      
317P3V3_VCC                     D0340PA01X+089650Y+169080               S0      
317P3V3_VCC         VIA        MD0280PA01X+089650Y+169630               S0      
327P3V3_VFB                           A01X+089961Y+170705X0360Y0120     S0      
317P3V3_VFB                     D0220PA01X+091180Y+170300               S0      
317P3V3_VFB                     D0220PA01X+091180Y+169500               S0      
317P3V3_VFB                     D0240PA01X+091170Y+169900               S0      
317P3V3_VFB                     D0240PA01X+091170Y+169100               S0      
317P3V3_VFB         VIA        MD0280PA01X+090600Y+170340               S0      
317P3V3_SNB                     D0340PA01X+087800Y+172880               S0      
327P3V3_SNB                           A01X+088450Y+173080X0550Y0450     S0      
317P3V3_CC_R                    D0340PA01X+091970Y+169500               S0      
317P3V3_CC_R                    D0220PA01X+091520Y+169500               S0      
317P3V3_CC_R                    D0220PA01X+090600Y+168780               S0      
317P3V3_CC_R                    D0240PA01X+091530Y+169900               S0      
317P3V3_CC_R        VIA        MD0280PA01X+091180Y+168400               S0      
327P3V3_CC                            A01X+082250Y+173025X0100Y0070     S0      
317P3V3_CC                      D0340PA01X+092530Y+169500               S0      
317P3V3_CC          VIA        MD0280PA01X+089809Y+174526               S0      
317I2C_MUX_RESET                D0220PA01X+032920Y+060500               S0      
317I2C_MUX_RESET                D0220PA01X+031950Y+139230               S0      
317I2C_MUX_RESET                D0220PA01X+032920Y+060900               S0      
317I2C_MUX_RESET    VIA        MD0280PA08X+031150Y+137450               S0      
317I2C_MUX_RESET    VIA        MD0100PA00X+031950Y+138900               S0      
317I2C_MUX_RESET    VIA        MD0100PA00X+033250Y+060500               S0      
317I2C_B_SCL                    D0220PA01X+079930Y+180700               S0      
317I2C_B_SCL                    D0220PA01X+079930Y+019300               S0      
317I2C_B_SCL                    D0220PA01X+034850Y+012720               S0      
317I2C_B_SCL                    D0220PA01X+027680Y+172200               S0      
317I2C_B_SCL                    D0220PA01X+027650Y+173130               S0      
317I2C_B_SCL                    D0220PA01X+009280Y+149200               S0      
317I2C_B_SCL                    D0220PA01X+018520Y+052700               S0      
317I2C_B_SCL                    D0220PA01X+027650Y+171770               S0      
317I2C_B_SCL        VIA        MD0120PA00X+042750Y+029716               S0      
317I2C_B_SCL        VIA        MD0100PA00X+018885Y+052710               S0      
317I2C_B_SCL        VIA        MD0100PA00X+027640Y+172615               S0      
317I2C_B_SCL        VIA        MD0100PA00X+037681Y+175543               S0      
317I2C_B_SCL        VIA        MD0100PA00X+079234Y+019360               S0      
317I2C_B_SCL        VIA        MD0100PA00X+008201Y+154050               S0      
317I2C_B_SDA                    D0220PA01X+079930Y+181200               S0      
317I2C_B_SDA                    D0220PA01X+079930Y+019800               S0      
317I2C_B_SDA                    D0220PA01X+035250Y+012720               S0      
317I2C_B_SDA                    D0220PA01X+027220Y+172200               S0      
317I2C_B_SDA                    D0220PA01X+027250Y+173130               S0      
317I2C_B_SDA                    D0220PA01X+009280Y+149700               S0      
317I2C_B_SDA                    D0220PA01X+018520Y+053100               S0      
317I2C_B_SDA                    D0220PA01X+027250Y+171770               S0      
317I2C_B_SDA        VIA        MD0120PA00X+042750Y+030466               S0      
317I2C_B_SDA        VIA        MD0100PA00X+018885Y+053090               S0      
317I2C_B_SDA        VIA        MD0100PA00X+027260Y+172615               S0      
317I2C_B_SDA        VIA        MD0100PA00X+037301Y+175543               S0      
317I2C_B_SDA        VIA        MD0100PA00X+079234Y+019740               S0      
317I2C_B_SDA        VIA        MD0100PA00X+008581Y+154050               S0      
327NNAME00250                         A01X+089645Y+171611X0120Y0360     S0      
317NNAME00250                   D0220PA01X+091050Y+172780               S0      
317NNAME00250                   D0220PA01X+090250Y+172730               S0      
317NNAME00250                   D0220PA01X+091920Y+171500               S0      
317NNAME00250                   D0220PA01X+090650Y+172730               S0      
317NNAME00250       VIA        MD0280PA08X+091300Y+171775               S0      
317NNAME00250       VIA        MD0100PA00X+091050Y+172470               S0      
317NNAME00250       VIA        MD0100PA00X+091925Y+171150               S0      
327P3V3_VBST                          A01X+088739Y+170705X0360Y0120     S0      
317P3V3_VBST                    D0220PA01X+088150Y+169970               S0      
327P3V3_VO                            A01X+089645Y+170389X0120Y0360     S0      
317P3V3_VO                      D0220PA01X+090600Y+169120               S0      
317P3V3_VO          VIA        MD0280PA01X+090428Y+169610               S0      
327NNAME00251                         A01X+009773Y+024186X0480Y0160     S0      
317NNAME00251                   D0220PA01X+009280Y+021447               S0      
317NNAME00251                   D0300PA01X+009425Y+022397               S0      
317NNAME00251                   D0300PA01X+008071Y+021661               S0      
317NNAME00251       VIA        MD0280PA01X+009773Y+023424               S0      
317NNAME00252                   D0220PA01X+008759Y+023102               S0      
317NNAME00252                   D0300PA01X+008071Y+022436               S0      
317NNAME00252       VIA        MD0280PA01X+008759Y+022591               S0      
317NNAME00253                   D0220PA01X+078839Y+196436               S0      
317NNAME00253                   D0300PA01X+079449Y+196828               S0      
317NNAME00253                   D0300PA01X+078249Y+196441               S0      
317NNAME00253       VIA        MD0280PA01X+078839Y+196929               S0      
317SSD0_PWREN_R                 D0220PA01X+076361Y+196828               S0      
317SSD0_PWREN_R                 D0300PA01X+077499Y+196828               S0      
317SSD0_PWREN_R     VIA        MD0280PA01X+076856Y+196828               S0      
327NNAME00254                         A01X+081534Y+195941X0550Y0450     S0      
317NNAME00254                   D0300PA01X+080199Y+196441               S0      
317NNAME00254       VIA        MD0280PA01X+080834Y+196251               S0      
327NNAME00255                         A01X+089125Y+176206X0480Y0160     S0      
317NNAME00255                   D0220PA01X+086520Y+177000               S0      
317NNAME00255                   D0300PA01X+087063Y+177225               S0      
317NNAME00255                   D0300PA01X+086900Y+176375               S0      
317NNAME00255       VIA        MD0280PA01X+088164Y+175755               S0      
317NNAME00256                   D0220PA01X+092320Y+175200               S0      
317NNAME00256                   D0300PA01X+092438Y+176675               S0      
317NNAME00256       VIA        MD0280PA01X+093150Y+176150               S0      
317SSD_ACT_DR0_R                D0220PA01X+090970Y+176850               S0      
317SSD_ACT_DR0_R                D0300PA01X+091663Y+176675               S0      
317SSD_ACT_DR0_R    VIA        MD0280PA01X+090975Y+176327               S0      
317ATTN_LED_DR0_R               D0220PA01X+088455Y+177325               S0      
317ATTN_LED_DR0_R               D0300PA01X+087838Y+177225               S0      
317ATTN_LED_DR0_R   VIA        MD0280PA01X+088150Y+176550               S0      
317NNAME00257                   D0220PA01X+084015Y+159035               S0      
317NNAME00257                   D0300PA01X+084625Y+159428               S0      
317NNAME00257                   D0300PA01X+083425Y+159040               S0      
317NNAME00257       VIA        MD0280PA01X+084015Y+159528               S0      
317SSD1_PWREN_R                 D0220PA01X+081538Y+159428               S0      
317SSD1_PWREN_R                 D0300PA01X+082675Y+159428               S0      
317SSD1_PWREN_R     VIA        MD0280PA01X+082033Y+159428               S0      
327NNAME00258                         A01X+086630Y+159440X0450Y0550     S0      
317NNAME00258                   D0300PA01X+085375Y+159040               S0      
317NNAME00258       VIA        MD0280PA01X+085819Y+160101               S0      
317NNAME00259                   D0220PA01X+092320Y+134649               S0      
317NNAME00259                   D0300PA01X+092438Y+136124               S0      
317NNAME00259       VIA        MD0280PA01X+093150Y+135599               S0      
317SSD_ACT_DR1_R                D0220PA01X+090970Y+136299               S0      
317SSD_ACT_DR1_R                D0300PA01X+091663Y+136124               S0      
317SSD_ACT_DR1_R    VIA        MD0280PA01X+090975Y+135776               S0      
327NNAME00260                         A01X+089125Y+135655X0480Y0160     S0      
317NNAME00260                   D0220PA01X+086520Y+136449               S0      
317NNAME00260                   D0300PA01X+087063Y+136674               S0      
317NNAME00260                   D0300PA01X+086900Y+135824               S0      
317NNAME00260       VIA        MD0280PA01X+088064Y+135254               S0      
317ATTN_LED_DR1_R               D0220PA01X+088399Y+136520               S0      
317ATTN_LED_DR1_R               D0300PA01X+087838Y+136674               S0      
317ATTN_LED_DR1_R   VIA        MD0280PA01X+088150Y+135999               S0      
317NNAME00261                   D0220PA01X+084015Y+118485               S0      
317NNAME00261                   D0300PA01X+084625Y+118877               S0      
317NNAME00261                   D0300PA01X+083425Y+118490               S0      
317NNAME00261       VIA        MD0280PA01X+084015Y+118978               S0      
317SSD2_PWREN_R                 D0220PA01X+081538Y+118877               S0      
317SSD2_PWREN_R                 D0300PA01X+082675Y+118877               S0      
317SSD2_PWREN_R     VIA        MD0280PA01X+082033Y+118877               S0      
327NNAME00262                         A01X+086630Y+118740X0450Y0550     S0      
317NNAME00262                   D0300PA01X+085375Y+118490               S0      
317NNAME00262       VIA        MD0280PA01X+086027Y+119437               S0      
317NNAME00263                   D0220PA01X+092320Y+094098               S0      
317NNAME00263                   D0300PA01X+092438Y+095573               S0      
317NNAME00263       VIA        MD0280PA01X+093150Y+095048               S0      
317SSD_ACT_DR2_R                D0220PA01X+090970Y+095748               S0      
317SSD_ACT_DR2_R                D0300PA01X+091663Y+095573               S0      
317SSD_ACT_DR2_R    VIA        MD0280PA01X+090975Y+095225               S0      
327NNAME00264                         A01X+089125Y+095104X0480Y0160     S0      
317NNAME00264                   D0220PA01X+086520Y+095898               S0      
317NNAME00264                   D0300PA01X+087063Y+096123               S0      
317NNAME00264                   D0300PA01X+086900Y+095273               S0      
317NNAME00264       VIA        MD0280PA01X+088064Y+094703               S0      
317ATTN_LED_DR2_R               D0220PA01X+088455Y+096223               S0      
317ATTN_LED_DR2_R               D0300PA01X+087838Y+096123               S0      
317ATTN_LED_DR2_R   VIA        MD0280PA01X+088150Y+095448               S0      
327NNAME00265                         A01X+086630Y+078190X0450Y0550     S0      
317NNAME00265                   D0300PA01X+085375Y+077940               S0      
317NNAME00265       VIA        MD0280PA01X+085974Y+078967               S0      
317NNAME00266                   D0220PA01X+084015Y+077935               S0      
317NNAME00266                   D0300PA01X+084625Y+078328               S0      
317NNAME00266                   D0300PA01X+083425Y+077940               S0      
317NNAME00266       VIA        MD0280PA01X+084015Y+078428               S0      
317SSD3_PWREN_R                 D0220PA01X+081538Y+078328               S0      
317SSD3_PWREN_R                 D0300PA01X+082675Y+078328               S0      
317SSD3_PWREN_R     VIA        MD0280PA01X+082033Y+078328               S0      
317NNAME00267                   D0220PA01X+092320Y+053546               S0      
317NNAME00267                   D0300PA01X+092438Y+055021               S0      
317NNAME00267       VIA        MD0280PA01X+093150Y+054497               S0      
317SSD_ACT_DR3_R                D0220PA01X+090970Y+055197               S0      
317SSD_ACT_DR3_R                D0300PA01X+091663Y+055021               S0      
317SSD_ACT_DR3_R    VIA        MD0280PA01X+090975Y+054674               S0      
327NNAME00268                         A01X+089125Y+054552X0480Y0160     S0      
317NNAME00268                   D0220PA01X+086520Y+055347               S0      
317NNAME00268                   D0300PA01X+087063Y+055572               S0      
317NNAME00268                   D0300PA01X+086900Y+054722               S0      
317NNAME00268       VIA        MD0280PA01X+088064Y+054151               S0      
317ATTN_LED_DR3_R               D0220PA01X+088455Y+055672               S0      
317ATTN_LED_DR3_R               D0300PA01X+087838Y+055572               S0      
317ATTN_LED_DR3_R   VIA        MD0280PA01X+088150Y+054897               S0      
327NNAME00269                         A01X+086680Y+037640X0450Y0550     S0      
317NNAME00269                   D0300PA01X+085375Y+037390               S0      
317NNAME00269       VIA        MD0280PA01X+086189Y+038301               S0      
317NNAME00270                   D0220PA01X+084015Y+037385               S0      
317NNAME00270                   D0300PA01X+084625Y+037778               S0      
317NNAME00270                   D0300PA01X+083425Y+037390               S0      
317NNAME00270       VIA        MD0280PA01X+084015Y+037878               S0      
317SSD4_PWREN_R                 D0220PA01X+081538Y+037778               S0      
317SSD4_PWREN_R                 D0300PA01X+082675Y+037778               S0      
317SSD4_PWREN_R     VIA        MD0280PA01X+082033Y+037778               S0      
317NNAME00271                   D0220PA01X+092320Y+012995               S0      
317NNAME00271                   D0300PA01X+092438Y+014470               S0      
317NNAME00271       VIA        MD0280PA01X+093150Y+013945               S0      
317SSD_ACT_DR4_R                D0220PA01X+091070Y+014645               S0      
317SSD_ACT_DR4_R                D0300PA01X+091663Y+014470               S0      
317SSD_ACT_DR4_R    VIA        MD0280PA01X+091075Y+014122               S0      
327NNAME00272                         A01X+089225Y+014001X0480Y0160     S0      
317NNAME00272                   D0220PA01X+086696Y+015596               S0      
317NNAME00272                   D0300PA01X+087229Y+015591               S0      
317NNAME00272                   D0300PA01X+087675Y+014500               S0      
317NNAME00272       VIA        MD0280PA01X+088400Y+014001               S0      
317ATTN_LED_DR4_R               D0220PA01X+088630Y+015700               S0      
317ATTN_LED_DR4_R               D0300PA01X+088004Y+015591               S0      
317ATTN_LED_DR4_R   VIA        MD0280PA01X+088341Y+014900               S0      
327NNAME00273                         A01X+008720Y+196040X0550Y0450     S0      
317NNAME00273                   D0300PA01X+007445Y+196520               S0      
317NNAME00273       VIA        MD0280PA01X+008060Y+196400               S0      
317NNAME00274                   D0220PA01X+006105Y+196525               S0      
317NNAME00274                   D0300PA01X+005535Y+196530               S0      
317NNAME00274                   D0300PA01X+006695Y+196907               S0      
317NNAME00274       VIA        MD0280PA01X+006060Y+197030               S0      
317SSD5_PWREN_R                 D0220PA01X+003678Y+197028               S0      
317SSD5_PWREN_R                 D0300PA01X+004785Y+196918               S0      
317SSD5_PWREN_R     VIA        MD0280PA01X+004170Y+196940               S0      
317NNAME00275                   D0220PA01X+018165Y+177450               S0      
317NNAME00275                   D0300PA01X+018810Y+175962               S0      
317NNAME00275       VIA        MD0280PA01X+017500Y+177450               S0      
317SSD_ACT_DR5_R                D0220PA01X+019475Y+175645               S0      
317SSD_ACT_DR5_R                D0300PA01X+018810Y+176737               S0      
317SSD_ACT_DR5_R    VIA        MD0280PA01X+019475Y+176200               S0      
327NNAME00276                         A01X+020760Y+176944X0480Y0160     S0      
317NNAME00276                   D0220PA01X+024490Y+176990               S0      
317NNAME00276                   D0300PA01X+023938Y+176375               S0      
317NNAME00276                   D0300PA01X+022100Y+175625               S0      
317NNAME00276       VIA        MD0280PA01X+021050Y+176140               S0      
317ATTN_LED_DR5_R               D0220PA01X+021940Y+177210               S0      
317ATTN_LED_DR5_R               D0300PA01X+023162Y+176375               S0      
317ATTN_LED_DR5_R   VIA        MD0280PA01X+022818Y+177210               S0      
327NNAME00277                         A01X+012973Y+158113X0550Y0450     S0      
317NNAME00277                   D0300PA01X+011663Y+158478               S0      
317NNAME00277       VIA        MD0280PA01X+012304Y+158345               S0      
317NNAME00278                   D0220PA01X+010303Y+158473               S0      
317NNAME00278                   D0300PA01X+009713Y+158478               S0      
317NNAME00278                   D0300PA01X+010913Y+158865               S0      
317NNAME00278       VIA        MD0280PA01X+010303Y+158965               S0      
317SSD6_PWREN_R                 D0220PA01X+007526Y+158708               S0      
317SSD6_PWREN_R                 D0300PA01X+008963Y+158865               S0      
317SSD6_PWREN_R     VIA        MD0280PA01X+008320Y+158865               S0      
317NNAME00279                   D0220PA01X+019485Y+134649               S0      
317NNAME00279                   D0300PA01X+019603Y+136124               S0      
317NNAME00279       VIA        MD0280PA01X+019990Y+134649               S0      
317SSD_ACT_DR6_R                D0220PA01X+018135Y+136249               S0      
317SSD_ACT_DR6_R                D0300PA01X+018828Y+136124               S0      
317SSD_ACT_DR6_R    VIA        MD0280PA01X+018140Y+135756               S0      
327NNAME00280                         A01X+016290Y+135655X0480Y0160     S0      
317NNAME00280                   D0220PA01X+013668Y+137801               S0      
317NNAME00280                   D0300PA01X+013663Y+136429               S0      
317NNAME00280                   D0300PA01X+015500Y+136429               S0      
317NNAME00280       VIA        MD0280PA01X+015500Y+135784               S0      
317ATTN_LED_DR6_R               D0220PA01X+015126Y+135230               S0      
317ATTN_LED_DR6_R               D0300PA01X+014438Y+136429               S0      
317ATTN_LED_DR6_R   VIA        MD0280PA01X+014438Y+135719               S0      
327NNAME00281                         A01X+013770Y+118590X0450Y0550     S0      
317NNAME00281                   D0300PA01X+012725Y+118490               S0      
317NNAME00281       VIA        MD0280PA01X+013310Y+119170               S0      
317NNAME00282                   D0220PA01X+011365Y+118485               S0      
317NNAME00282                   D0300PA01X+010775Y+118490               S0      
317NNAME00282                   D0300PA01X+011975Y+118877               S0      
317NNAME00282       VIA        MD0280PA01X+011365Y+118978               S0      
317SSD7_PWREN_R                 D0220PA01X+008888Y+118877               S0      
317SSD7_PWREN_R                 D0300PA01X+010025Y+118877               S0      
317SSD7_PWREN_R     VIA        MD0280PA01X+009383Y+118877               S0      
317NNAME00283                   D0220PA01X+017680Y+096350               S0      
317NNAME00283                   D0300PA01X+014763Y+096375               S0      
317NNAME00283       VIA        MD0280PA01X+017148Y+096500               S0      
317SSD_ACT_DR7_R                D0220PA01X+016622Y+096000               S0      
317SSD_ACT_DR7_R                D0300PA01X+015538Y+096375               S0      
317SSD_ACT_DR7_R    VIA        MD0280PA01X+016151Y+096376               S0      
327NNAME00284                         A01X+018744Y+094975X0160Y0480     S0      
317NNAME00284                   D0220PA01X+022950Y+095318               S0      
317NNAME00284                   D0300PA01X+022338Y+095273               S0      
317NNAME00284                   D0300PA01X+020500Y+094523               S0      
317NNAME00284       VIA        MD0280PA01X+019150Y+094250               S0      
317ATTN_LED_DR7_R               D0220PA01X+020730Y+096098               S0      
317ATTN_LED_DR7_R               D0300PA01X+021563Y+095273               S0      
317ATTN_LED_DR7_R   VIA        MD0280PA01X+021230Y+096100               S0      
317NNAME00285                   D0220PA01X+011365Y+077935               S0      
317NNAME00285                   D0300PA01X+011975Y+078328               S0      
317NNAME00285                   D0300PA01X+010775Y+077940               S0      
317NNAME00285       VIA        MD0280PA01X+011365Y+078428               S0      
317SSD8_PWREN_R                 D0220PA01X+008888Y+078328               S0      
317SSD8_PWREN_R                 D0300PA01X+010025Y+078328               S0      
317SSD8_PWREN_R     VIA        MD0280PA01X+009383Y+078328               S0      
327NNAME00286                         A01X+013910Y+078060X0450Y0550     S0      
317NNAME00286                   D0300PA01X+012725Y+077940               S0      
317NNAME00286       VIA        MD0280PA01X+013290Y+078390               S0      
317NNAME00287                   D0220PA01X+017070Y+055633               S0      
317NNAME00287                   D0300PA01X+020975Y+055512               S0      
317NNAME00287       VIA        MD0280PA01X+019400Y+055512               S0      
317SSD_ACT_DR8_R                D0220PA01X+021270Y+056900               S0      
317SSD_ACT_DR8_R                D0300PA01X+020975Y+056288               S0      
317SSD_ACT_DR8_R    VIA        MD0280PA01X+021720Y+056570               S0      
327NNAME00288                         A01X+015094Y+055675X0160Y0480     S0      
317NNAME00288                   D0220PA01X+012203Y+056968               S0      
317NNAME00288                   D0300PA01X+012163Y+055625               S0      
317NNAME00288                   D0300PA01X+014000Y+055625               S0      
317NNAME00288       VIA        MD0280PA01X+014475Y+054950               S0      
317ATTN_LED_DR8_R               D0220PA01X+015000Y+054130               S0      
317ATTN_LED_DR8_R               D0300PA01X+012938Y+055625               S0      
317ATTN_LED_DR8_R   VIA        MD0280PA01X+014132Y+054125               S0      
317NNAME00289                   D0220PA01X+011365Y+037385               S0      
317NNAME00289                   D0300PA01X+011975Y+037778               S0      
317NNAME00289                   D0300PA01X+010775Y+037390               S0      
317NNAME00289       VIA        MD0280PA01X+011365Y+037878               S0      
317SSD9_PWREN_R                 D0220PA01X+008888Y+037778               S0      
317SSD9_PWREN_R                 D0300PA01X+010025Y+037778               S0      
317SSD9_PWREN_R     VIA        MD0280PA01X+009383Y+037778               S0      
327NNAME00290                         A01X+013900Y+037530X0450Y0550     S0      
317NNAME00290                   D0300PA01X+012725Y+037390               S0      
317NNAME00290       VIA        MD0280PA01X+013310Y+037970               S0      
317NNAME00291                   D0220PA01X+019370Y+013500               S0      
317NNAME00291                   D0300PA01X+019538Y+014825               S0      
317NNAME00291       VIA        MD0280PA01X+020315Y+013945               S0      
317SSD_ACT_DR9_R                D0220PA01X+018135Y+014745               S0      
317SSD_ACT_DR9_R                D0300PA01X+018763Y+014825               S0      
317SSD_ACT_DR9_R    VIA        MD0280PA01X+018140Y+014255               S0      
327NNAME00292                         A01X+016290Y+014101X0480Y0160     S0      
317NNAME00292                   D0220PA01X+013268Y+016248               S0      
317NNAME00292                   D0300PA01X+013263Y+014875               S0      
317NNAME00292                   D0300PA01X+015100Y+014875               S0      
317NNAME00292       VIA        MD0280PA01X+015542Y+014266               S0      
317ATTN_LED_DR9_R               D0220PA01X+014640Y+013970               S0      
317ATTN_LED_DR9_R               D0300PA01X+014038Y+014875               S0      
317ATTN_LED_DR9_R   VIA        MD0280PA01X+014150Y+014050               S0      
317NNAME00293                   D0220PA01X+013035Y+161915               S0      
317NNAME00293                   D0300PA01X+012425Y+161423               S0      
317NNAME00293                   D0300PA01X+013625Y+161810               S0      
317NNAME00293       VIA        MD0280PA01X+013035Y+161322               S0      
317SSD10_PWREN_R                D0220PA01X+015513Y+161423               S0      
317SSD10_PWREN_R                D0300PA01X+014375Y+161423               S0      
317SSD10_PWREN_R    VIA        MD0280PA01X+015018Y+161423               S0      
327NNAME00294                         A01X+010500Y+161670X0450Y0550     S0      
317NNAME00294                   D0300PA01X+011675Y+161810               S0      
317NNAME00294       VIA        MD0280PA01X+011100Y+161320               S0      
317NNAME00295                   D0220PA01X+008830Y+186740               S0      
317NNAME00295                   D0300PA01X+009743Y+185315               S0      
317NNAME00295       VIA        MD0280PA01X+009320Y+186740               S0      
317SSD_ACT_DR10_R               D0220PA01X+010530Y+183990               S0      
317SSD_ACT_DR10_R               D0300PA01X+010518Y+185315               S0      
317SSD_ACT_DR10_R   VIA        MD0280PA01X+010535Y+184630               S0      
327NNAME00296                         A01X+008564Y+184715X0160Y0480     S0      
317NNAME00296                   D0220PA01X+007710Y+184620               S0      
317NNAME00296                   D0300PA01X+007148Y+185215               S0      
317NNAME00296                   D0300PA01X+007310Y+186715               S0      
317NNAME00296       VIA        MD0280PA01X+008347Y+186246               S0      
317NNAME00297                   D0220PA01X+008440Y+184060               S0      
317NNAME00297                   D0300PA01X+006373Y+185215               S0      
317NNAME00297       VIA        MD0280PA01X+007950Y+184140               S0      
327NNAME00298                         A01X+010510Y+121180X0450Y0550     S0      
317NNAME00298                   D0300PA01X+011675Y+121260               S0      
317NNAME00298       VIA        MD0280PA01X+011100Y+120780               S0      
317NNAME00299                   D0220PA01X+013035Y+121265               S0      
317NNAME00299                   D0300PA01X+013625Y+121260               S0      
317NNAME00299                   D0300PA01X+012425Y+120873               S0      
317NNAME00299       VIA        MD0280PA01X+013035Y+120772               S0      
317SSD11_PWREN_R                D0220PA01X+015513Y+120873               S0      
317SSD11_PWREN_R                D0300PA01X+014375Y+120873               S0      
317SSD11_PWREN_R    VIA        MD0280PA01X+015018Y+120873               S0      
317NNAME00300                   D0220PA01X+007730Y+147000               S0      
317NNAME00300                   D0300PA01X+005962Y+145425               S0      
317NNAME00300       VIA        MD0280PA01X+007200Y+147000               S0      
317SSD_ACT_DR11_R               D0220PA01X+007675Y+144741               S0      
317SSD_ACT_DR11_R               D0300PA01X+006738Y+145425               S0      
317SSD_ACT_DR11_R   VIA        MD0280PA01X+007027Y+144736               S0      
327NNAME00301                         A01X+009773Y+145840X0480Y0160     S0      
317NNAME00301                   D0220PA01X+009280Y+143100               S0      
317NNAME00301                   D0300PA01X+008071Y+143314               S0      
317NNAME00301                   D0300PA01X+009425Y+144050               S0      
317NNAME00301       VIA        MD0280PA01X+009773Y+145077               S0      
317NNAME00302                   D0220PA01X+008759Y+144755               S0      
317NNAME00302                   D0300PA01X+008071Y+144089               S0      
317NNAME00302       VIA        MD0280PA01X+008759Y+144244               S0      
327NNAME00303                         A01X+010520Y+080570X0450Y0550     S0      
317NNAME00303                   D0300PA01X+011675Y+080710               S0      
317NNAME00303       VIA        MD0280PA01X+011120Y+080205               S0      
317NNAME00304                   D0220PA01X+013035Y+080715               S0      
317NNAME00304                   D0300PA01X+013625Y+080710               S0      
317NNAME00304                   D0300PA01X+012425Y+080323               S0      
317NNAME00304       VIA        MD0280PA01X+013035Y+080222               S0      
317SSD12_PWREN_R                D0220PA01X+015850Y+080430               S0      
317SSD12_PWREN_R                D0300PA01X+014375Y+080323               S0      
317SSD12_PWREN_R    VIA        MD0280PA01X+015018Y+080323               S0      
317NNAME00305                   D0220PA01X+007730Y+106449               S0      
317NNAME00305                   D0300PA01X+006313Y+105075               S0      
317NNAME00305       VIA        MD0280PA01X+007200Y+106449               S0      
317SSD_ACT_DR12_R               D0220PA01X+007775Y+104090               S0      
317SSD_ACT_DR12_R               D0300PA01X+007088Y+105075               S0      
317SSD_ACT_DR12_R   VIA        MD0280PA01X+007088Y+104400               S0      
327NNAME00306                         A01X+009773Y+105289X0480Y0160     S0      
317NNAME00306                   D0220PA01X+009280Y+102549               S0      
317NNAME00306                   D0300PA01X+008071Y+102763               S0      
317NNAME00306                   D0300PA01X+009425Y+103499               S0      
317NNAME00306       VIA        MD0280PA01X+009773Y+104526               S0      
317NNAME00307                   D0220PA01X+008800Y+104280               S0      
317NNAME00307                   D0300PA01X+008071Y+103538               S0      
317NNAME00307       VIA        MD0280PA01X+008800Y+103751               S0      
327NNAME00308                         A01X+010503Y+040103X0450Y0550     S0      
317NNAME00308                   D0300PA01X+011638Y+040123               S0      
317NNAME00308       VIA        MD0280PA01X+011060Y+039630               S0      
317NNAME00309                   D0220PA01X+012998Y+040128               S0      
317NNAME00309                   D0300PA01X+013587Y+040123               S0      
317NNAME00309                   D0300PA01X+012388Y+039735               S0      
317NNAME00309       VIA        MD0280PA01X+012998Y+039635               S0      
317SSD13_PWREN_R                D0220PA01X+015475Y+039735               S0      
317SSD13_PWREN_R                D0300PA01X+014337Y+039735               S0      
317SSD13_PWREN_R    VIA        MD0280PA01X+014980Y+039735               S0      
317NNAME00310                   D0220PA01X+007730Y+065898               S0      
317NNAME00310                   D0300PA01X+005962Y+064323               S0      
317NNAME00310       VIA        MD0280PA01X+007200Y+065898               S0      
317SSD_ACT_DR13_R               D0220PA01X+007675Y+063638               S0      
317SSD_ACT_DR13_R               D0300PA01X+006738Y+064323               S0      
317SSD_ACT_DR13_R   VIA        MD0280PA01X+007062Y+063633               S0      
327NNAME00311                         A01X+009773Y+064738X0480Y0160     S0      
317NNAME00311                   D0220PA01X+009280Y+061998               S0      
317NNAME00311                   D0300PA01X+008071Y+062212               S0      
317NNAME00311                   D0300PA01X+009425Y+062948               S0      
317NNAME00311       VIA        MD0280PA01X+009773Y+063975               S0      
317NNAME00312                   D0220PA01X+008759Y+063653               S0      
317NNAME00312                   D0300PA01X+008071Y+062987               S0      
317NNAME00312       VIA        MD0280PA01X+008759Y+063142               S0      
327NNAME00313                         A01X+016040Y+003660X0450Y0550     S0      
317NNAME00313                   D0300PA01X+016725Y+002760               S0      
317NNAME00313       VIA        MD0280PA01X+016570Y+003780               S0      
317NNAME00314                   D0220PA01X+018085Y+002765               S0      
317NNAME00314                   D0300PA01X+018675Y+002760               S0      
317NNAME00314                   D0300PA01X+017475Y+002373               S0      
317NNAME00314       VIA        MD0280PA01X+018085Y+002272               S0      
317SSD14_PWREN_R                D0220PA01X+020563Y+002373               S0      
317SSD14_PWREN_R                D0300PA01X+019425Y+002373               S0      
317SSD14_PWREN_R    VIA        MD0280PA01X+020068Y+002373               S0      
317NNAME00315                   D0220PA01X+007730Y+025347               S0      
317NNAME00315                   D0300PA01X+005962Y+023772               S0      
317NNAME00315       VIA        MD0280PA01X+007200Y+025347               S0      
317SSD_ACT_DR14_R               D0220PA01X+007675Y+023087               S0      
317SSD_ACT_DR14_R               D0300PA01X+006738Y+023772               S0      
317SSD_ACT_DR14_R   VIA        MD0280PA01X+007082Y+023082               S0      
327TMP2_SDA                           A01X+082065Y+181093X0600Y0140     S0      
317TMP2_SDA                     D0220PA01X+080270Y+181200               S0      
317TMP2_SDA         VIA        MD0280PA01X+081050Y+181350               S0      
327I2C_B_TMP2_A2                      A01X+083683Y+180325X0600Y0140     S0      
317I2C_B_TMP2_A2                D0220PA01X+083750Y+179170               S0      
317I2C_B_TMP2_A2                D0220PA01X+084150Y+179170               S0      
317I2C_B_TMP2_A2    VIA        MD0280PA01X+083750Y+179700               S0      
327I2C_B_TMP2_A1                      A01X+083683Y+180581X0600Y0140     S0      
317I2C_B_TMP2_A1                D0220PA01X+082950Y+179170               S0      
317I2C_B_TMP2_A1                D0220PA01X+082550Y+179170               S0      
317I2C_B_TMP2_A1    VIA        MD0280PA01X+082950Y+179700               S0      
327I2C_B_TMP2_A0                      A01X+083683Y+180837X0600Y0140     S0      
317I2C_B_TMP2_A0                D0220PA01X+081900Y+179170               S0      
317I2C_B_TMP2_A0                D0220PA01X+081500Y+179170               S0      
317I2C_B_TMP2_A0    VIA        MD0280PA01X+081900Y+179700               S0      
327I2C_B_TMP1_A1                      A01X+018132Y+054203X0600Y0140     S0      
317I2C_B_TMP1_A1                D0220PA01X+019900Y+053530               S0      
317I2C_B_TMP1_A1                D0220PA01X+020300Y+053530               S0      
317I2C_B_TMP1_A1    VIA        MD0280PA01X+019375Y+053525               S0      
327TMP2_SCL                           A01X+082065Y+180837X0600Y0140     S0      
317TMP2_SCL                     D0220PA01X+080270Y+180700               S0      
317TMP2_SCL         VIA        MD0280PA01X+081050Y+180550               S0      
327TMP1_SDA                           A01X+016514Y+054715X0600Y0140     S0      
317TMP1_SDA                     D0220PA01X+018180Y+053100               S0      
317TMP1_SDA         VIA        MD0280PA01X+017666Y+053163               S0      
327TMP1_SCL                           A01X+016514Y+054459X0600Y0140     S0      
317TMP1_SCL                     D0220PA01X+018180Y+052700               S0      
317TMP1_SCL         VIA        MD0280PA01X+016900Y+053350               S0      
327I2C_B_TMP1_A0                      A01X+018132Y+054459X0600Y0140     S0      
317I2C_B_TMP1_A0                D0220PA01X+019900Y+054280               S0      
317I2C_B_TMP1_A0                D0220PA01X+020300Y+054280               S0      
317I2C_B_TMP1_A0    VIA        MD0280PA01X+019150Y+054350               S0      
327TMP3_SDA                           A01X+082065Y+019675X0600Y0140     S0      
317TMP3_SDA                     D0220PA01X+080270Y+019800               S0      
317TMP3_SDA         VIA        MD0280PA01X+081050Y+019950               S0      
327I2C_B_TMP3_A0                      A01X+083683Y+019419X0600Y0140     S0      
317I2C_B_TMP3_A0                D0220PA01X+082050Y+017770               S0      
317I2C_B_TMP3_A0                D0220PA01X+081650Y+017770               S0      
317I2C_B_TMP3_A0    VIA        MD0280PA01X+082050Y+018300               S0      
327I2C_B_TMP3_A2                      A01X+083683Y+018907X0600Y0140     S0      
317I2C_B_TMP3_A2                D0220PA01X+083650Y+017770               S0      
317I2C_B_TMP3_A2                D0220PA01X+083250Y+017770               S0      
317I2C_B_TMP3_A2    VIA        MD0280PA01X+083650Y+018300               S0      
327I2C_B_TMP3_A1                      A01X+083683Y+019163X0600Y0140     S0      
317I2C_B_TMP3_A1                D0220PA01X+082850Y+017770               S0      
317I2C_B_TMP3_A1                D0220PA01X+082450Y+017770               S0      
317I2C_B_TMP3_A1    VIA        MD0280PA01X+082850Y+018300               S0      
327TMP4_SDA                           A01X+011396Y+149597X0600Y0140     S0      
317TMP4_SDA                     D0220PA01X+009620Y+149700               S0      
317TMP4_SDA         VIA        MD0280PA01X+010400Y+149850               S0      
327I2C_B_TMP4_A2                      A01X+013014Y+148829X0600Y0140     S0      
317I2C_B_TMP4_A2                D0220PA01X+013000Y+147670               S0      
317I2C_B_TMP4_A2                D0220PA01X+012600Y+147670               S0      
317I2C_B_TMP4_A2    VIA        MD0280PA01X+013000Y+148200               S0      
327I2C_B_TMP4_A1                      A01X+013014Y+149085X0600Y0140     S0      
317I2C_B_TMP4_A1                D0220PA01X+012200Y+147670               S0      
317I2C_B_TMP4_A1                D0220PA01X+011800Y+147670               S0      
317I2C_B_TMP4_A1    VIA        MD0280PA01X+012200Y+148200               S0      
327I2C_B_TMP4_A0                      A01X+013014Y+149341X0600Y0140     S0      
317I2C_B_TMP4_A0                D0220PA01X+011400Y+147670               S0      
317I2C_B_TMP4_A0                D0220PA01X+011000Y+147670               S0      
317I2C_B_TMP4_A0    VIA        MD0280PA01X+011400Y+148200               S0      
327TMP3_SCL                           A01X+082065Y+019419X0600Y0140     S0      
317TMP3_SCL                     D0220PA01X+080270Y+019300               S0      
317TMP3_SCL         VIA        MD0280PA01X+081050Y+019150               S0      
327TMP4_SCL                           A01X+011396Y+149341X0600Y0140     S0      
317TMP4_SCL                     D0220PA01X+009620Y+149200               S0      
317TMP4_SCL         VIA        MD0280PA01X+010400Y+149050               S0      
327I2C_B_TMP1_A2                      A01X+018132Y+053947X0600Y0140     S0      
317I2C_B_TMP1_A2                D0220PA01X+020300Y+052780               S0      
317I2C_B_TMP1_A2                D0220PA01X+019900Y+052780               S0      
317I2C_B_TMP1_A2    VIA        MD0280PA01X+019400Y+052775               S0      
327EEPROM_A0                          A01X+028084Y+177460X0140Y0600     S0      
317EEPROM_A0                    D0220PA01X+028750Y+178830               S0      
317EEPROM_A0                    D0220PA01X+029150Y+178830               S0      
317EEPROM_A0        VIA        MD0280PA01X+028750Y+178300               S0      
327EEPROM_A1                          A01X+027828Y+177460X0140Y0600     S0      
317EEPROM_A1                    D0220PA01X+027950Y+178830               S0      
317EEPROM_A1                    D0220PA01X+028350Y+178830               S0      
317EEPROM_A1        VIA        MD0280PA01X+027950Y+178300               S0      
327EEPROM_A2                          A01X+027572Y+177460X0140Y0600     S0      
317EEPROM_A2                    D0220PA01X+027150Y+178830               S0      
317EEPROM_A2                    D0220PA01X+027550Y+178830               S0      
317EEPROM_A2        VIA        MD0280PA01X+027150Y+178300               S0      
327EEPROM_WP                          A01X+027828Y+175240X0140Y0600     S0      
317EEPROM_WP                    D0220PA01X+028050Y+173470               S0      
317EEPROM_WP        VIA        MD0280PA01X+028200Y+174550               S0      
327EEPROM_SCL                         A01X+027572Y+175240X0140Y0600     S0      
317EEPROM_SCL                   D0220PA01X+027650Y+173470               S0      
317EEPROM_SCL       VIA        MD0280PA01X+027650Y+174000               S0      
327EEPROM_SDA                         A01X+027316Y+175240X0140Y0600     S0      
317EEPROM_SDA                   D0220PA01X+027250Y+173470               S0      
317EEPROM_SDA       VIA        MD0280PA01X+027100Y+174550               S0      
327VOL_SEN_ALERT                      A01X+035653Y+008835X0120Y0600     S0      
317VOL_SEN_ALERT                D0320PA01X+035800Y+007600               S0      
317VOL_SEN_ALERT                D0220PA01X+035800Y+007070               S0      
327VOL_SEN_ADDR                       A01X+035457Y+008835X0120Y0600     S0      
317VOL_SEN_ADDR                 D0220PA01X+035250Y+007520               S0      
317VOL_SEN_ADDR                 D0220PA01X+034850Y+007520               S0      
317VOL_SEN_ADDR     VIA        MD0280PA01X+035250Y+008150               S0      
327VOL_SEN_SCL                        A01X+035457Y+010465X0120Y0600     S0      
317VOL_SEN_SCL                  D0220PA01X+034850Y+012380               S0      
317VOL_SEN_SCL      VIA        MD0280PA01X+034850Y+011850               S0      
327VOL_SEN_SDA                        A01X+035653Y+010465X0120Y0600     S0      
317VOL_SEN_SDA                  D0220PA01X+035250Y+012380               S0      
317VOL_SEN_SDA      VIA        MD0280PA01X+035500Y+011200               S0      
327NNAME00316                         A01X+089775Y+175694X0480Y0160     S0      
317NNAME00316                   D0220PA01X+091980Y+175200               S0      
317NNAME00316       VIA        MD0280PA01X+091392Y+175200               S0      
327NNAME00317                         A01X+089775Y+135143X0480Y0160     S0      
317NNAME00317                   D0220PA01X+091980Y+134649               S0      
317NNAME00317       VIA        MD0280PA01X+090853Y+134846               S0      
327NNAME00318                         A01X+089775Y+094592X0480Y0160     S0      
317NNAME00318                   D0220PA01X+091980Y+094098               S0      
317NNAME00318       VIA        MD0280PA01X+090818Y+094273               S0      
327NNAME00319                         A01X+089775Y+054041X0480Y0160     S0      
317NNAME00319                   D0220PA01X+091980Y+053546               S0      
317NNAME00319       VIA        MD0280PA01X+090749Y+053684               S0      
327NNAME00320                         A01X+089875Y+013489X0480Y0160     S0      
317NNAME00320                   D0220PA01X+091980Y+012995               S0      
317NNAME00320       VIA        MD0280PA01X+090988Y+013199               S0      
327NNAME00321                         A01X+020110Y+177456X0480Y0160     S0      
317NNAME00321                   D0220PA01X+018505Y+177450               S0      
317NNAME00321       VIA        MD0280PA01X+019027Y+177660               S0      
327NNAME00322                         A01X+016940Y+135143X0480Y0160     S0      
317NNAME00322                   D0220PA01X+019145Y+134649               S0      
317NNAME00322       VIA        MD0280PA01X+018610Y+134660               S0      
327NNAME00323                         A01X+019256Y+095625X0160Y0480     S0      
317NNAME00323                   D0220PA01X+018020Y+096350               S0      
317NNAME00323       VIA        MD0280PA01X+019100Y+096430               S0      
327NNAME00324                         A01X+015606Y+056325X0160Y0480     S0      
317NNAME00324                   D0220PA01X+016730Y+055633               S0      
317NNAME00324       VIA        MD0280PA01X+016230Y+055810               S0      
327NNAME00325                         A01X+016940Y+013589X0480Y0160     S0      
317NNAME00325                   D0220PA01X+019030Y+013500               S0      
317NNAME00325       VIA        MD0280PA01X+018258Y+013500               S0      
327NNAME00326                         A01X+009076Y+185365X0160Y0480     S0      
317NNAME00326                   D0220PA01X+008490Y+186740               S0      
317NNAME00326       VIA        MD0280PA01X+009075Y+186031               S0      
327NNAME00327                         A01X+009123Y+146352X0480Y0160     S0      
317NNAME00327                   D0220PA01X+008070Y+147000               S0      
317NNAME00327       VIA        MD0280PA01X+008600Y+147000               S0      
327NNAME00328                         A01X+009123Y+105801X0480Y0160     S0      
317NNAME00328                   D0220PA01X+008070Y+106449               S0      
317NNAME00328       VIA        MD0280PA01X+008600Y+106449               S0      
327NNAME00329                         A01X+009123Y+065249X0480Y0160     S0      
317NNAME00329                   D0220PA01X+008070Y+065898               S0      
317NNAME00329       VIA        MD0280PA01X+008600Y+065898               S0      
327NNAME00330                         A01X+009123Y+024698X0480Y0160     S0      
317NNAME00330                   D0220PA01X+008070Y+025347               S0      
317NNAME00330       VIA        MD0280PA01X+008600Y+025347               S0      
327NNAME00331                         A01X+082065Y+180581X0600Y0140     S0      
317NNAME00331                   D0320PA01X+081050Y+179700               S0      
327NNAME00332                         A01X+016514Y+054203X0600Y0140     S0      
317NNAME00332                   D0320PA01X+015450Y+053600               S0      
327NNAME00333                         A01X+082065Y+019163X0600Y0140     S0      
317NNAME00333                   D0320PA01X+081050Y+018300               S0      
327NNAME00334                         A01X+011396Y+149085X0600Y0140     S0      
317NNAME00334                   D0320PA01X+010400Y+148200               S0      
999
